G04 ================== begin FILE IDENTIFICATION RECORD ==================*
G04 Layout Name:  F:/<user>/2022/FB/R4006-TIMING/brd/gerber-3/R4006-B0001-02_R01.brd*
G04 Film Name:    R4006-B0001-02_R01_FAB*
G04 File Format:  Gerber RS274X*
G04 File Origin:  Cadence Allegro 17.2-S079*
G04 Origin Date:  Fri Feb 25 18:14:44 2022*
G04 *
G04 Layer:  MANUFACTURING/NCLEGEND-1-10*
G04 Layer:  BOARD GEOMETRY/OUTLINE*
G04 Layer:  BOARD GEOMETRY/DIMENSION*
G04 Layer:  BOARD GEOMETRY/FAB_NOTES*
G04 Layer:  DRAWING FORMAT/OUTLINE*
G04 *
G04 Offset:    (0.00 0.00)*
G04 Mirror:    No*
G04 Mode:      Positive*
G04 Rotation:  0*
G04 FullContactRelief:  No*
G04 UndefLineWidth:     6.00*
G04 ================== end FILE IDENTIFICATION RECORD ====================*
%FSLAX55Y55*MOIN*%
%IR0*IPPOS*OFA0.00000B0.00000*MIA0B0*SFA1.00000B1.00000*%
%AMMACRO22*
1,1,.006,0.0,.059*
20,1,.006,0.0,.059,.010245,.058104,0.0*
1,1,.006,.010245,.058104*
20,1,.006,.010245,.058104,.020179,.055442,0.0*
1,1,.006,.020179,.055442*
20,1,.006,.020179,.055442,.0295,.051095,0.0*
1,1,.006,.0295,.051095*
20,1,.006,.0295,.051095,.037924,.045197,0.0*
1,1,.006,.037924,.045197*
20,1,.006,.037924,.045197,.045197,.037924,0.0*
1,1,.006,.045197,.037924*
20,1,.006,.045197,.037924,.051095,.0295,0.0*
1,1,.006,.051095,.0295*
20,1,.006,.051095,.0295,.055442,.020179,0.0*
1,1,.006,.055442,.020179*
20,1,.006,.055442,.020179,.058104,.010245,0.0*
1,1,.006,.058104,.010245*
20,1,.006,.058104,.010245,.059,0.0,0.0*
1,1,.006,.059,0.0*
20,1,.006,.059,0.0,.058104,-.010245,0.0*
1,1,.006,.058104,-.010245*
20,1,.006,.058104,-.010245,.055442,-.020179,0.0*
1,1,.006,.055442,-.020179*
20,1,.006,.055442,-.020179,.051095,-.0295,0.0*
1,1,.006,.051095,-.0295*
20,1,.006,.051095,-.0295,.045197,-.037924,0.0*
1,1,.006,.045197,-.037924*
20,1,.006,.045197,-.037924,.037924,-.045197,0.0*
1,1,.006,.037924,-.045197*
20,1,.006,.037924,-.045197,.0295,-.051095,0.0*
1,1,.006,.0295,-.051095*
20,1,.006,.0295,-.051095,.020179,-.055442,0.0*
1,1,.006,.020179,-.055442*
20,1,.006,.020179,-.055442,.010245,-.058104,0.0*
1,1,.006,.010245,-.058104*
20,1,.006,.010245,-.058104,0.0,-.059,0.0*
1,1,.006,0.0,-.059*
20,1,.006,0.0,-.059,-.010245,-.058104,0.0*
1,1,.006,-.010245,-.058104*
20,1,.006,-.010245,-.058104,-.020179,-.055442,0.0*
1,1,.006,-.020179,-.055442*
20,1,.006,-.020179,-.055442,-.0295,-.051095,0.0*
1,1,.006,-.0295,-.051095*
20,1,.006,-.0295,-.051095,-.037924,-.045197,0.0*
1,1,.006,-.037924,-.045197*
20,1,.006,-.037924,-.045197,-.045197,-.037924,0.0*
1,1,.006,-.045197,-.037924*
20,1,.006,-.045197,-.037924,-.051095,-.0295,0.0*
1,1,.006,-.051095,-.0295*
20,1,.006,-.051095,-.0295,-.055442,-.020179,0.0*
1,1,.006,-.055442,-.020179*
20,1,.006,-.055442,-.020179,-.058104,-.010245,0.0*
1,1,.006,-.058104,-.010245*
20,1,.006,-.058104,-.010245,-.059,0.0,0.0*
1,1,.006,-.059,0.0*
20,1,.006,-.059,0.0,-.058104,.010245,0.0*
1,1,.006,-.058104,.010245*
20,1,.006,-.058104,.010245,-.055442,.020179,0.0*
1,1,.006,-.055442,.020179*
20,1,.006,-.055442,.020179,-.051095,.0295,0.0*
1,1,.006,-.051095,.0295*
20,1,.006,-.051095,.0295,-.045197,.037924,0.0*
1,1,.006,-.045197,.037924*
20,1,.006,-.045197,.037924,-.037924,.045197,0.0*
1,1,.006,-.037924,.045197*
20,1,.006,-.037924,.045197,-.0295,.051095,0.0*
1,1,.006,-.0295,.051095*
20,1,.006,-.0295,.051095,-.020179,.055442,0.0*
1,1,.006,-.020179,.055442*
20,1,.006,-.020179,.055442,-.010245,.058104,0.0*
1,1,.006,-.010245,.058104*
20,1,.006,-.010245,.058104,0.0,.059,0.0*
1,1,.006,0.0,.059*
1,1,.006,-.0295,-.0295*
20,1,.006,-.0295,-.0295,-.0295,.0295,0.0*
1,1,.006,-.0295,.0295*
20,1,.006,-.0295,.0295,-.0413,.0177,0.0*
1,1,.006,-.0413,.0177*
1,1,.006,-.0413,-.0295*
20,1,.006,-.0413,-.0295,-.0177,-.0295,0.0*
1,1,.006,-.0177,-.0295*
1,1,.006,.02951,-.0295*
20,1,.006,.02951,-.0295,.02951,.0295,0.0*
1,1,.006,.02951,.0295*
20,1,.006,.02951,.0295,.01771,.0177,0.0*
1,1,.006,.01771,.0177*
1,1,.006,.01771,-.0295*
20,1,.006,.01771,-.0295,.04131,-.0295,0.0*
1,1,.006,.04131,-.0295*
%
%ADD22MACRO22*%
%AMMACRO13*
1,1,.006,0.0,.0625*
20,1,.006,0.0,.0625,.054127,-.03125,0.0*
1,1,.006,.054127,-.03125*
20,1,.006,.054127,-.03125,-.054127,-.03125,0.0*
1,1,.006,-.054127,-.03125*
20,1,.006,-.054127,-.03125,0.0,.0625,0.0*
1,1,.006,0.0,.0625*
1,1,.006,-.01406,-.01406*
20,1,.006,-.01406,-.01406,-.01406,.01406,0.0*
1,1,.006,-.01406,.01406*
20,1,.006,-.01406,.01406,-.01968,.00844,0.0*
1,1,.006,-.01968,.00844*
1,1,.006,-.01968,-.01406*
20,1,.006,-.01968,-.01406,-.00844,-.01406,0.0*
1,1,.006,-.00844,-.01406*
1,1,.006,.00517,.00937*
20,1,.006,.00517,.00937,.00798,.01218,0.0*
1,1,.006,.00798,.01218*
20,1,.006,.00798,.01218,.01126,.01359,0.0*
1,1,.006,.01126,.01359*
20,1,.006,.01126,.01359,.01501,.01406,0.0*
1,1,.006,.01501,.01406*
20,1,.006,.01501,.01406,.01969,.01312,0.0*
1,1,.006,.01969,.01312*
20,1,.006,.01969,.01312,.02297,.01078,0.0*
1,1,.006,.02297,.01078*
20,1,.006,.02297,.01078,.02391,.00797,0.0*
1,1,.006,.02391,.00797*
20,1,.006,.02391,.00797,.02344,.00515,0.0*
1,1,.006,.02344,.00515*
20,1,.006,.02344,.00515,.02157,.00281,0.0*
1,1,.006,.02157,.00281*
20,1,.006,.02157,.00281,.0122,-.00187,0.0*
1,1,.006,.0122,-.00187*
20,1,.006,.0122,-.00187,.00798,-.00516,0.0*
1,1,.006,.00798,-.00516*
20,1,.006,.00798,-.00516,.00517,-.00984,0.0*
1,1,.006,.00517,-.00984*
20,1,.006,.00517,-.00984,.00423,-.01406,0.0*
1,1,.006,.00423,-.01406*
20,1,.006,.00423,-.01406,.02391,-.01406,0.0*
1,1,.006,.02391,-.01406*
%
%ADD13MACRO13*%
%AMMACRO24*
1,1,.006,.025,0.0*
20,1,.006,.025,0.0,.02462,-.004341,0.0*
1,1,.006,.02462,-.004341*
20,1,.006,.02462,-.004341,.023492,-.008551,0.0*
1,1,.006,.023492,-.008551*
20,1,.006,.023492,-.008551,.021651,-.0125,0.0*
1,1,.006,.021651,-.0125*
20,1,.006,.021651,-.0125,.019151,-.01607,0.0*
1,1,.006,.019151,-.01607*
20,1,.006,.019151,-.01607,.01607,-.019151,0.0*
1,1,.006,.01607,-.019151*
20,1,.006,.01607,-.019151,.0125,-.021651,0.0*
1,1,.006,.0125,-.021651*
20,1,.006,.0125,-.021651,.008551,-.023492,0.0*
1,1,.006,.008551,-.023492*
20,1,.006,.008551,-.023492,.004341,-.02462,0.0*
1,1,.006,.004341,-.02462*
20,1,.006,.004341,-.02462,0.0,-.025,0.0*
1,1,.006,0.0,-.025*
20,1,.006,0.0,-.025,-.004341,-.02462,0.0*
1,1,.006,-.004341,-.02462*
20,1,.006,-.004341,-.02462,-.008551,-.023492,0.0*
1,1,.006,-.008551,-.023492*
20,1,.006,-.008551,-.023492,-.0125,-.021651,0.0*
1,1,.006,-.0125,-.021651*
20,1,.006,-.0125,-.021651,-.01607,-.019151,0.0*
1,1,.006,-.01607,-.019151*
20,1,.006,-.01607,-.019151,-.019151,-.01607,0.0*
1,1,.006,-.019151,-.01607*
20,1,.006,-.019151,-.01607,-.021651,-.0125,0.0*
1,1,.006,-.021651,-.0125*
20,1,.006,-.021651,-.0125,-.023492,-.008551,0.0*
1,1,.006,-.023492,-.008551*
20,1,.006,-.023492,-.008551,-.02462,-.004341,0.0*
1,1,.006,-.02462,-.004341*
20,1,.006,-.02462,-.004341,-.025,0.0,0.0*
1,1,.006,-.025,0.0*
20,1,.006,-.025,0.0,-.02462,.004341,0.0*
1,1,.006,-.02462,.004341*
20,1,.006,-.02462,.004341,-.023492,.008551,0.0*
1,1,.006,-.023492,.008551*
20,1,.006,-.023492,.008551,-.021651,.0125,0.0*
1,1,.006,-.021651,.0125*
20,1,.006,-.021651,.0125,-.019151,.01607,0.0*
1,1,.006,-.019151,.01607*
20,1,.006,-.019151,.01607,-.01607,.019151,0.0*
1,1,.006,-.01607,.019151*
20,1,.006,-.01607,.019151,-.0125,.021651,0.0*
1,1,.006,-.0125,.021651*
20,1,.006,-.0125,.021651,-.008551,.023492,0.0*
1,1,.006,-.008551,.023492*
20,1,.006,-.008551,.023492,-.004341,.02462,0.0*
1,1,.006,-.004341,.02462*
20,1,.006,-.004341,.02462,0.0,.025,0.0*
1,1,.006,0.0,.025*
20,1,.006,0.0,.025,.004341,.02462,0.0*
1,1,.006,.004341,.02462*
20,1,.006,.004341,.02462,.008551,.023492,0.0*
1,1,.006,.008551,.023492*
20,1,.006,.008551,.023492,.0125,.021651,0.0*
1,1,.006,.0125,.021651*
20,1,.006,.0125,.021651,.01607,.019151,0.0*
1,1,.006,.01607,.019151*
20,1,.006,.01607,.019151,.019151,.01607,0.0*
1,1,.006,.019151,.01607*
20,1,.006,.019151,.01607,.021651,.0125,0.0*
1,1,.006,.021651,.0125*
20,1,.006,.021651,.0125,.023492,.008551,0.0*
1,1,.006,.023492,.008551*
20,1,.006,.023492,.008551,.02462,.004341,0.0*
1,1,.006,.02462,.004341*
20,1,.006,.02462,.004341,.025,0.0,0.0*
1,1,.006,.025,0.0*
1,1,.006,-.00917,-.0125*
20,1,.006,-.00917,-.0125,-.00917,.0125,0.0*
1,1,.006,-.00917,.0125*
20,1,.006,-.00917,.0125,-.00083,.0125,0.0*
1,1,.006,-.00083,.0125*
20,1,.006,-.00083,.0125,.0025,.01125,0.0*
1,1,.006,.0025,.01125*
20,1,.006,.0025,.01125,.005,.00958,0.0*
1,1,.006,.005,.00958*
20,1,.006,.005,.00958,.00708,.00708,0.0*
1,1,.006,.00708,.00708*
20,1,.006,.00708,.00708,.00875,.00417,0.0*
1,1,.006,.00875,.00417*
20,1,.006,.00875,.00417,.00917,0.0,0.0*
1,1,.006,.00917,0.0*
20,1,.006,.00917,0.0,.00875,-.00417,0.0*
1,1,.006,.00875,-.00417*
20,1,.006,.00875,-.00417,.00708,-.00708,0.0*
1,1,.006,.00708,-.00708*
20,1,.006,.00708,-.00708,.005,-.00958,0.0*
1,1,.006,.005,-.00958*
20,1,.006,.005,-.00958,.0025,-.01125,0.0*
1,1,.006,.0025,-.01125*
20,1,.006,.0025,-.01125,-.00083,-.0125,0.0*
1,1,.006,-.00083,-.0125*
20,1,.006,-.00083,-.0125,-.00917,-.0125,0.0*
1,1,.006,-.00917,-.0125*
%
%ADD24MACRO24*%
%AMMACRO12*
1,1,.006,.025,0.0*
20,1,.006,.025,0.0,-.025,0.0,0.0*
1,1,.006,-.025,0.0*
1,1,.006,0.0,.025*
20,1,.006,0.0,.025,0.0,-.025,0.0*
1,1,.006,0.0,-.025*
1,1,.006,.01583,.01333*
20,1,.006,.01583,.01333,.0175,.01458,0.0*
1,1,.006,.0175,.01458*
20,1,.006,.0175,.01458,.01875,.01667,0.0*
1,1,.006,.01875,.01667*
20,1,.006,.01875,.01667,.01958,.01958,0.0*
1,1,.006,.01958,.01958*
20,1,.006,.01958,.01958,.01875,.02208,0.0*
1,1,.006,.01875,.02208*
20,1,.006,.01875,.02208,.01708,.02375,0.0*
1,1,.006,.01708,.02375*
20,1,.006,.01708,.02375,.01417,.025,0.0*
1,1,.006,.01417,.025*
20,1,.006,.01417,.025,.00292,.025,0.0*
1,1,.006,.00292,.025*
20,1,.006,.00292,.025,.00292,0.0,0.0*
1,1,.006,.00292,0.0*
20,1,.006,.00292,0.0,.01667,0.0,0.0*
1,1,.006,.01667,0.0*
20,1,.006,.01667,0.0,.01958,.00167,0.0*
1,1,.006,.01958,.00167*
20,1,.006,.01958,.00167,.02125,.00417,0.0*
1,1,.006,.02125,.00417*
20,1,.006,.02125,.00417,.02208,.00708,0.0*
1,1,.006,.02208,.00708*
20,1,.006,.02208,.00708,.02125,.01,0.0*
1,1,.006,.02125,.01*
20,1,.006,.02125,.01,.01875,.0125,0.0*
1,1,.006,.01875,.0125*
20,1,.006,.01875,.0125,.01583,.01333,0.0*
1,1,.006,.01583,.01333*
20,1,.006,.01583,.01333,.00292,.01333,0.0*
1,1,.006,.00292,.01333*
%
%ADD12MACRO12*%
%AMMACRO17*
1,1,.006,.025,.025*
20,1,.006,.025,.025,.025,-.025,0.0*
1,1,.006,.025,-.025*
20,1,.006,.025,-.025,-.025,-.025,0.0*
1,1,.006,-.025,-.025*
20,1,.006,-.025,-.025,-.025,.025,0.0*
1,1,.006,-.025,.025*
20,1,.006,-.025,.025,.025,.025,0.0*
1,1,.006,.025,.025*
1,1,.006,.00333,.00083*
20,1,.006,.00333,.00083,.005,.00208,0.0*
1,1,.006,.005,.00208*
20,1,.006,.005,.00208,.00625,.00417,0.0*
1,1,.006,.00625,.00417*
20,1,.006,.00625,.00417,.00708,.00708,0.0*
1,1,.006,.00708,.00708*
20,1,.006,.00708,.00708,.00625,.00958,0.0*
1,1,.006,.00625,.00958*
20,1,.006,.00625,.00958,.00458,.01125,0.0*
1,1,.006,.00458,.01125*
20,1,.006,.00458,.01125,.00167,.0125,0.0*
1,1,.006,.00167,.0125*
20,1,.006,.00167,.0125,-.00958,.0125,0.0*
1,1,.006,-.00958,.0125*
20,1,.006,-.00958,.0125,-.00958,-.0125,0.0*
1,1,.006,-.00958,-.0125*
20,1,.006,-.00958,-.0125,.00417,-.0125,0.0*
1,1,.006,.00417,-.0125*
20,1,.006,.00417,-.0125,.00708,-.01083,0.0*
1,1,.006,.00708,-.01083*
20,1,.006,.00708,-.01083,.00875,-.00833,0.0*
1,1,.006,.00875,-.00833*
20,1,.006,.00875,-.00833,.00958,-.00542,0.0*
1,1,.006,.00958,-.00542*
20,1,.006,.00958,-.00542,.00875,-.0025,0.0*
1,1,.006,.00875,-.0025*
20,1,.006,.00875,-.0025,.00625,0.0,0.0*
1,1,.006,.00625,0.0*
20,1,.006,.00625,0.0,.00333,.00083,0.0*
1,1,.006,.00333,.00083*
20,1,.006,.00333,.00083,-.00958,.00083,0.0*
1,1,.006,-.00958,.00083*
%
%ADD17MACRO17*%
%AMMACRO11*
1,1,.006,.0315,0.0*
20,1,.006,.0315,0.0,.031021,-.00547,0.0*
1,1,.006,.031021,-.00547*
20,1,.006,.031021,-.00547,.0296,-.010774,0.0*
1,1,.006,.0296,-.010774*
20,1,.006,.0296,-.010774,.02728,-.01575,0.0*
1,1,.006,.02728,-.01575*
20,1,.006,.02728,-.01575,.02413,-.020248,0.0*
1,1,.006,.02413,-.020248*
20,1,.006,.02413,-.020248,.020248,-.02413,0.0*
1,1,.006,.020248,-.02413*
20,1,.006,.020248,-.02413,.01575,-.02728,0.0*
1,1,.006,.01575,-.02728*
20,1,.006,.01575,-.02728,.010774,-.0296,0.0*
1,1,.006,.010774,-.0296*
20,1,.006,.010774,-.0296,.00547,-.031021,0.0*
1,1,.006,.00547,-.031021*
20,1,.006,.00547,-.031021,0.0,-.0315,0.0*
1,1,.006,0.0,-.0315*
20,1,.006,0.0,-.0315,-.00547,-.031021,0.0*
1,1,.006,-.00547,-.031021*
20,1,.006,-.00547,-.031021,-.010774,-.0296,0.0*
1,1,.006,-.010774,-.0296*
20,1,.006,-.010774,-.0296,-.01575,-.02728,0.0*
1,1,.006,-.01575,-.02728*
20,1,.006,-.01575,-.02728,-.020248,-.02413,0.0*
1,1,.006,-.020248,-.02413*
20,1,.006,-.020248,-.02413,-.02413,-.020248,0.0*
1,1,.006,-.02413,-.020248*
20,1,.006,-.02413,-.020248,-.02728,-.01575,0.0*
1,1,.006,-.02728,-.01575*
20,1,.006,-.02728,-.01575,-.0296,-.010774,0.0*
1,1,.006,-.0296,-.010774*
20,1,.006,-.0296,-.010774,-.031021,-.00547,0.0*
1,1,.006,-.031021,-.00547*
20,1,.006,-.031021,-.00547,-.0315,0.0,0.0*
1,1,.006,-.0315,0.0*
20,1,.006,-.0315,0.0,-.031021,.00547,0.0*
1,1,.006,-.031021,.00547*
20,1,.006,-.031021,.00547,-.0296,.010774,0.0*
1,1,.006,-.0296,.010774*
20,1,.006,-.0296,.010774,-.02728,.01575,0.0*
1,1,.006,-.02728,.01575*
20,1,.006,-.02728,.01575,-.02413,.020248,0.0*
1,1,.006,-.02413,.020248*
20,1,.006,-.02413,.020248,-.020248,.02413,0.0*
1,1,.006,-.020248,.02413*
20,1,.006,-.020248,.02413,-.01575,.02728,0.0*
1,1,.006,-.01575,.02728*
20,1,.006,-.01575,.02728,-.010774,.0296,0.0*
1,1,.006,-.010774,.0296*
20,1,.006,-.010774,.0296,-.00547,.031021,0.0*
1,1,.006,-.00547,.031021*
20,1,.006,-.00547,.031021,0.0,.0315,0.0*
1,1,.006,0.0,.0315*
20,1,.006,0.0,.0315,.00547,.031021,0.0*
1,1,.006,.00547,.031021*
20,1,.006,.00547,.031021,.010774,.0296,0.0*
1,1,.006,.010774,.0296*
20,1,.006,.010774,.0296,.01575,.02728,0.0*
1,1,.006,.01575,.02728*
20,1,.006,.01575,.02728,.020248,.02413,0.0*
1,1,.006,.020248,.02413*
20,1,.006,.020248,.02413,.02413,.020248,0.0*
1,1,.006,.02413,.020248*
20,1,.006,.02413,.020248,.02728,.01575,0.0*
1,1,.006,.02728,.01575*
20,1,.006,.02728,.01575,.0296,.010774,0.0*
1,1,.006,.0296,.010774*
20,1,.006,.0296,.010774,.031021,.00547,0.0*
1,1,.006,.031021,.00547*
20,1,.006,.031021,.00547,.0315,0.0,0.0*
1,1,.006,.0315,0.0*
1,1,.006,.00315,0.0*
20,1,.006,.00315,0.0,.01365,0.0,0.0*
1,1,.006,.01365,0.0*
20,1,.006,.01365,0.0,.01365,-.00945,0.0*
1,1,.006,.01365,-.00945*
20,1,.006,.01365,-.00945,.0105,-.0126,0.0*
1,1,.006,.0105,-.0126*
20,1,.006,.0105,-.0126,.00682,-.0147,0.0*
1,1,.006,.00682,-.0147*
20,1,.006,.00682,-.0147,.00158,-.01575,0.0*
1,1,.006,.00158,-.01575*
20,1,.006,.00158,-.01575,-.00367,-.0147,0.0*
1,1,.006,-.00367,-.0147*
20,1,.006,-.00367,-.0147,-.00735,-.0126,0.0*
1,1,.006,-.00735,-.0126*
20,1,.006,-.00735,-.0126,-.0105,-.00945,0.0*
1,1,.006,-.0105,-.00945*
20,1,.006,-.0105,-.00945,-.0126,-.00578,0.0*
1,1,.006,-.0126,-.00578*
20,1,.006,-.0126,-.00578,-.01365,-.00158,0.0*
1,1,.006,-.01365,-.00158*
20,1,.006,-.01365,-.00158,-.01365,.0021,0.0*
1,1,.006,-.01365,.0021*
20,1,.006,-.01365,.0021,-.0126,.00525,0.0*
1,1,.006,-.0126,.00525*
20,1,.006,-.0126,.00525,-.0105,.00893,0.0*
1,1,.006,-.0105,.00893*
20,1,.006,-.0105,.00893,-.00735,.01207,0.0*
1,1,.006,-.00735,.01207*
20,1,.006,-.00735,.01207,-.0042,.01417,0.0*
1,1,.006,-.0042,.01417*
20,1,.006,-.0042,.01417,0.0,.01575,0.0*
1,1,.006,0.0,.01575*
20,1,.006,0.0,.01575,.00367,.01575,0.0*
1,1,.006,.00367,.01575*
20,1,.006,.00367,.01575,.00787,.0147,0.0*
1,1,.006,.00787,.0147*
20,1,.006,.00787,.0147,.01103,.0126,0.0*
1,1,.006,.01103,.0126*
%
%ADD11MACRO11*%
%AMMACRO19*
1,1,.006,.05,0.0*
20,1,.006,.05,0.0,-.05,0.0,0.0*
1,1,.006,-.05,0.0*
1,1,.006,0.0,.05*
20,1,.006,0.0,.05,0.0,-.05,0.0*
1,1,.006,0.0,-.05*
1,1,.006,.025,0.0*
20,1,.006,.025,0.0,.025,.05,0.0*
1,1,.006,.025,.05*
20,1,.006,.025,.05,.015,.04,0.0*
1,1,.006,.015,.04*
1,1,.006,.015,0.0*
20,1,.006,.015,0.0,.035,0.0,0.0*
1,1,.006,.035,0.0*
1,1,.006,.07501,.05*
20,1,.006,.07501,.05,.06834,.04833,0.0*
1,1,.006,.06834,.04833*
20,1,.006,.06834,.04833,.06334,.04417,0.0*
1,1,.006,.06334,.04417*
20,1,.006,.06334,.04417,.06001,.03917,0.0*
1,1,.006,.06001,.03917*
20,1,.006,.06001,.03917,.05751,.0325,0.0*
1,1,.006,.05751,.0325*
20,1,.006,.05751,.0325,.05668,.025,0.0*
1,1,.006,.05668,.025*
20,1,.006,.05668,.025,.05751,.0175,0.0*
1,1,.006,.05751,.0175*
20,1,.006,.05751,.0175,.06001,.01083,0.0*
1,1,.006,.06001,.01083*
20,1,.006,.06001,.01083,.06334,.00583,0.0*
1,1,.006,.06334,.00583*
20,1,.006,.06334,.00583,.06834,.00167,0.0*
1,1,.006,.06834,.00167*
20,1,.006,.06834,.00167,.07501,0.0,0.0*
1,1,.006,.07501,0.0*
20,1,.006,.07501,0.0,.08168,.00167,0.0*
1,1,.006,.08168,.00167*
20,1,.006,.08168,.00167,.08668,.00583,0.0*
1,1,.006,.08668,.00583*
20,1,.006,.08668,.00583,.09001,.01083,0.0*
1,1,.006,.09001,.01083*
20,1,.006,.09001,.01083,.09251,.0175,0.0*
1,1,.006,.09251,.0175*
20,1,.006,.09251,.0175,.09334,.025,0.0*
1,1,.006,.09334,.025*
20,1,.006,.09334,.025,.09251,.0325,0.0*
1,1,.006,.09251,.0325*
20,1,.006,.09251,.0325,.09001,.03917,0.0*
1,1,.006,.09001,.03917*
20,1,.006,.09001,.03917,.08668,.04417,0.0*
1,1,.006,.08668,.04417*
20,1,.006,.08668,.04417,.08168,.04833,0.0*
1,1,.006,.08168,.04833*
20,1,.006,.08168,.04833,.07501,.05,0.0*
1,1,.006,.07501,.05*
%
%ADD19MACRO19*%
%AMMACRO21*
1,1,.006,.038,.038*
20,1,.006,.038,.038,.038,-.038,0.0*
1,1,.006,.038,-.038*
20,1,.006,.038,-.038,-.038,-.038,0.0*
1,1,.006,-.038,-.038*
20,1,.006,-.038,-.038,-.038,.038,0.0*
1,1,.006,-.038,.038*
20,1,.006,-.038,.038,.038,.038,0.0*
1,1,.006,.038,.038*
1,1,.006,-.0133,-.019*
20,1,.006,-.0133,-.019,-.0133,.019,0.0*
1,1,.006,-.0133,.019*
1,1,.006,.0133,.019*
20,1,.006,.0133,.019,.0133,-.019,0.0*
1,1,.006,.0133,-.019*
1,1,.006,.0133,0.0*
20,1,.006,.0133,0.0,-.0133,0.0,0.0*
1,1,.006,-.0133,0.0*
%
%ADD21MACRO21*%
%AMMACRO15*
1,1,.006,.0295,0.0*
20,1,.006,.0295,0.0,0.0,-.0295,0.0*
1,1,.006,0.0,-.0295*
20,1,.006,0.0,-.0295,-.0295,0.0,0.0*
1,1,.006,-.0295,0.0*
20,1,.006,-.0295,0.0,0.0,.0295,0.0*
1,1,.006,0.0,.0295*
20,1,.006,0.0,.0295,.0295,0.0,0.0*
1,1,.006,.0295,0.0*
1,1,.006,-.00934,-.01475*
20,1,.006,-.00934,-.01475,-.00934,.01475,0.0*
1,1,.006,-.00934,.01475*
20,1,.006,-.00934,.01475,.00934,.01475,0.0*
1,1,.006,.00934,.01475*
1,1,.006,.00246,.00049*
20,1,.006,.00246,.00049,-.00934,.00049,0.0*
1,1,.006,-.00934,.00049*
%
%ADD15MACRO15*%
%AMMACRO23*
1,1,.006,-.0135,.012*
20,1,.006,-.0135,.012,.0135,.012,0.0*
1,1,.006,.0135,.012*
20,1,.006,.0135,.012,.015584,.011818,0.0*
1,1,.006,.015584,.011818*
20,1,.006,.015584,.011818,.017604,.011276,0.0*
1,1,.006,.017604,.011276*
20,1,.006,.017604,.011276,.0195,.010392,0.0*
1,1,.006,.0195,.010392*
20,1,.006,.0195,.010392,.021213,.009193,0.0*
1,1,.006,.021213,.009193*
20,1,.006,.021213,.009193,.022693,.007713,0.0*
1,1,.006,.022693,.007713*
20,1,.006,.022693,.007713,.023892,.006,0.0*
1,1,.006,.023892,.006*
20,1,.006,.023892,.006,.024776,.004104,0.0*
1,1,.006,.024776,.004104*
20,1,.006,.024776,.004104,.025318,.002084,0.0*
1,1,.006,.025318,.002084*
20,1,.006,.025318,.002084,.0255,0.0,0.0*
1,1,.006,.0255,0.0*
20,1,.006,.0255,0.0,.025318,-.002084,0.0*
1,1,.006,.025318,-.002084*
20,1,.006,.025318,-.002084,.024776,-.004104,0.0*
1,1,.006,.024776,-.004104*
20,1,.006,.024776,-.004104,.023892,-.006,0.0*
1,1,.006,.023892,-.006*
20,1,.006,.023892,-.006,.022693,-.007713,0.0*
1,1,.006,.022693,-.007713*
20,1,.006,.022693,-.007713,.021213,-.009193,0.0*
1,1,.006,.021213,-.009193*
20,1,.006,.021213,-.009193,.0195,-.010392,0.0*
1,1,.006,.0195,-.010392*
20,1,.006,.0195,-.010392,.017604,-.011276,0.0*
1,1,.006,.017604,-.011276*
20,1,.006,.017604,-.011276,.015584,-.011818,0.0*
1,1,.006,.015584,-.011818*
20,1,.006,.015584,-.011818,.0135,-.012,0.0*
1,1,.006,.0135,-.012*
20,1,.006,.0135,-.012,-.0135,-.012,0.0*
1,1,.006,-.0135,-.012*
20,1,.006,-.0135,-.012,-.015584,-.011818,0.0*
1,1,.006,-.015584,-.011818*
20,1,.006,-.015584,-.011818,-.017604,-.011276,0.0*
1,1,.006,-.017604,-.011276*
20,1,.006,-.017604,-.011276,-.0195,-.010392,0.0*
1,1,.006,-.0195,-.010392*
20,1,.006,-.0195,-.010392,-.021213,-.009193,0.0*
1,1,.006,-.021213,-.009193*
20,1,.006,-.021213,-.009193,-.022693,-.007713,0.0*
1,1,.006,-.022693,-.007713*
20,1,.006,-.022693,-.007713,-.023892,-.006,0.0*
1,1,.006,-.023892,-.006*
20,1,.006,-.023892,-.006,-.024776,-.004104,0.0*
1,1,.006,-.024776,-.004104*
20,1,.006,-.024776,-.004104,-.025318,-.002084,0.0*
1,1,.006,-.025318,-.002084*
20,1,.006,-.025318,-.002084,-.0255,0.0,0.0*
1,1,.006,-.0255,0.0*
20,1,.006,-.0255,0.0,-.025318,.002084,0.0*
1,1,.006,-.025318,.002084*
20,1,.006,-.025318,.002084,-.024776,.004104,0.0*
1,1,.006,-.024776,.004104*
20,1,.006,-.024776,.004104,-.023892,.006,0.0*
1,1,.006,-.023892,.006*
20,1,.006,-.023892,.006,-.022693,.007713,0.0*
1,1,.006,-.022693,.007713*
20,1,.006,-.022693,.007713,-.021213,.009193,0.0*
1,1,.006,-.021213,.009193*
20,1,.006,-.021213,.009193,-.0195,.010392,0.0*
1,1,.006,-.0195,.010392*
20,1,.006,-.0195,.010392,-.017604,.011276,0.0*
1,1,.006,-.017604,.011276*
20,1,.006,-.017604,.011276,-.015584,.011818,0.0*
1,1,.006,-.015584,.011818*
20,1,.006,-.015584,.011818,-.0135,.012,0.0*
1,1,.006,-.0135,.012*
1,1,.006,-.006,-.006*
20,1,.006,-.006,-.006,-.0076,-.0058,0.0*
1,1,.006,-.0076,-.0058*
20,1,.006,-.0076,-.0058,-.009,-.005,0.0*
1,1,.006,-.009,-.005*
20,1,.006,-.009,-.005,-.0102,-.0038,0.0*
1,1,.006,-.0102,-.0038*
20,1,.006,-.0102,-.0038,-.011,-.0024,0.0*
1,1,.006,-.011,-.0024*
20,1,.006,-.011,-.0024,-.0114,-.0008,0.0*
1,1,.006,-.0114,-.0008*
20,1,.006,-.0114,-.0008,-.0114,.0008,0.0*
1,1,.006,-.0114,.0008*
20,1,.006,-.0114,.0008,-.011,.0024,0.0*
1,1,.006,-.011,.0024*
20,1,.006,-.011,.0024,-.0102,.0038,0.0*
1,1,.006,-.0102,.0038*
20,1,.006,-.0102,.0038,-.009,.005,0.0*
1,1,.006,-.009,.005*
20,1,.006,-.009,.005,-.0076,.0058,0.0*
1,1,.006,-.0076,.0058*
20,1,.006,-.0076,.0058,-.006,.006,0.0*
1,1,.006,-.006,.006*
20,1,.006,-.006,.006,-.0044,.0058,0.0*
1,1,.006,-.0044,.0058*
20,1,.006,-.0044,.0058,-.003,.005,0.0*
1,1,.006,-.003,.005*
20,1,.006,-.003,.005,-.0018,.0038,0.0*
1,1,.006,-.0018,.0038*
20,1,.006,-.0018,.0038,-.001,.0024,0.0*
1,1,.006,-.001,.0024*
20,1,.006,-.001,.0024,-.0006,.0008,0.0*
1,1,.006,-.0006,.0008*
20,1,.006,-.0006,.0008,-.0006,-.0008,0.0*
1,1,.006,-.0006,-.0008*
20,1,.006,-.0006,-.0008,-.001,-.0024,0.0*
1,1,.006,-.001,-.0024*
20,1,.006,-.001,-.0024,-.0018,-.0038,0.0*
1,1,.006,-.0018,-.0038*
20,1,.006,-.0018,-.0038,-.003,-.005,0.0*
1,1,.006,-.003,-.005*
20,1,.006,-.003,-.005,-.0044,-.0058,0.0*
1,1,.006,-.0044,-.0058*
20,1,.006,-.0044,-.0058,-.006,-.006,0.0*
1,1,.006,-.006,-.006*
1,1,.006,.00761,.0004*
20,1,.006,.00761,.0004,.00841,.001,0.0*
1,1,.006,.00841,.001*
20,1,.006,.00841,.001,.00901,.002,0.0*
1,1,.006,.00901,.002*
20,1,.006,.00901,.002,.00941,.0034,0.0*
1,1,.006,.00941,.0034*
20,1,.006,.00941,.0034,.00901,.0046,0.0*
1,1,.006,.00901,.0046*
20,1,.006,.00901,.0046,.00821,.0054,0.0*
1,1,.006,.00821,.0054*
20,1,.006,.00821,.0054,.00681,.006,0.0*
1,1,.006,.00681,.006*
20,1,.006,.00681,.006,.00141,.006,0.0*
1,1,.006,.00141,.006*
20,1,.006,.00141,.006,.00141,-.006,0.0*
1,1,.006,.00141,-.006*
20,1,.006,.00141,-.006,.00801,-.006,0.0*
1,1,.006,.00801,-.006*
20,1,.006,.00801,-.006,.00941,-.0052,0.0*
1,1,.006,.00941,-.0052*
20,1,.006,.00941,-.0052,.01021,-.004,0.0*
1,1,.006,.01021,-.004*
20,1,.006,.01021,-.004,.01061,-.0026,0.0*
1,1,.006,.01061,-.0026*
20,1,.006,.01061,-.0026,.01021,-.0012,0.0*
1,1,.006,.01021,-.0012*
20,1,.006,.01021,-.0012,.00901,0.0,0.0*
1,1,.006,.00901,0.0*
20,1,.006,.00901,0.0,.00761,.0004,0.0*
1,1,.006,.00761,.0004*
20,1,.006,.00761,.0004,.00141,.0004,0.0*
1,1,.006,.00141,.0004*
%
%ADD23MACRO23*%
%AMMACRO20*
1,1,.006,.083,.083*
20,1,.006,.083,.083,.083,-.083,0.0*
1,1,.006,.083,-.083*
20,1,.006,.083,-.083,-.083,-.083,0.0*
1,1,.006,-.083,-.083*
20,1,.006,-.083,-.083,-.083,.083,0.0*
1,1,.006,-.083,.083*
20,1,.006,-.083,.083,.083,.083,0.0*
1,1,.006,.083,.083*
1,1,.006,0.0,-.0415*
20,1,.006,0.0,-.0415,-.01107,-.04012,0.0*
1,1,.006,-.01107,-.04012*
20,1,.006,-.01107,-.04012,-.02075,-.03458,0.0*
1,1,.006,-.02075,-.03458*
20,1,.006,-.02075,-.03458,-.02905,-.02628,0.0*
1,1,.006,-.02905,-.02628*
20,1,.006,-.02905,-.02628,-.03458,-.0166,0.0*
1,1,.006,-.03458,-.0166*
20,1,.006,-.03458,-.0166,-.03735,-.00553,0.0*
1,1,.006,-.03735,-.00553*
20,1,.006,-.03735,-.00553,-.03735,.00553,0.0*
1,1,.006,-.03735,.00553*
20,1,.006,-.03735,.00553,-.03458,.0166,0.0*
1,1,.006,-.03458,.0166*
20,1,.006,-.03458,.0166,-.02905,.02628,0.0*
1,1,.006,-.02905,.02628*
20,1,.006,-.02905,.02628,-.02075,.03458,0.0*
1,1,.006,-.02075,.03458*
20,1,.006,-.02075,.03458,-.01107,.04012,0.0*
1,1,.006,-.01107,.04012*
20,1,.006,-.01107,.04012,0.0,.0415,0.0*
1,1,.006,0.0,.0415*
20,1,.006,0.0,.0415,.01107,.04012,0.0*
1,1,.006,.01107,.04012*
20,1,.006,.01107,.04012,.02075,.03458,0.0*
1,1,.006,.02075,.03458*
20,1,.006,.02075,.03458,.02905,.02628,0.0*
1,1,.006,.02905,.02628*
20,1,.006,.02905,.02628,.03458,.0166,0.0*
1,1,.006,.03458,.0166*
20,1,.006,.03458,.0166,.03735,.00553,0.0*
1,1,.006,.03735,.00553*
20,1,.006,.03735,.00553,.03735,-.00553,0.0*
1,1,.006,.03735,-.00553*
20,1,.006,.03735,-.00553,.03458,-.0166,0.0*
1,1,.006,.03458,-.0166*
20,1,.006,.03458,-.0166,.02905,-.02628,0.0*
1,1,.006,.02905,-.02628*
20,1,.006,.02905,-.02628,.02075,-.03458,0.0*
1,1,.006,.02075,-.03458*
20,1,.006,.02075,-.03458,.01107,-.04012,0.0*
1,1,.006,.01107,-.04012*
20,1,.006,.01107,-.04012,0.0,-.0415,0.0*
1,1,.006,0.0,-.0415*
1,1,.006,.01107,-.01937*
20,1,.006,.01107,-.01937,.02767,-.0415,0.0*
1,1,.006,.02767,-.0415*
%
%ADD20MACRO20*%
%AMMACRO16*
1,1,.006,-.0195,.012*
20,1,.006,-.0195,.012,.0195,.012,0.0*
1,1,.006,.0195,.012*
20,1,.006,.0195,.012,.021584,.011818,0.0*
1,1,.006,.021584,.011818*
20,1,.006,.021584,.011818,.023604,.011276,0.0*
1,1,.006,.023604,.011276*
20,1,.006,.023604,.011276,.0255,.010392,0.0*
1,1,.006,.0255,.010392*
20,1,.006,.0255,.010392,.027213,.009193,0.0*
1,1,.006,.027213,.009193*
20,1,.006,.027213,.009193,.028693,.007713,0.0*
1,1,.006,.028693,.007713*
20,1,.006,.028693,.007713,.029892,.006,0.0*
1,1,.006,.029892,.006*
20,1,.006,.029892,.006,.030776,.004104,0.0*
1,1,.006,.030776,.004104*
20,1,.006,.030776,.004104,.031318,.002084,0.0*
1,1,.006,.031318,.002084*
20,1,.006,.031318,.002084,.0315,0.0,0.0*
1,1,.006,.0315,0.0*
20,1,.006,.0315,0.0,.031318,-.002084,0.0*
1,1,.006,.031318,-.002084*
20,1,.006,.031318,-.002084,.030776,-.004104,0.0*
1,1,.006,.030776,-.004104*
20,1,.006,.030776,-.004104,.029892,-.006,0.0*
1,1,.006,.029892,-.006*
20,1,.006,.029892,-.006,.028693,-.007713,0.0*
1,1,.006,.028693,-.007713*
20,1,.006,.028693,-.007713,.027213,-.009193,0.0*
1,1,.006,.027213,-.009193*
20,1,.006,.027213,-.009193,.0255,-.010392,0.0*
1,1,.006,.0255,-.010392*
20,1,.006,.0255,-.010392,.023604,-.011276,0.0*
1,1,.006,.023604,-.011276*
20,1,.006,.023604,-.011276,.021584,-.011818,0.0*
1,1,.006,.021584,-.011818*
20,1,.006,.021584,-.011818,.0195,-.012,0.0*
1,1,.006,.0195,-.012*
20,1,.006,.0195,-.012,-.0195,-.012,0.0*
1,1,.006,-.0195,-.012*
20,1,.006,-.0195,-.012,-.021584,-.011818,0.0*
1,1,.006,-.021584,-.011818*
20,1,.006,-.021584,-.011818,-.023604,-.011276,0.0*
1,1,.006,-.023604,-.011276*
20,1,.006,-.023604,-.011276,-.0255,-.010392,0.0*
1,1,.006,-.0255,-.010392*
20,1,.006,-.0255,-.010392,-.027213,-.009193,0.0*
1,1,.006,-.027213,-.009193*
20,1,.006,-.027213,-.009193,-.028693,-.007713,0.0*
1,1,.006,-.028693,-.007713*
20,1,.006,-.028693,-.007713,-.029892,-.006,0.0*
1,1,.006,-.029892,-.006*
20,1,.006,-.029892,-.006,-.030776,-.004104,0.0*
1,1,.006,-.030776,-.004104*
20,1,.006,-.030776,-.004104,-.031318,-.002084,0.0*
1,1,.006,-.031318,-.002084*
20,1,.006,-.031318,-.002084,-.0315,0.0,0.0*
1,1,.006,-.0315,0.0*
20,1,.006,-.0315,0.0,-.031318,.002084,0.0*
1,1,.006,-.031318,.002084*
20,1,.006,-.031318,.002084,-.030776,.004104,0.0*
1,1,.006,-.030776,.004104*
20,1,.006,-.030776,.004104,-.029892,.006,0.0*
1,1,.006,-.029892,.006*
20,1,.006,-.029892,.006,-.028693,.007713,0.0*
1,1,.006,-.028693,.007713*
20,1,.006,-.028693,.007713,-.027213,.009193,0.0*
1,1,.006,-.027213,.009193*
20,1,.006,-.027213,.009193,-.0255,.010392,0.0*
1,1,.006,-.0255,.010392*
20,1,.006,-.0255,.010392,-.023604,.011276,0.0*
1,1,.006,-.023604,.011276*
20,1,.006,-.023604,.011276,-.021584,.011818,0.0*
1,1,.006,-.021584,.011818*
20,1,.006,-.021584,.011818,-.0195,.012,0.0*
1,1,.006,-.0195,.012*
1,1,.006,-.006,-.006*
20,1,.006,-.006,-.006,-.0076,-.0058,0.0*
1,1,.006,-.0076,-.0058*
20,1,.006,-.0076,-.0058,-.009,-.005,0.0*
1,1,.006,-.009,-.005*
20,1,.006,-.009,-.005,-.0102,-.0038,0.0*
1,1,.006,-.0102,-.0038*
20,1,.006,-.0102,-.0038,-.011,-.0024,0.0*
1,1,.006,-.011,-.0024*
20,1,.006,-.011,-.0024,-.0114,-.0008,0.0*
1,1,.006,-.0114,-.0008*
20,1,.006,-.0114,-.0008,-.0114,.0008,0.0*
1,1,.006,-.0114,.0008*
20,1,.006,-.0114,.0008,-.011,.0024,0.0*
1,1,.006,-.011,.0024*
20,1,.006,-.011,.0024,-.0102,.0038,0.0*
1,1,.006,-.0102,.0038*
20,1,.006,-.0102,.0038,-.009,.005,0.0*
1,1,.006,-.009,.005*
20,1,.006,-.009,.005,-.0076,.0058,0.0*
1,1,.006,-.0076,.0058*
20,1,.006,-.0076,.0058,-.006,.006,0.0*
1,1,.006,-.006,.006*
20,1,.006,-.006,.006,-.0044,.0058,0.0*
1,1,.006,-.0044,.0058*
20,1,.006,-.0044,.0058,-.003,.005,0.0*
1,1,.006,-.003,.005*
20,1,.006,-.003,.005,-.0018,.0038,0.0*
1,1,.006,-.0018,.0038*
20,1,.006,-.0018,.0038,-.001,.0024,0.0*
1,1,.006,-.001,.0024*
20,1,.006,-.001,.0024,-.0006,.0008,0.0*
1,1,.006,-.0006,.0008*
20,1,.006,-.0006,.0008,-.0006,-.0008,0.0*
1,1,.006,-.0006,-.0008*
20,1,.006,-.0006,-.0008,-.001,-.0024,0.0*
1,1,.006,-.001,-.0024*
20,1,.006,-.001,-.0024,-.0018,-.0038,0.0*
1,1,.006,-.0018,-.0038*
20,1,.006,-.0018,-.0038,-.003,-.005,0.0*
1,1,.006,-.003,-.005*
20,1,.006,-.003,-.005,-.0044,-.0058,0.0*
1,1,.006,-.0044,-.0058*
20,1,.006,-.0044,-.0058,-.006,-.006,0.0*
1,1,.006,-.006,-.006*
1,1,.006,.00761,.0004*
20,1,.006,.00761,.0004,.00841,.001,0.0*
1,1,.006,.00841,.001*
20,1,.006,.00841,.001,.00901,.002,0.0*
1,1,.006,.00901,.002*
20,1,.006,.00901,.002,.00941,.0034,0.0*
1,1,.006,.00941,.0034*
20,1,.006,.00941,.0034,.00901,.0046,0.0*
1,1,.006,.00901,.0046*
20,1,.006,.00901,.0046,.00821,.0054,0.0*
1,1,.006,.00821,.0054*
20,1,.006,.00821,.0054,.00681,.006,0.0*
1,1,.006,.00681,.006*
20,1,.006,.00681,.006,.00141,.006,0.0*
1,1,.006,.00141,.006*
20,1,.006,.00141,.006,.00141,-.006,0.0*
1,1,.006,.00141,-.006*
20,1,.006,.00141,-.006,.00801,-.006,0.0*
1,1,.006,.00801,-.006*
20,1,.006,.00801,-.006,.00941,-.0052,0.0*
1,1,.006,.00941,-.0052*
20,1,.006,.00941,-.0052,.01021,-.004,0.0*
1,1,.006,.01021,-.004*
20,1,.006,.01021,-.004,.01061,-.0026,0.0*
1,1,.006,.01061,-.0026*
20,1,.006,.01061,-.0026,.01021,-.0012,0.0*
1,1,.006,.01021,-.0012*
20,1,.006,.01021,-.0012,.00901,0.0,0.0*
1,1,.006,.00901,0.0*
20,1,.006,.00901,0.0,.00761,.0004,0.0*
1,1,.006,.00761,.0004*
20,1,.006,.00761,.0004,.00141,.0004,0.0*
1,1,.006,.00141,.0004*
%
%ADD16MACRO16*%
%AMMACRO18*
1,1,.006,.0395,0.0*
20,1,.006,.0395,0.0,0.0,-.0395,0.0*
1,1,.006,0.0,-.0395*
20,1,.006,0.0,-.0395,-.0395,0.0,0.0*
1,1,.006,-.0395,0.0*
20,1,.006,-.0395,0.0,0.0,.0395,0.0*
1,1,.006,0.0,.0395*
20,1,.006,0.0,.0395,.0395,0.0,0.0*
1,1,.006,.0395,0.0*
1,1,.006,-.01383,-.01975*
20,1,.006,-.01383,-.01975,-.01383,.01975,0.0*
1,1,.006,-.01383,.01975*
1,1,.006,.01383,.01975*
20,1,.006,.01383,.01975,.01383,-.01975,0.0*
1,1,.006,.01383,-.01975*
1,1,.006,.01383,0.0*
20,1,.006,.01383,0.0,-.01383,0.0,0.0*
1,1,.006,-.01383,0.0*
%
%ADD18MACRO18*%
%AMMACRO10*
1,1,.006,0.0,.025*
20,1,.006,0.0,.025,.004341,.02462,0.0*
1,1,.006,.004341,.02462*
20,1,.006,.004341,.02462,.008551,.023492,0.0*
1,1,.006,.008551,.023492*
20,1,.006,.008551,.023492,.0125,.021651,0.0*
1,1,.006,.0125,.021651*
20,1,.006,.0125,.021651,.01607,.019151,0.0*
1,1,.006,.01607,.019151*
20,1,.006,.01607,.019151,.019151,.01607,0.0*
1,1,.006,.019151,.01607*
20,1,.006,.019151,.01607,.021651,.0125,0.0*
1,1,.006,.021651,.0125*
20,1,.006,.021651,.0125,.023492,.008551,0.0*
1,1,.006,.023492,.008551*
20,1,.006,.023492,.008551,.02462,.004341,0.0*
1,1,.006,.02462,.004341*
20,1,.006,.02462,.004341,.025,0.0,0.0*
1,1,.006,.025,0.0*
20,1,.006,.025,0.0,.02462,-.004341,0.0*
1,1,.006,.02462,-.004341*
20,1,.006,.02462,-.004341,.023492,-.008551,0.0*
1,1,.006,.023492,-.008551*
20,1,.006,.023492,-.008551,.021651,-.0125,0.0*
1,1,.006,.021651,-.0125*
20,1,.006,.021651,-.0125,.019151,-.01607,0.0*
1,1,.006,.019151,-.01607*
20,1,.006,.019151,-.01607,.01607,-.019151,0.0*
1,1,.006,.01607,-.019151*
20,1,.006,.01607,-.019151,.0125,-.021651,0.0*
1,1,.006,.0125,-.021651*
20,1,.006,.0125,-.021651,.008551,-.023492,0.0*
1,1,.006,.008551,-.023492*
20,1,.006,.008551,-.023492,.004341,-.02462,0.0*
1,1,.006,.004341,-.02462*
20,1,.006,.004341,-.02462,0.0,-.025,0.0*
1,1,.006,0.0,-.025*
20,1,.006,0.0,-.025,-.004341,-.02462,0.0*
1,1,.006,-.004341,-.02462*
20,1,.006,-.004341,-.02462,-.008551,-.023492,0.0*
1,1,.006,-.008551,-.023492*
20,1,.006,-.008551,-.023492,-.0125,-.021651,0.0*
1,1,.006,-.0125,-.021651*
20,1,.006,-.0125,-.021651,-.01607,-.019151,0.0*
1,1,.006,-.01607,-.019151*
20,1,.006,-.01607,-.019151,-.019151,-.01607,0.0*
1,1,.006,-.019151,-.01607*
20,1,.006,-.019151,-.01607,-.021651,-.0125,0.0*
1,1,.006,-.021651,-.0125*
20,1,.006,-.021651,-.0125,-.023492,-.008551,0.0*
1,1,.006,-.023492,-.008551*
20,1,.006,-.023492,-.008551,-.02462,-.004341,0.0*
1,1,.006,-.02462,-.004341*
20,1,.006,-.02462,-.004341,-.025,0.0,0.0*
1,1,.006,-.025,0.0*
20,1,.006,-.025,0.0,-.02462,.004341,0.0*
1,1,.006,-.02462,.004341*
20,1,.006,-.02462,.004341,-.023492,.008551,0.0*
1,1,.006,-.023492,.008551*
20,1,.006,-.023492,.008551,-.021651,.0125,0.0*
1,1,.006,-.021651,.0125*
20,1,.006,-.021651,.0125,-.019151,.01607,0.0*
1,1,.006,-.019151,.01607*
20,1,.006,-.019151,.01607,-.01607,.019151,0.0*
1,1,.006,-.01607,.019151*
20,1,.006,-.01607,.019151,-.0125,.021651,0.0*
1,1,.006,-.0125,.021651*
20,1,.006,-.0125,.021651,-.008551,.023492,0.0*
1,1,.006,-.008551,.023492*
20,1,.006,-.008551,.023492,-.004341,.02462,0.0*
1,1,.006,-.004341,.02462*
20,1,.006,-.004341,.02462,0.0,.025,0.0*
1,1,.006,0.0,.025*
1,1,.006,-.01042,-.0125*
20,1,.006,-.01042,-.0125,0.0,.0125,0.0*
1,1,.006,0.0,.0125*
20,1,.006,0.0,.0125,.01042,-.0125,0.0*
1,1,.006,.01042,-.0125*
1,1,.006,.00667,-.00375*
20,1,.006,.00667,-.00375,-.00667,-.00375,0.0*
1,1,.006,-.00667,-.00375*
%
%ADD10MACRO10*%
%AMMACRO14*
1,1,.006,0.0,.025*
20,1,.006,0.0,.025,-.021651,.0125,0.0*
1,1,.006,-.021651,.0125*
20,1,.006,-.021651,.0125,-.021651,-.0125,0.0*
1,1,.006,-.021651,-.0125*
20,1,.006,-.021651,-.0125,0.0,-.025,0.0*
1,1,.006,0.0,-.025*
20,1,.006,0.0,-.025,.021651,-.0125,0.0*
1,1,.006,.021651,-.0125*
20,1,.006,.021651,-.0125,.021651,.0125,0.0*
1,1,.006,.021651,.0125*
20,1,.006,.021651,.0125,0.0,.025,0.0*
1,1,.006,0.0,.025*
1,1,.006,.00333,.00083*
20,1,.006,.00333,.00083,.005,.00208,0.0*
1,1,.006,.005,.00208*
20,1,.006,.005,.00208,.00625,.00417,0.0*
1,1,.006,.00625,.00417*
20,1,.006,.00625,.00417,.00708,.00708,0.0*
1,1,.006,.00708,.00708*
20,1,.006,.00708,.00708,.00625,.00958,0.0*
1,1,.006,.00625,.00958*
20,1,.006,.00625,.00958,.00458,.01125,0.0*
1,1,.006,.00458,.01125*
20,1,.006,.00458,.01125,.00167,.0125,0.0*
1,1,.006,.00167,.0125*
20,1,.006,.00167,.0125,-.00958,.0125,0.0*
1,1,.006,-.00958,.0125*
20,1,.006,-.00958,.0125,-.00958,-.0125,0.0*
1,1,.006,-.00958,-.0125*
20,1,.006,-.00958,-.0125,.00417,-.0125,0.0*
1,1,.006,.00417,-.0125*
20,1,.006,.00417,-.0125,.00708,-.01083,0.0*
1,1,.006,.00708,-.01083*
20,1,.006,.00708,-.01083,.00875,-.00833,0.0*
1,1,.006,.00875,-.00833*
20,1,.006,.00875,-.00833,.00958,-.00542,0.0*
1,1,.006,.00958,-.00542*
20,1,.006,.00958,-.00542,.00875,-.0025,0.0*
1,1,.006,.00875,-.0025*
20,1,.006,.00875,-.0025,.00625,0.0,0.0*
1,1,.006,.00625,0.0*
20,1,.006,.00625,0.0,.00333,.00083,0.0*
1,1,.006,.00333,.00083*
20,1,.006,.00333,.00083,-.00958,.00083,0.0*
1,1,.006,-.00958,.00083*
%
%ADD14MACRO14*%
%ADD25C,.01*%
%ADD26C,.001*%
%ADD27C,.006*%
G75*
%LPD*%
G75*
G54D10*
X8878Y21717D03*
X4878D03*
X4000Y25619D03*
Y29619D03*
Y33619D03*
Y37619D03*
Y41619D03*
Y45619D03*
Y49619D03*
Y281619D03*
Y285619D03*
Y289619D03*
Y293619D03*
Y297619D03*
Y301619D03*
Y305619D03*
Y309619D03*
Y313619D03*
Y337619D03*
Y341619D03*
Y345619D03*
Y349619D03*
Y353619D03*
Y357619D03*
Y361619D03*
Y365619D03*
Y369619D03*
Y373619D03*
Y377619D03*
Y381619D03*
Y385619D03*
Y389619D03*
Y393619D03*
Y397619D03*
Y401619D03*
Y405619D03*
Y409619D03*
Y413619D03*
Y417619D03*
Y421619D03*
Y425619D03*
Y429619D03*
X4413Y433598D03*
X8413D03*
X24878Y21717D03*
X20878D03*
X16878D03*
X12878D03*
X12413Y433598D03*
X16413D03*
X20413D03*
X24413D03*
X28413D03*
X44878Y21717D03*
X40878D03*
X36878D03*
X32878D03*
X28878D03*
X46000Y82000D03*
X32413Y433598D03*
X36413D03*
X40413D03*
X44413D03*
X55055Y25073D03*
X52878Y21717D03*
X48878D03*
X55055Y41073D03*
Y37073D03*
Y33073D03*
Y29073D03*
X61463Y54048D03*
X57859Y52313D03*
X55558Y49041D03*
X55055Y45073D03*
X51765Y96600D03*
X48413Y433598D03*
X52413D03*
X56413D03*
X60413D03*
X77460Y54197D03*
X73460D03*
X69460D03*
X65460D03*
X76100Y154400D03*
X75950Y164200D03*
X79500Y234500D03*
X79600Y248900D03*
X79248Y266100D03*
X77964Y260100D03*
X73600Y252500D03*
X75800Y274300D03*
X67000Y283100D03*
X72000Y271400D03*
X68600Y274000D03*
X75500Y282500D03*
X63800Y274000D03*
X76700Y357500D03*
X67100D03*
X73500D03*
X70300D03*
X70500Y419000D03*
X75580Y419004D03*
X68413Y433598D03*
X72413D03*
X76413D03*
X80413D03*
X64413D03*
X97460Y54197D03*
X93460D03*
X89460D03*
X85460D03*
X81460D03*
X88300Y163900D03*
X86800Y230000D03*
X82500Y230500D03*
X84600Y248900D03*
X89600D03*
X85600Y263700D03*
X82500Y273200D03*
X87100Y271300D03*
X85800Y287452D03*
X98000Y420000D03*
X90000Y420500D03*
X85500D03*
X84413Y433598D03*
X88413D03*
X92413D03*
X96413D03*
X113460Y54197D03*
X109460D03*
X105460D03*
X101460D03*
X112800Y66600D03*
X112880Y73020D03*
X113700Y382500D03*
X104100D03*
X110500D03*
X107300D03*
X104413Y433598D03*
X108413D03*
X112413D03*
X100413D03*
X132920Y51926D03*
X129450Y53917D03*
X125460Y54197D03*
X121460D03*
X117460D03*
X126000Y67000D03*
Y62000D03*
X131500Y290500D03*
X116413Y433598D03*
X120413D03*
X124413D03*
X128413D03*
X132413D03*
X135299Y24509D03*
X150163Y21717D03*
X146163D03*
X142163D03*
X138163D03*
X135299Y28509D03*
Y32509D03*
Y36509D03*
Y40509D03*
Y44509D03*
X134977Y48496D03*
X148500Y62500D03*
X139500D03*
X144000D03*
X138500Y75000D03*
X145900Y75200D03*
X142070Y77900D03*
X142000Y69535D03*
X136000Y290500D03*
X138250Y372250D03*
X148500Y376000D03*
X138500Y387500D03*
X140413Y433598D03*
X144413D03*
X148413D03*
X136413D03*
X158163Y21717D03*
X154163D03*
X158795Y25667D03*
Y41667D03*
Y37667D03*
Y33667D03*
Y29667D03*
X160736Y49309D03*
X159112Y45654D03*
X163543Y52159D03*
X151840Y79935D03*
X153500Y390500D03*
X163300Y382900D03*
X151100Y386300D03*
X167100Y405600D03*
X152100Y399300D03*
X151530Y406300D03*
X153150Y394590D03*
X160600Y417400D03*
X152200Y416300D03*
X152413Y433598D03*
X156413D03*
X160413D03*
X164413D03*
X183170Y56390D03*
X180341Y47225D03*
X178196Y50601D03*
X180620Y77890D03*
X180390Y70720D03*
X180910Y63390D03*
X168413Y433598D03*
X172413D03*
X176413D03*
X180413D03*
X184413D03*
X191535Y28900D03*
X201950Y29050D03*
X187598Y36900D03*
X189500Y33000D03*
X186000D03*
X187598Y28900D03*
X191535Y41200D03*
X198135Y36500D03*
X195000Y54550D03*
X203000Y75000D03*
X196497Y76502D03*
X200413Y433598D03*
X188413D03*
X192413D03*
X196413D03*
X210500Y30500D03*
X207880Y78740D03*
X214810Y78810D03*
X208300Y289500D03*
X217300D03*
X212800D03*
X218500Y301700D03*
X213500D03*
X208500D03*
X209660Y331500D03*
X204413Y433598D03*
X208413D03*
X212413D03*
X216413D03*
X220413D03*
X232700Y29100D03*
X221800Y289500D03*
X224500Y302000D03*
X222000Y330000D03*
X224413Y433598D03*
X228413D03*
X232413D03*
X236413D03*
X254527Y28900D03*
X244619D03*
X254527Y33900D03*
X243500Y48650D03*
X252700Y44000D03*
X250222Y76300D03*
X247022D03*
X240508D03*
Y66700D03*
X243822Y76300D03*
X253422D03*
X240508Y69900D03*
Y73100D03*
X240413Y433598D03*
X244413D03*
X248413D03*
X252413D03*
X264339Y35300D03*
Y38500D03*
Y32100D03*
X264304Y28900D03*
X272309D03*
X264339Y41700D03*
X263300Y52200D03*
X269907Y76300D03*
X266707D03*
X263507D03*
X256413Y433598D03*
X260413D03*
X264413D03*
X268413D03*
X272413D03*
X280087Y35300D03*
Y38500D03*
Y41700D03*
Y32100D03*
X280052Y28900D03*
X288057D03*
X285055Y76300D03*
X281855D03*
X288255D03*
X273107D03*
X278655D03*
X284500Y181100D03*
Y184300D03*
Y187500D03*
X283400Y198700D03*
X280200D03*
X277000D03*
X286600D03*
X284500Y190700D03*
X286151Y329500D03*
X289600Y330100D03*
X288413Y433598D03*
X284413D03*
X280413D03*
X276413D03*
X295835Y35300D03*
Y38500D03*
Y41700D03*
Y32100D03*
X295800Y28900D03*
X295835Y44900D03*
Y48100D03*
X298726Y43529D03*
Y49471D03*
X307300Y61300D03*
X297700Y335100D03*
X298700Y327000D03*
Y323500D03*
X293200Y329500D03*
X304413Y433598D03*
X300413D03*
X296413D03*
X292413D03*
X307708Y28900D03*
X321402Y54197D03*
X317402D03*
X314763Y85237D03*
X312500Y87500D03*
X310237Y89763D03*
X317025Y82975D03*
X319510Y190299D03*
X322710D03*
X324000Y236000D03*
X318000Y268500D03*
X324300Y254700D03*
X322200Y320500D03*
Y325000D03*
X310600Y330500D03*
Y335000D03*
X322200Y338500D03*
X324413Y433598D03*
X320413D03*
X316413D03*
X312413D03*
X308413D03*
X329402Y54197D03*
X325402D03*
X337402D03*
X341402D03*
X333402D03*
X338599Y108500D03*
X341799D03*
X337500Y113000D03*
Y122600D03*
Y116200D03*
Y119400D03*
X329110Y190299D03*
X325910D03*
X327500Y232000D03*
X332600Y246600D03*
X328500Y238645D03*
X327800Y246800D03*
X334350Y282000D03*
X336500Y295000D03*
X336525Y320500D03*
Y325500D03*
X341500Y338500D03*
Y328500D03*
Y333500D03*
X336525Y330500D03*
X340413Y433598D03*
X336413D03*
X332413D03*
X328413D03*
X345402Y54197D03*
X349402D03*
X353402D03*
X357402D03*
X349000Y82500D03*
X359300Y92000D03*
X348199Y108500D03*
X348264Y104707D03*
X357864D03*
X344999Y108500D03*
X351464Y104707D03*
X354664D03*
X352300Y175000D03*
X345301Y196299D03*
Y186699D03*
Y193099D03*
Y189899D03*
X358400Y182700D03*
X345930Y217000D03*
X342900Y246800D03*
X354850Y276100D03*
X354800Y285600D03*
Y289800D03*
X344000Y295000D03*
X355000Y332500D03*
Y328000D03*
X358250Y340050D03*
X356413Y433598D03*
X352413D03*
X348413D03*
X344413D03*
X369402Y54197D03*
X373402D03*
X377402D03*
X361402D03*
X365402D03*
X373500Y78000D03*
X368900Y92000D03*
X373500Y94000D03*
X365700Y92000D03*
X362500D03*
X365101Y191559D03*
Y188359D03*
Y194759D03*
Y185159D03*
X361124Y349876D03*
X375500Y350500D03*
X376413Y433598D03*
X372413D03*
X368413D03*
X364413D03*
X360413D03*
X381402Y54197D03*
X385402D03*
X389402D03*
X393402D03*
X379500Y72500D03*
X380500Y77400D03*
X380400Y81600D03*
X381700Y92400D03*
X390000Y100500D03*
X387193Y143005D03*
X391130D03*
X387193Y135130D03*
X391130Y139067D03*
X387193D03*
Y146942D03*
X391130D03*
Y135130D03*
X387193Y150879D03*
X391130D03*
X387193Y158753D03*
X391130D03*
X387193Y154816D03*
Y162690D03*
X391130D03*
Y154816D03*
X387193Y166627D03*
X391130D03*
X387193Y170564D03*
X391130Y178437D03*
X387193D03*
X391130Y170564D03*
X383128Y178372D03*
X391130Y182374D03*
Y186311D03*
X385500Y196154D03*
X387193Y186311D03*
X391130Y205996D03*
Y209933D03*
X387193D03*
Y217807D03*
X391600Y304800D03*
X379300Y305000D03*
X383000Y328500D03*
Y333500D03*
Y346600D03*
X388500Y391000D03*
X393500D03*
X388500Y400000D03*
X393500D03*
X393000Y418500D03*
X392413Y433598D03*
X388413D03*
X384413D03*
X380413D03*
X397402Y54197D03*
X401402D03*
X405402D03*
X409402D03*
X396400Y100500D03*
X409200D03*
X398450Y116099D03*
X408050D03*
X401650D03*
X404850D03*
X395067Y146942D03*
X399005D03*
X395067Y139067D03*
X399005D03*
Y143005D03*
X402942D03*
Y146942D03*
X406879D03*
X410816D03*
X395067Y143005D03*
Y131193D03*
X406879Y135130D03*
X410816D03*
X406879Y139067D03*
X402942D03*
X410811Y131188D03*
X406874D03*
X399000Y135125D03*
Y131188D03*
X395067Y135130D03*
X410816Y143005D03*
Y139067D03*
X406879Y143005D03*
X395067Y154816D03*
X399005D03*
X395067Y162690D03*
X399005D03*
X395067Y150879D03*
X402942Y154816D03*
X399005Y158753D03*
X410816D03*
X402942Y162690D03*
X410816D03*
Y150879D03*
Y154816D03*
X395067Y158753D03*
X402942Y150879D03*
X406879D03*
X399005D03*
X402942Y158753D03*
X406879Y162690D03*
Y154816D03*
Y158753D03*
X395067Y170564D03*
X399005D03*
X395067Y166627D03*
X410816D03*
X402942Y170564D03*
X406879D03*
X395067Y178437D03*
X399005D03*
X410816D03*
Y170564D03*
X402942Y166627D03*
X406879D03*
X399005D03*
X402942Y178437D03*
X406879D03*
X395067Y182374D03*
X399005Y186311D03*
Y190248D03*
X406879Y198122D03*
X399005Y182374D03*
X410816Y186311D03*
X395067Y194185D03*
X402942Y190248D03*
X406879Y182374D03*
Y186311D03*
Y194185D03*
X395067Y186311D03*
Y190248D03*
X402942Y182374D03*
X399005Y198122D03*
X395067D03*
X410816Y182374D03*
Y190248D03*
Y198122D03*
X402942Y186311D03*
Y194185D03*
X399005D03*
X402942Y198122D03*
X410816Y194185D03*
X406879Y190248D03*
X402942Y209933D03*
X395067Y213870D03*
X410816Y205996D03*
X399005Y202059D03*
X395067D03*
X402942Y205996D03*
X399005D03*
X406879Y202059D03*
X410816Y209933D03*
Y202059D03*
X399005Y209933D03*
X395067D03*
X406879Y205996D03*
Y209933D03*
X402942Y202059D03*
X395067Y205996D03*
X406879Y213870D03*
Y217807D03*
X405463Y383000D03*
X410463D03*
X398500Y391000D03*
Y400000D03*
X403000Y418500D03*
X398000D03*
X408413Y433598D03*
X404413D03*
X400413D03*
X396413D03*
X417402Y54197D03*
X421402D03*
X425402D03*
X429402D03*
X413402D03*
X413622Y75000D03*
X414753Y131193D03*
X422627Y146942D03*
X426564Y135130D03*
X418690Y139067D03*
X422627Y135130D03*
X418690D03*
X414753D03*
X422627Y131193D03*
X418690D03*
X426564Y146942D03*
Y143005D03*
Y131193D03*
Y139067D03*
X422627D03*
Y143005D03*
X418690D03*
X414753D03*
Y139067D03*
X418690Y146942D03*
X414753D03*
Y162690D03*
Y154816D03*
X418690Y158753D03*
X422627Y162690D03*
Y154816D03*
X426564Y162690D03*
Y158753D03*
X418690Y154816D03*
Y162690D03*
X414753Y158753D03*
X422627D03*
X426564Y154816D03*
X414753Y150879D03*
X422627D03*
X418690D03*
X426564D03*
X418690Y166627D03*
X414753Y170564D03*
X422627D03*
X418690Y178437D03*
X426564Y166627D03*
Y178437D03*
X418690Y170564D03*
X414753Y166627D03*
X426564Y170564D03*
X414753Y178437D03*
X422627Y166627D03*
Y178437D03*
Y190248D03*
X414753Y194185D03*
X426564Y198122D03*
X418690Y182374D03*
X426564Y186311D03*
Y190248D03*
X418690Y198122D03*
X422627Y194185D03*
Y186311D03*
Y182374D03*
X426564D03*
X414753Y190248D03*
X418690D03*
Y186311D03*
X414753D03*
Y182374D03*
Y198122D03*
X426564Y194185D03*
X422627Y198122D03*
X418690Y194185D03*
X414753Y213870D03*
X418690Y202059D03*
X422627Y209933D03*
X418690Y205996D03*
X414753D03*
Y209933D03*
X418690Y213870D03*
X414753Y202059D03*
X426564D03*
Y205996D03*
Y209933D03*
X422627Y202059D03*
Y205996D03*
X418690Y209933D03*
X426564Y217807D03*
X421360Y359970D03*
X415463Y383000D03*
X414000Y419000D03*
X422337Y424000D03*
X416800D03*
X428413Y433598D03*
X424413D03*
X420413D03*
X416413D03*
X412413D03*
X433402Y54197D03*
X437402D03*
X441402D03*
X445402D03*
X444050Y116599D03*
X434450D03*
X437650D03*
X440850D03*
X442311Y139067D03*
X446248Y143005D03*
X434437D03*
X438374Y131193D03*
X446248Y146942D03*
X442311Y143005D03*
Y146942D03*
X438374Y135130D03*
X434437Y146942D03*
X438374D03*
X446248Y139067D03*
X445939Y135439D03*
X438374Y143005D03*
Y139067D03*
X434437D03*
Y135130D03*
Y131193D03*
X446248Y158753D03*
X442311Y162690D03*
X434437D03*
Y154816D03*
X438374Y162690D03*
Y150879D03*
Y158753D03*
X442311Y154816D03*
X434437Y158753D03*
X442311D03*
X438374Y154816D03*
X446248D03*
Y162690D03*
X434437Y150879D03*
X442311D03*
X446248D03*
X438374Y166627D03*
X446248D03*
X434437Y170564D03*
X442311D03*
X446248Y178437D03*
X434437Y166627D03*
X438374Y178437D03*
Y170564D03*
X442311Y166627D03*
X434437Y178437D03*
X446248Y170564D03*
X442311Y178437D03*
X446248Y182374D03*
Y186311D03*
X442311D03*
Y182374D03*
X438374Y194185D03*
Y190248D03*
X446248D03*
X434437Y186311D03*
Y190248D03*
Y194185D03*
Y182374D03*
X438374Y198122D03*
X442311Y190248D03*
Y194185D03*
X434437Y198122D03*
X446248D03*
X438374Y182374D03*
Y186311D03*
X446248Y194185D03*
X442311Y198122D03*
X434437Y205996D03*
X446248Y209933D03*
X438374D03*
Y205996D03*
Y202059D03*
X442311Y209933D03*
X438374Y213870D03*
X442311Y202059D03*
X434437D03*
Y213870D03*
X442311Y205996D03*
X446248D03*
Y202059D03*
X434437Y209933D03*
X438374Y217807D03*
X434437D03*
X446500Y289500D03*
X441500Y297500D03*
X439500Y337892D03*
X442500Y336089D03*
X439500Y341500D03*
X443000Y386500D03*
Y401500D03*
Y396500D03*
X432000D03*
X444000Y406500D03*
X431900Y392200D03*
X431169Y401169D03*
X444000Y416500D03*
Y411500D03*
X444413Y433598D03*
X440413D03*
X436413D03*
X432413D03*
X449402Y54197D03*
X453402D03*
X457402D03*
X461402D03*
X450930Y122167D03*
X460530D03*
X457330D03*
X454130D03*
X454122Y143005D03*
X457844Y131408D03*
X461996Y131193D03*
X450185Y143005D03*
Y135130D03*
X461996Y139067D03*
X454122D03*
X458059D03*
X461996Y135130D03*
X454122D03*
X457844Y135345D03*
X449876Y131502D03*
X454122Y131193D03*
X458059Y146942D03*
X461996D03*
X450185D03*
X454122D03*
X458059Y143005D03*
X461996D03*
X450185Y139067D03*
X458059Y158753D03*
X450185Y154816D03*
X461996Y158753D03*
X450185Y162690D03*
X454122Y158753D03*
Y162690D03*
X450185Y158753D03*
X458059Y150879D03*
Y162690D03*
X454122Y150879D03*
X461996D03*
X454122Y154816D03*
X458059D03*
X461996D03*
X450185Y150879D03*
X458059Y178437D03*
Y166627D03*
X450185Y170564D03*
X454123D03*
X454122Y166627D03*
X450185D03*
Y178437D03*
X454122D03*
X461996Y170564D03*
Y178437D03*
X458060Y170564D03*
X461996Y166627D03*
X450185Y182374D03*
X454122Y186311D03*
X450185Y198122D03*
X458059Y190248D03*
X454122Y182374D03*
X461996D03*
X458059Y194185D03*
X461996Y186311D03*
X458059Y182374D03*
X454122Y194185D03*
X450185D03*
X454122Y190248D03*
X458059Y186311D03*
X454122Y198122D03*
X458059D03*
X461996Y190248D03*
Y198122D03*
Y194185D03*
X450185Y186311D03*
Y190248D03*
X461996Y202059D03*
X458059Y213870D03*
X454122Y205996D03*
X461996Y209933D03*
Y205996D03*
Y213870D03*
X458059Y202059D03*
Y205996D03*
X454122Y209933D03*
X458059D03*
X450185D03*
Y213870D03*
X454122D03*
X450185Y202059D03*
X454122D03*
X450185Y205996D03*
X454122Y217807D03*
X450185D03*
X461996D03*
X458059D03*
X464413Y433598D03*
X460413D03*
X456413D03*
X452413D03*
X448413D03*
X465402Y54197D03*
X469402D03*
X473402D03*
X477402D03*
X481402D03*
X465933Y146942D03*
X469870Y135130D03*
X465933Y131193D03*
X473807Y135130D03*
Y139067D03*
Y146942D03*
X469870D03*
X473807Y143005D03*
X465933Y139067D03*
X469870D03*
Y131193D03*
X473807D03*
X465933Y135130D03*
Y143005D03*
X469870D03*
X465933Y154816D03*
X469870D03*
X475000Y163000D03*
X465933Y158753D03*
Y150879D03*
X469870D03*
Y178437D03*
X473807Y166627D03*
X465933D03*
Y170564D03*
Y178437D03*
X469870Y166627D03*
Y170564D03*
X473807D03*
Y178437D03*
X465933Y190248D03*
Y194185D03*
X473807Y186311D03*
X469870Y198122D03*
X465933Y186311D03*
X469870Y190248D03*
X473807Y182374D03*
X469870D03*
X465933D03*
X469870Y186311D03*
X473807Y190248D03*
X469870Y194185D03*
X465933Y198122D03*
X473807Y205996D03*
X465933Y209933D03*
X469870Y213870D03*
Y209933D03*
X465933Y202059D03*
Y205996D03*
X473807Y213870D03*
X469870Y205996D03*
X473807Y209933D03*
X469870Y217807D03*
X473807D03*
X470462Y369462D03*
X470500Y395000D03*
X480413Y433598D03*
X476413D03*
X472413D03*
X468413D03*
X485402Y54197D03*
X489402D03*
X493402D03*
X497402D03*
X490970Y133500D03*
Y138500D03*
X488500Y359000D03*
X493500D03*
X496413Y433598D03*
X492413D03*
X488413D03*
X484413D03*
X501402Y54197D03*
X505402D03*
X509402D03*
X513402D03*
X500500Y271100D03*
X500000Y278799D03*
X503000Y354600D03*
X516413Y433598D03*
X512413D03*
X508413D03*
X504413D03*
X500413D03*
X517402Y54197D03*
X521402D03*
X525402D03*
X529402D03*
X533402D03*
X533000Y95000D03*
Y99500D03*
X522400Y270700D03*
X522600Y276200D03*
X528500Y299000D03*
X532300Y425700D03*
X532413Y433598D03*
X528413D03*
X524413D03*
X520413D03*
X537402Y54197D03*
X541402D03*
X545402D03*
X549402D03*
X549500Y69400D03*
X548158Y228033D03*
X545250Y256300D03*
X539977Y275124D03*
X540318Y270436D03*
X537500Y296607D03*
X550643Y400900D03*
X548413Y433598D03*
X544413D03*
X540413D03*
X536413D03*
X553402Y54197D03*
X557402D03*
X561402D03*
X565402D03*
X568600Y76000D03*
X566600Y212900D03*
X553122Y227979D03*
X559500Y228000D03*
X566700Y227500D03*
X568000Y356700D03*
X552000Y367597D03*
Y371141D03*
X555200Y367597D03*
Y371141D03*
X555569Y388051D03*
X552000Y374684D03*
Y378227D03*
X555200D03*
Y374684D03*
X568413Y433598D03*
X564413D03*
X560413D03*
X556413D03*
X552413D03*
X569402Y54197D03*
X573402D03*
X577402D03*
X581402D03*
X585402D03*
X572500Y60301D03*
X572870Y67570D03*
X577100Y227900D03*
X581400Y262100D03*
Y272100D03*
Y282100D03*
X581500Y302100D03*
X576200Y342500D03*
X584413Y433598D03*
X580413D03*
X576413D03*
X572413D03*
X589402Y54197D03*
X593402D03*
X597402D03*
X601402D03*
X597000Y199900D03*
X591902Y200300D03*
X601902Y200100D03*
X594153Y220500D03*
X589953Y236600D03*
X591000Y261500D03*
X590500Y301500D03*
X600413Y433598D03*
X596413D03*
X592413D03*
X588413D03*
X605402Y54197D03*
X609402D03*
X613402D03*
X617402D03*
X621402D03*
X606902Y200400D03*
X619961Y230874D03*
Y221274D03*
Y224474D03*
Y227674D03*
X620413Y433598D03*
X616413D03*
X612413D03*
X608413D03*
X604413D03*
X625402Y54197D03*
X629402D03*
X633500Y205906D03*
X625800Y215874D03*
X633000Y267000D03*
X636413Y433598D03*
X632413D03*
X628413D03*
X624413D03*
X649402Y54197D03*
X653402D03*
X656039Y57205D03*
Y61205D03*
Y65205D03*
Y69205D03*
Y73205D03*
Y77205D03*
Y81205D03*
Y85205D03*
Y89205D03*
Y93205D03*
Y97205D03*
Y101205D03*
Y105205D03*
Y109205D03*
Y113205D03*
Y117205D03*
Y121205D03*
Y125205D03*
Y129205D03*
Y145205D03*
Y133205D03*
Y137205D03*
Y141205D03*
Y149205D03*
Y153205D03*
Y157205D03*
Y161205D03*
Y165205D03*
Y169205D03*
Y173205D03*
Y177205D03*
Y181205D03*
Y235585D03*
Y311909D03*
Y315909D03*
Y319909D03*
Y323909D03*
Y327909D03*
Y331909D03*
Y335909D03*
Y339909D03*
Y343909D03*
Y347909D03*
Y351909D03*
Y355909D03*
Y359909D03*
Y363909D03*
Y367909D03*
Y371909D03*
Y375909D03*
Y379909D03*
Y383909D03*
Y387909D03*
Y391909D03*
Y395909D03*
Y399909D03*
Y403909D03*
Y407909D03*
Y411909D03*
Y415909D03*
Y419909D03*
Y423909D03*
Y427909D03*
Y431909D03*
X652413Y433598D03*
X648413D03*
X644413D03*
X640413D03*
X873950Y373500D03*
G54D20*
X255906Y309646D03*
Y412008D03*
X494094Y309646D03*
Y412008D03*
X873950Y148500D03*
G54D11*
X6039Y61260D03*
Y81260D03*
Y118346D03*
Y138346D03*
Y175433D03*
Y195433D03*
Y232520D03*
Y252520D03*
X26039Y61260D03*
Y81260D03*
Y118346D03*
Y138346D03*
Y175433D03*
Y195433D03*
Y232520D03*
Y252520D03*
X873950Y223500D03*
G54D21*
X588779Y334449D03*
Y350984D03*
Y367519D03*
X605315Y334449D03*
Y350984D03*
Y367519D03*
X873950Y198500D03*
G54D12*
X11264Y152264D03*
X9000Y279000D03*
Y286000D03*
X17500Y91000D03*
X12500D03*
Y96000D03*
Y101000D03*
Y106000D03*
X19100Y148798D03*
X23600D03*
X28100D03*
X13620Y148720D03*
X13000Y157000D03*
X12500Y162000D03*
X17000Y204500D03*
X12500Y209500D03*
Y204500D03*
Y214500D03*
Y219500D03*
X11963Y266437D03*
X19000Y262500D03*
X24200Y262508D03*
X28700D03*
X12500Y261500D03*
X19900Y283000D03*
X15000Y279000D03*
X28700Y274300D03*
X13000Y273327D03*
X16000Y302500D03*
X28500Y302000D03*
X28000Y296500D03*
X16000Y297500D03*
Y307500D03*
X24100Y310900D03*
X18000Y314500D03*
X13000Y318700D03*
X11976Y323524D03*
X28000Y327000D03*
X44500Y73500D03*
X45500Y104390D03*
Y126000D03*
X41500Y127500D03*
X41409Y132591D03*
X45500Y161000D03*
X41600Y148798D03*
X32600Y148700D03*
X37100Y148798D03*
X45500Y182500D03*
X45000Y213000D03*
X46000Y219500D03*
X42000Y236800D03*
X40500Y262000D03*
X33200Y262508D03*
X43000Y255500D03*
X37400Y282900D03*
X29000Y291500D03*
X43000Y314500D03*
X33000D03*
X44500Y309000D03*
X39500D03*
X34500D03*
X35500Y327000D03*
X59600Y60200D03*
X55500Y59000D03*
X50500Y60228D03*
X51772Y73600D03*
X47600Y68900D03*
X60100Y73000D03*
X63500Y84500D03*
X57000Y83500D03*
X51500D03*
X47000Y100000D03*
X61400Y104900D03*
X50500Y104800D03*
X59000Y96500D03*
X62500Y100500D03*
X57500Y101500D03*
X56500Y113000D03*
X62500Y117000D03*
X48390Y128312D03*
X53740Y126000D03*
X51772Y130500D03*
X55922Y140543D03*
X46500Y133000D03*
X47500Y140500D03*
X53900Y157000D03*
X60600Y161200D03*
X60500Y152000D03*
X51400Y161600D03*
X54130Y152500D03*
X60600Y157000D03*
X48957Y153619D03*
X54500Y171000D03*
X62000Y199500D03*
X51772Y187987D03*
X53500Y183500D03*
X58000Y213500D03*
X54000D03*
X48000Y200500D03*
X53000D03*
X63000Y206000D03*
Y210500D03*
Y215000D03*
X49600Y213455D03*
X57500Y226500D03*
Y218500D03*
X51452Y219900D03*
X51772Y245074D03*
X53200Y240187D03*
X54590Y266870D03*
X48232Y264530D03*
X48500Y252500D03*
X55200Y253500D03*
X48500Y271500D03*
X52500Y278000D03*
X52800Y272000D03*
X63600Y291500D03*
X57500Y289000D03*
X62000Y307000D03*
X61489Y332329D03*
X62000Y323500D03*
X55000Y336000D03*
Y355400D03*
X63500Y359600D03*
X62500Y365000D03*
Y369000D03*
Y373000D03*
Y378000D03*
Y382000D03*
X60300Y407100D03*
Y401100D03*
Y395100D03*
Y413100D03*
X75500Y62000D03*
X64400Y70000D03*
X67700Y65000D03*
X66400Y77400D03*
X71500Y77000D03*
X66000Y91100D03*
X76400Y87200D03*
X76321Y78300D03*
X78500Y82250D03*
X69500Y100000D03*
X73500Y112500D03*
X67000Y109000D03*
X79000Y100500D03*
X74000D03*
X64500Y129500D03*
X67500Y114500D03*
X68000Y119000D03*
X73500D03*
X69500Y130000D03*
X74000D03*
X75000Y141700D03*
X64445Y168945D03*
X69000Y187500D03*
Y193000D03*
X69023Y198524D03*
X74593Y202207D03*
X71400Y221700D03*
X67500Y222900D03*
X67400Y227100D03*
X71400Y232900D03*
X64700Y251700D03*
X71500Y247800D03*
X68000Y235500D03*
X67700Y240200D03*
X72400Y264600D03*
X80148Y253648D03*
X69500Y257800D03*
X64248Y258000D03*
X64500Y296750D03*
X78000Y291500D03*
X79500Y308500D03*
X66000Y318500D03*
X79000Y315500D03*
X71000Y330500D03*
X78000D03*
X72000Y335000D03*
X66000Y323500D03*
X78635Y324492D03*
X79500Y341790D03*
Y348500D03*
X72000Y346300D03*
X73000Y365000D03*
X69500D03*
X66000D03*
X66500Y382000D03*
X70500D03*
X80700Y399200D03*
Y404200D03*
X71300D03*
Y399200D03*
X76000D03*
Y404200D03*
X71300Y394200D03*
X76000D03*
X80700D03*
X64300Y407600D03*
Y401600D03*
Y395600D03*
X66000Y419000D03*
X80500Y420500D03*
X80700Y409200D03*
X76000D03*
X71300D03*
X64300Y413600D03*
X88900Y67000D03*
X86000Y63100D03*
X84200Y75000D03*
X83300Y87100D03*
X82100Y79300D03*
X96500Y98000D03*
X92250Y97750D03*
X94500Y105000D03*
X89000Y110500D03*
X93500D03*
X90500Y105000D03*
X84000Y100500D03*
X87000Y130000D03*
Y120000D03*
X93500Y125000D03*
X87000Y125500D03*
X93500Y130000D03*
X86600Y141300D03*
X90500Y144500D03*
X95500Y145500D03*
X96500Y140000D03*
X91500D03*
X88400Y154900D03*
X93900Y155200D03*
X95200Y151000D03*
X88500Y149000D03*
X94500Y163000D03*
X98500Y159000D03*
X91000Y181500D03*
X88250Y177250D03*
X83500Y178000D03*
X97500Y172000D03*
X98500Y165500D03*
X92000Y173000D03*
X83500D03*
X95500Y192000D03*
X83500Y193000D03*
Y188500D03*
X90500D03*
X94500Y197000D03*
X90500Y193500D03*
X85750Y202750D03*
X97500Y214000D03*
X84500Y218000D03*
X95700Y227500D03*
X98500Y218500D03*
X93032Y246477D03*
X96000Y241000D03*
X85700Y236500D03*
X96500Y235500D03*
X87200Y258300D03*
X98700Y268300D03*
X98500Y256661D03*
X83200Y260300D03*
X86900Y267200D03*
X95900Y278900D03*
X94500Y299000D03*
X88500Y303000D03*
X95000Y291500D03*
X87500Y295500D03*
X94500Y312500D03*
X95000Y321500D03*
X95593Y333347D03*
X82500Y339000D03*
X82951Y327940D03*
X97500Y341000D03*
X95100Y351900D03*
X83000Y352500D03*
Y344500D03*
X95000D03*
X82800Y364600D03*
X94500Y373000D03*
Y369000D03*
Y364500D03*
X90500D03*
X86500D03*
X91500Y359500D03*
X83500Y360000D03*
X82800Y384600D03*
X94500Y380500D03*
X94000Y384500D03*
X90500D03*
X86500D03*
X94500Y376500D03*
X97800Y391800D03*
X85400Y404200D03*
Y399200D03*
Y394200D03*
X96800Y408100D03*
X92800D03*
Y402100D03*
X96800D03*
Y396100D03*
X92800D03*
X94000Y420000D03*
X83000Y417000D03*
X85400Y409200D03*
X96800Y414100D03*
X92800D03*
X111330Y59810D03*
X103800Y76240D03*
X99000Y175500D03*
Y188500D03*
Y197500D03*
Y206500D03*
Y201500D03*
Y260025D03*
X98800Y272400D03*
X112500Y302000D03*
X107500D03*
X112500Y290000D03*
X102500D03*
Y302000D03*
X104500Y305500D03*
X105410Y318500D03*
X115253Y306247D03*
X99000Y350000D03*
X101500Y341000D03*
X104019Y347425D03*
X103000Y351500D03*
X113000Y344500D03*
X114000Y352000D03*
X99500Y370000D03*
X103000Y364000D03*
X106500D03*
X110000D03*
X115500Y389000D03*
X104500Y377000D03*
X102500Y420000D03*
X119500Y57694D03*
X125000Y76500D03*
X126000Y72000D03*
X127500Y290500D03*
X117500Y290000D03*
X125095Y306095D03*
X129000Y321500D03*
X126000Y318000D03*
X129500Y328000D03*
X123500Y347500D03*
X130000Y349664D03*
X119000Y352000D03*
X124500D03*
X120000Y364500D03*
X129000Y365000D03*
Y370500D03*
X120000Y368000D03*
Y371500D03*
X132000Y379000D03*
X118500D03*
X132000Y375500D03*
X127000Y397061D03*
X117000Y397000D03*
X121169Y396892D03*
X150860Y67400D03*
X145000Y296500D03*
X141000Y298500D03*
X140100Y306900D03*
X135000Y312000D03*
X149500Y311034D03*
X140700Y320000D03*
X142130Y325630D03*
X146000Y334000D03*
X141916Y333916D03*
X140900Y355400D03*
X142000Y350000D03*
X148000Y370000D03*
X137000Y364000D03*
X145000Y359000D03*
X140123Y391604D03*
X135500Y383000D03*
Y390500D03*
X141000Y379500D03*
X148500Y380000D03*
X145000Y378000D03*
X140100Y395600D03*
X135500Y396000D03*
X135200Y408400D03*
X140000Y401000D03*
X135100Y412600D03*
X143500Y418000D03*
X153270Y58400D03*
X151200Y75191D03*
X160500Y75500D03*
Y71500D03*
X165000Y294000D03*
X166150Y304050D03*
X156800Y301100D03*
X156600Y295000D03*
X153500Y310500D03*
X156000Y320500D03*
Y316500D03*
X166700Y338800D03*
X151000Y324200D03*
X156000Y325000D03*
Y329000D03*
X159100Y350400D03*
Y354600D03*
X166700Y343800D03*
X151500Y370000D03*
Y358000D03*
X159100Y382600D03*
X163600Y378600D03*
X157900Y387400D03*
X158500Y405200D03*
X160582Y410000D03*
X160550Y413400D03*
X151700Y411300D03*
X173170Y70840D03*
X168500Y294000D03*
X169850Y298950D03*
X182600Y289500D03*
X179500Y294600D03*
X176500Y290000D03*
X178000Y309500D03*
X173800Y324100D03*
X178600Y378600D03*
Y374600D03*
X175100Y382600D03*
Y387100D03*
X174600Y401600D03*
Y406100D03*
X175000Y394500D03*
X177000Y398000D03*
X174600Y410600D03*
X176000Y416000D03*
X188900Y54960D03*
X192160Y77840D03*
X190000Y301500D03*
Y305500D03*
X189500Y319000D03*
X201700Y327900D03*
X189000Y326000D03*
X195900Y332500D03*
X191500Y413000D03*
X213500Y54000D03*
X208160Y73990D03*
X215000Y69000D03*
X220000D03*
X204770Y67780D03*
X207800Y83010D03*
X219200Y338800D03*
X205000Y348800D03*
Y353800D03*
X215000Y343800D03*
X219000Y348800D03*
X218000Y381100D03*
X219000Y392500D03*
X215500D03*
X216500Y396000D03*
X220000D03*
X217600Y415100D03*
X229582Y48918D03*
X223500Y58250D03*
X231000Y68000D03*
Y71500D03*
X228500Y75500D03*
Y79000D03*
X226500Y334000D03*
X222500Y324500D03*
X238000Y345000D03*
X225500Y347500D03*
X230000D03*
X228500Y382500D03*
X221500Y378500D03*
X226000D03*
X225000Y396000D03*
X221500Y415000D03*
X225600Y415100D03*
X229500Y415000D03*
X254000Y213500D03*
X241441Y215000D03*
X241900Y238800D03*
X249000Y290300D03*
X255400Y290100D03*
X247000Y344500D03*
X251000D03*
X255000D03*
X272330Y54871D03*
X259500Y54700D03*
Y70100D03*
X271000Y184500D03*
X269000Y215000D03*
X259000Y223000D03*
Y344500D03*
X282200Y179121D03*
X275260Y223000D03*
X280500Y224300D03*
X288000Y293000D03*
X288500Y317000D03*
X303500Y69400D03*
X296400Y70200D03*
X307500Y160500D03*
X303500Y164000D03*
X306500Y169500D03*
X298284Y175184D03*
X298500Y184500D03*
X300995Y187611D03*
X297772Y188694D03*
X292000Y294720D03*
X299500Y295500D03*
X301000Y312000D03*
X297000Y310500D03*
X301000Y317000D03*
X293700Y317300D03*
X309000Y164500D03*
X312500Y160500D03*
X320500Y170000D03*
X311000Y193500D03*
X312000Y217000D03*
X308967Y204000D03*
X324000Y227500D03*
X312000Y234400D03*
X324000Y220750D03*
X312500Y225400D03*
X311900Y229900D03*
Y243400D03*
X323500Y263000D03*
X311600Y252400D03*
X312000Y269000D03*
Y256500D03*
Y264500D03*
X314500Y276500D03*
X324000Y301000D03*
X312000Y295500D03*
X317500D03*
X321000D03*
X324500D03*
X310500Y321000D03*
X312500Y307500D03*
X310600Y326000D03*
X321899Y343000D03*
X325000Y363000D03*
X320000Y398500D03*
X323000Y401500D03*
X321300Y423600D03*
X324800Y415200D03*
X321300Y416700D03*
X324800Y410700D03*
X336000Y61060D03*
X340500Y63500D03*
Y87000D03*
X338000Y102500D03*
X338500Y213500D03*
X332550Y213550D03*
X341500Y233500D03*
X327923Y221577D03*
X335153Y217875D03*
X340953Y237000D03*
X330500Y265000D03*
X337500D03*
X328500Y258900D03*
X333500D03*
X338500Y259000D03*
X339500Y282000D03*
X332000Y301500D03*
X330500Y291500D03*
X341000Y304000D03*
X332500Y306500D03*
X328000D03*
X338000Y315000D03*
X341400Y323500D03*
X337000Y344000D03*
X326000Y374000D03*
X340500Y361300D03*
X332500D03*
X336500D03*
X325300Y387200D03*
X331500Y376000D03*
X338500D03*
X342000D03*
X339200Y380300D03*
X339300Y384000D03*
Y387700D03*
X340500Y391600D03*
X325300Y396200D03*
Y391700D03*
X336300Y423200D03*
Y415200D03*
Y419200D03*
X340800Y415200D03*
X349500Y61000D03*
X354500Y60920D03*
X345500Y87000D03*
X354000Y82500D03*
X344000Y103000D03*
X354000Y128000D03*
X351000Y130500D03*
X353500D03*
X356000D03*
X347500Y141500D03*
X350000D03*
X352500D03*
X355000D03*
X357000Y154200D03*
X353482Y154157D03*
X350085Y154300D03*
X350100Y169400D03*
X352600D03*
X357600D03*
X355100D03*
X347300Y179000D03*
X346500Y174000D03*
X344500Y181500D03*
X351200Y196600D03*
X349128Y186628D03*
X344000Y212000D03*
X350500Y229500D03*
X355500Y218000D03*
Y220500D03*
Y225500D03*
Y223000D03*
X351000Y233243D03*
X355000Y242500D03*
X354975Y247900D03*
X351000Y237000D03*
X358000Y261500D03*
X344500Y265000D03*
X343500Y258900D03*
X352500Y260000D03*
X348500D03*
X357680Y271780D03*
X357000Y295500D03*
X356000Y302300D03*
X349000Y303000D03*
Y295500D03*
X355500Y306500D03*
X346000D03*
X351000Y308000D03*
X355000Y337000D03*
X348418Y361300D03*
X344500D03*
X347700Y381600D03*
X347000Y391200D03*
X360000Y402400D03*
X359800Y397700D03*
X347600Y398800D03*
X348279Y405678D03*
X353000Y416500D03*
X350000Y419500D03*
X349500Y415000D03*
X346000Y416000D03*
X343700Y409900D03*
X348863Y410500D03*
X370500Y84000D03*
X376838Y100230D03*
X369310Y109500D03*
X369172Y102828D03*
X367000Y126000D03*
X374300Y129000D03*
X371800D03*
X362000Y123500D03*
Y128000D03*
X374300Y132000D03*
X371800D03*
X376500Y141000D03*
X374000D03*
X360500Y154500D03*
X374900Y154228D03*
X371400Y154300D03*
X367900Y154228D03*
X374600Y178200D03*
X363600Y176600D03*
X367600Y169300D03*
X364700Y169400D03*
X367400Y174400D03*
X373649Y185735D03*
X375000Y210000D03*
X369560Y213000D03*
X372060D03*
X367000D03*
X364500D03*
X367000Y232000D03*
X372500D03*
X377500Y218500D03*
Y221000D03*
Y226500D03*
Y223500D03*
X360500Y243000D03*
X367000Y241243D03*
X373500Y247000D03*
X365500Y246500D03*
X369500Y267500D03*
X375800Y255200D03*
X376500Y269000D03*
X365000Y268000D03*
X365500Y279500D03*
X362300Y286100D03*
X365800D03*
X370000Y276000D03*
X374500D03*
X374800Y291100D03*
X370300D03*
X361500Y296100D03*
X365800Y291100D03*
X362100Y291000D03*
X361400Y301500D03*
Y305800D03*
Y309900D03*
X365500Y305900D03*
X375500Y309200D03*
X371000Y326000D03*
X370000Y337000D03*
Y332500D03*
X366000Y350850D03*
X360700Y406200D03*
X369000Y413500D03*
X374500Y418500D03*
X363100Y418300D03*
X360311Y409880D03*
X363100Y422800D03*
X364500Y413500D03*
X382286Y86214D03*
X384000Y102980D03*
Y109500D03*
X379000Y141000D03*
X382000Y142000D03*
X378400Y154300D03*
X379800Y177100D03*
X380000Y210000D03*
Y204500D03*
X384091Y200091D03*
X394000Y223500D03*
X383000Y232500D03*
X390000D03*
X379500Y237500D03*
X391900Y246800D03*
X386000D03*
X380100D03*
X386000Y259250D03*
X378000Y273500D03*
X389400Y281100D03*
X378000Y281000D03*
X382200D03*
X394800Y281300D03*
X388650Y292650D03*
X378000Y293200D03*
X383000D03*
X393300Y312500D03*
X383000Y323500D03*
X390000Y338500D03*
X392500Y329100D03*
Y323900D03*
X383000Y341500D03*
X384300Y368700D03*
X383900Y372600D03*
X381000Y365000D03*
X386500D03*
X389500Y370000D03*
X395000D03*
Y360000D03*
Y382000D03*
X383900Y384600D03*
X379500Y381000D03*
Y375800D03*
Y417500D03*
X407000Y120000D03*
X399500D03*
X399000Y221407D03*
Y225000D03*
X407500D03*
X397800Y246800D03*
X403700D03*
X409300D03*
X397800Y259300D03*
X403700D03*
X400000Y265500D03*
X399800Y278400D03*
X409100Y281300D03*
X409300Y286300D03*
X402000Y303000D03*
X409200Y291700D03*
X396981Y304482D03*
X407500Y300500D03*
X402500Y308000D03*
X397500Y312900D03*
X407500Y305000D03*
X397300Y320700D03*
X408500Y316500D03*
Y321998D03*
Y311000D03*
X408000Y327000D03*
X398000Y336500D03*
X410000Y338000D03*
X398000Y352000D03*
X406610Y353410D03*
X411840Y353620D03*
X410000Y358543D03*
X409000Y371339D03*
X409650Y403950D03*
X412350Y401250D03*
Y397150D03*
X409650Y394450D03*
X422000Y77500D03*
X423000Y72950D03*
X417500Y75000D03*
X420500Y82000D03*
X413500Y88500D03*
X425000Y87700D03*
X423000Y100500D03*
X427800Y100300D03*
X429400Y107500D03*
X429000Y123500D03*
X422000D03*
X418500Y117000D03*
X415000Y123500D03*
X425400Y229600D03*
X420500Y229500D03*
X414900Y229800D03*
X423000Y235400D03*
X416100D03*
X420900Y246800D03*
X415000D03*
X420900Y259000D03*
X429000Y274000D03*
X424900Y284300D03*
X423900Y278500D03*
X424900Y292900D03*
X413000Y300500D03*
X429442Y310075D03*
X417500Y337000D03*
Y352000D03*
X422500Y354500D03*
X428500Y346000D03*
X413500Y373500D03*
X419000D03*
X420500Y366000D03*
X425000Y381000D03*
X420500D03*
X419150Y394450D03*
X416450Y401250D03*
Y397150D03*
X419150Y403950D03*
X423500Y415500D03*
X434500Y77000D03*
X441400Y78100D03*
X433500Y100500D03*
X444200D03*
X431000Y116500D03*
X444000Y226000D03*
X436500Y233000D03*
X443500Y231500D03*
X444000Y250000D03*
X436500Y237500D03*
X439500Y250000D03*
X435000Y250500D03*
X443500Y236500D03*
X439500Y266500D03*
X444000Y263000D03*
X440000Y278500D03*
X434600Y278300D03*
X435500Y274500D03*
X445600Y278300D03*
X438150Y283800D03*
X447000Y283000D03*
X433050Y291400D03*
X446000Y294000D03*
X439000Y302000D03*
X434500D03*
X433000Y314320D03*
X435143Y306643D03*
X447000Y321998D03*
X440000Y332500D03*
X434000Y328000D03*
X447200Y347500D03*
X433000Y353500D03*
X433500Y366500D03*
X433382Y360466D03*
X438500Y364500D03*
X430000Y386500D03*
X446000Y374500D03*
X438400Y382400D03*
X430000Y381000D03*
X431000Y406500D03*
Y416000D03*
Y411500D03*
X460000Y76000D03*
X448430Y89540D03*
X463500Y86500D03*
Y92000D03*
X458500Y86500D03*
X450000Y108200D03*
X454600Y108500D03*
X448500Y100500D03*
X462500Y117000D03*
X461996Y162690D03*
X462000Y224500D03*
X461000Y234500D03*
X457500Y227500D03*
Y223500D03*
X449000Y232500D03*
Y227500D03*
X461000Y230000D03*
X462000Y250000D03*
X448500Y237500D03*
X457500Y250000D03*
X448500D03*
X457500Y237400D03*
X453000Y250000D03*
X457000Y258500D03*
X459500Y262000D03*
X461500Y268409D03*
X460000Y284500D03*
Y289500D03*
X460800Y294200D03*
X461000Y302500D03*
X464500Y298500D03*
X456500Y305500D03*
X454000Y312500D03*
X448500Y311500D03*
X461500Y311000D03*
X451000Y306500D03*
X459500Y322000D03*
X459000Y326000D03*
X450900Y330900D03*
X450500Y368500D03*
X453500Y381500D03*
X454000Y393500D03*
Y397000D03*
X450000Y407000D03*
Y416500D03*
Y411500D03*
X481000Y70700D03*
X479500Y92500D03*
X478000Y78000D03*
X482000Y83500D03*
X465500Y78500D03*
X475500Y82500D03*
X470500D03*
X466500Y110400D03*
X471200Y115700D03*
X481600Y125800D03*
X476800Y120700D03*
X479867Y138867D03*
X473807Y154816D03*
X465933Y162690D03*
X473807Y150879D03*
X481500Y182016D03*
X481000Y172500D03*
X479246Y178464D03*
X477500Y170500D03*
X478000Y198000D03*
X481500Y193000D03*
X482000Y212500D03*
X480288Y203788D03*
X471000Y239000D03*
X477000D03*
X471000Y259200D03*
X477500Y259000D03*
X468500Y264500D03*
Y270000D03*
X467000Y355500D03*
X471000Y347000D03*
X478500Y346000D03*
X481000Y341000D03*
X471400Y363300D03*
X470500Y391000D03*
X493700Y79161D03*
X496000Y85000D03*
X482800Y110300D03*
X489400Y126300D03*
X493300Y121500D03*
X483000Y133000D03*
X485000Y154000D03*
X497500Y148500D03*
X491000Y154000D03*
X491500Y148500D03*
X497000Y154000D03*
X496000Y163000D03*
Y167500D03*
Y179258D03*
X484000Y166000D03*
X497000Y175000D03*
X485033Y174934D03*
X498060Y185500D03*
X496500Y192500D03*
X483871Y198241D03*
X496500Y197500D03*
X484000Y185500D03*
X497500Y214000D03*
X496000Y205500D03*
X485000Y202739D03*
X490500Y216750D03*
X492500Y226000D03*
X497500D03*
X497100Y244700D03*
X497200Y240600D03*
X492300Y240800D03*
X483100Y272800D03*
X492500Y272200D03*
X491800Y277700D03*
X497000Y341000D03*
X495000Y346000D03*
X483501D03*
X488500D03*
X504000Y64500D03*
X508500D03*
X513200Y66000D03*
X503005Y99494D03*
X508000Y105500D03*
Y110500D03*
Y115500D03*
X503860Y124150D03*
X503900Y128690D03*
X503950Y143000D03*
X514500Y144000D03*
X503950Y133500D03*
X503000Y155000D03*
X503500Y149000D03*
X514500Y151000D03*
Y148000D03*
Y154000D03*
Y157000D03*
X501500Y192500D03*
X507000D03*
Y188500D03*
X515500Y201000D03*
X513000Y210500D03*
X511500Y206500D03*
X513500Y215500D03*
X509000D03*
X512100Y249500D03*
X507100Y240700D03*
X512100D03*
Y244700D03*
X502200Y240700D03*
X512100Y262500D03*
X512300Y254400D03*
X512200Y258700D03*
X512650Y268150D03*
X501000Y263500D03*
X511900Y276200D03*
X508950Y273250D03*
X506100Y280600D03*
X509000Y340500D03*
X504500D03*
X514000Y374000D03*
X505000Y379500D03*
X504500Y376000D03*
X507500Y394500D03*
X503500D03*
X521500Y60000D03*
X529500Y60500D03*
X526500Y67500D03*
X519500Y75500D03*
X533000Y87000D03*
Y82000D03*
X519500Y81500D03*
X520000Y87000D03*
X524900Y99000D03*
X522500Y114500D03*
X533500Y124500D03*
X534000Y160500D03*
X517000Y212500D03*
X533200Y220000D03*
X529800Y223000D03*
X528710Y227500D03*
X534000Y231500D03*
X525400Y247000D03*
X522000D03*
X534500Y253600D03*
X530350Y257480D03*
X524300Y261700D03*
X523900Y257100D03*
X532500Y272500D03*
X523600Y281100D03*
X531000Y285500D03*
X526000Y295500D03*
X532900Y318900D03*
X527600D03*
X519000Y307500D03*
X532400Y340600D03*
Y345600D03*
X527100Y340600D03*
Y345600D03*
X517500Y374000D03*
X532200Y377700D03*
X523700Y384100D03*
X528200Y377700D03*
X523700D03*
X518000Y382500D03*
X527500Y389100D03*
X530000Y406500D03*
X532100Y399000D03*
X527500Y397100D03*
Y393100D03*
X525176Y411925D03*
X522100Y416500D03*
X551500Y59597D03*
X543957Y60543D03*
X537000Y69000D03*
X549000Y63500D03*
X544500Y79500D03*
X549000Y78223D03*
X544300Y87100D03*
X549400Y81600D03*
X536500Y84500D03*
Y79000D03*
X541000Y96000D03*
X534500Y130000D03*
Y136500D03*
X534600Y148300D03*
Y152000D03*
X544000Y159000D03*
X543520Y174970D03*
X542270Y169900D03*
X539770Y174900D03*
Y169900D03*
Y172400D03*
X542270D03*
X542500Y189500D03*
X538500D03*
X540900Y201500D03*
X543500Y205000D03*
X536900Y201500D03*
X545800Y216500D03*
X541000Y216400D03*
X540600Y234600D03*
X537500Y232000D03*
X548300Y222600D03*
X546500Y240500D03*
X549000Y267500D03*
X551700Y256300D03*
X541000Y281500D03*
X539500Y292000D03*
X541346Y303507D03*
X542000Y296450D03*
X537500Y304000D03*
X538600Y318900D03*
X538100Y340600D03*
Y345600D03*
X539000Y370000D03*
X539300Y365100D03*
X539000Y360000D03*
X543000Y370000D03*
X543300Y365100D03*
X543000Y360000D03*
X548557Y387700D03*
X540600Y386300D03*
X538500Y407875D03*
X543000Y396700D03*
X548829Y416329D03*
X548500Y411000D03*
X538558Y413779D03*
X550369Y427558D03*
X538558D03*
X562500Y74600D03*
X560650Y70450D03*
X559941Y62120D03*
X563341Y62102D03*
X564350Y65350D03*
X559000Y85000D03*
X560200Y81500D03*
X559000Y88800D03*
X565933Y102000D03*
X562533Y102001D03*
X553000Y108500D03*
X558000Y161500D03*
X568700Y204300D03*
X564700Y204400D03*
X554600Y202400D03*
X558900Y202500D03*
X566950Y220000D03*
X553800Y240200D03*
X560000Y240000D03*
X565400Y244700D03*
X562000Y254870D03*
X554400Y267500D03*
X561700Y320300D03*
X556700D03*
X562500Y336100D03*
Y326100D03*
X562000Y331600D03*
X566000Y347000D03*
X563700Y352400D03*
X560000Y342100D03*
X568100Y366400D03*
Y361700D03*
X568326Y371200D03*
X563800Y390700D03*
X564500Y379000D03*
X560200Y386500D03*
X567500D03*
X568600Y376000D03*
Y380700D03*
X560000Y401000D03*
X564400Y396700D03*
X567500Y403000D03*
X555000Y402000D03*
X567126Y417500D03*
X555315D03*
X562180Y413779D03*
Y427558D03*
X580500Y65800D03*
X580643Y60900D03*
X585900Y79600D03*
X580000Y104800D03*
X576500Y98000D03*
X586500Y107000D03*
Y112500D03*
X576459Y161971D03*
X575072Y165500D03*
X580500Y194500D03*
X583000Y192000D03*
X573200Y204300D03*
X586500Y230000D03*
X571000Y217900D03*
X576500Y219700D03*
X569943Y223300D03*
X585000Y226500D03*
X576000Y246500D03*
X578900Y236600D03*
X581500Y267000D03*
X581400Y292250D03*
X583000Y297000D03*
X580300Y356700D03*
X576300Y371200D03*
X580200Y361700D03*
X580100Y366700D03*
X580300Y380700D03*
Y375700D03*
Y385700D03*
Y390700D03*
X571800Y396500D03*
X576900Y403100D03*
X578937Y417500D03*
X572500Y413500D03*
X584000Y421900D03*
X573991Y427558D03*
X599000Y92500D03*
X588000Y96500D03*
X600850Y112350D03*
X592000Y127063D03*
X599500Y116500D03*
X592000Y136000D03*
Y141000D03*
Y146000D03*
Y163000D03*
Y151500D03*
Y157063D03*
Y173000D03*
Y178000D03*
Y168000D03*
X587000Y184000D03*
X597703Y187000D03*
X587500Y190000D03*
X594003Y187000D03*
X602500Y183000D03*
X601550Y208450D03*
X596450Y210350D03*
X601953Y218853D03*
X595500Y239000D03*
X590650Y245680D03*
X604000Y254500D03*
X591000Y271500D03*
Y278500D03*
Y291500D03*
X602500Y404000D03*
X591000D03*
X604000Y398000D03*
X597500Y421900D03*
X602559Y417500D03*
X590748Y418725D03*
X597613Y413779D03*
Y427558D03*
X616500Y194874D03*
X606902Y186000D03*
X610500Y190500D03*
X614100Y224100D03*
X610500Y227000D03*
X614100Y236400D03*
X618650Y249300D03*
X609500Y254500D03*
X614500Y398000D03*
Y403500D03*
X614370Y417500D03*
X609424Y413779D03*
Y427558D03*
X633500Y108000D03*
Y102000D03*
Y96500D03*
X637900Y116900D03*
X622000Y127063D03*
Y136000D03*
Y141500D03*
Y146500D03*
Y162000D03*
Y151600D03*
Y157000D03*
Y181500D03*
Y175500D03*
X622035Y167063D03*
X633500Y196874D03*
X628500Y189500D03*
X636000Y216142D03*
X627500Y205374D03*
X626989Y237989D03*
X633000Y286500D03*
X633500Y301500D03*
X647000Y108000D03*
Y113500D03*
X873950Y348500D03*
G54D13*
X29528Y36811D03*
Y373031D03*
X640039Y65354D03*
Y417835D03*
X873950Y73500D03*
G54D22*
X634055Y334449D03*
Y367519D03*
X873950Y98500D03*
G54D14*
X19878Y36811D03*
X22704Y29987D03*
Y43635D03*
X19878Y373031D03*
X22704Y366207D03*
Y379855D03*
X29528Y27161D03*
X36352Y29987D03*
X39178Y36811D03*
X36352Y43635D03*
X29528Y46461D03*
Y363381D03*
X36352Y366207D03*
X39178Y373031D03*
X36352Y379855D03*
X29528Y382681D03*
X633215Y58530D03*
Y72178D03*
X630389Y65354D03*
X633215Y424659D03*
X630389Y417835D03*
X633215Y411011D03*
X640039Y55704D03*
X646863Y58530D03*
X649689Y65354D03*
X646863Y72178D03*
X640039Y75004D03*
Y408185D03*
X646863Y411011D03*
X649689Y417835D03*
X646863Y424659D03*
X640039Y427485D03*
X873950Y323500D03*
G54D23*
X651582Y197244D03*
Y224804D03*
X873950Y48500D03*
G54D15*
X16039Y71260D03*
Y128346D03*
Y185433D03*
Y242520D03*
X873950Y248500D03*
G54D24*
X640952Y201181D03*
Y220867D03*
X873950Y273500D03*
G54D25*
G01X1049850Y-1584500D02*
X1024850D01*
Y-1534500D01*
X1049850D01*
G01X1039850Y-1558666D02*
X1024850D01*
G54D16*
X24807Y335985D03*
Y347245D03*
X43705Y331655D03*
Y351576D03*
X873950Y23500D03*
G54D26*
G01X-2466000Y-1412000D02*
X-2433100D01*
G01X-2466000Y-1078500D02*
X-2433100D01*
G01X-2466000Y-745100D02*
X-2433100D01*
G01X-2466000Y-411500D02*
X-2433100D01*
G01X-2476400Y-82400D02*
X-2433100D01*
G01X-2466000Y251200D02*
X-2433100D01*
G01X-2466000Y584600D02*
X-2433100D01*
G01X-2466000Y918100D02*
X-2433100D01*
G01X-2466000Y1251500D02*
X-2433100D01*
G01X-2457800Y-1593700D02*
X-2448600Y-1568000D01*
G01X-2455900Y-1588200D02*
X-2441400D01*
G01X-2448600Y-1568000D02*
X-2439500Y-1593700D01*
G01X-2457800Y-1232300D02*
Y-1258000D01*
G01D02*
X-2448600D01*
G01D02*
X-2445100Y-1257600D01*
G01Y-1244000D02*
X-2448600Y-1243400D01*
G01D02*
X-2457800D01*
G01X-2448600D02*
X-2445400Y-1242800D01*
G01Y-1232900D02*
X-2448600Y-1232300D01*
G01D02*
X-2457800D01*
G01Y-904400D02*
Y-919200D01*
G01D02*
X-2457000Y-921200D01*
G01D02*
X-2455100Y-923000D01*
G01D02*
X-2452200Y-924200D01*
G01D02*
X-2448600Y-924600D01*
G01D02*
X-2439500D01*
G01X-2452200Y-899400D02*
X-2455100Y-900600D01*
G01D02*
X-2457000Y-902300D01*
G01D02*
X-2457800Y-904400D01*
G01X-2439500Y-898900D02*
X-2448600D01*
G01D02*
X-2452200Y-899400D01*
G01X-2457800Y-591200D02*
X-2448600D01*
G01D02*
X-2445100Y-590200D01*
G01X-2457800Y-565400D02*
Y-591200D01*
G01X-2445100Y-566400D02*
X-2448600Y-565400D01*
G01D02*
X-2457800D01*
G01Y-232000D02*
Y-257700D01*
G01D02*
X-2439500D01*
G01X-2457800Y-244800D02*
X-2444900D01*
G01X-2439500Y-232000D02*
X-2457800D01*
G01Y71500D02*
Y97300D01*
G01Y84300D02*
X-2444900D01*
G01X-2457800Y97300D02*
X-2439500D01*
G01X-2455100Y408000D02*
X-2452900Y405800D01*
G01D02*
X-2450400Y405000D01*
G01D02*
X-2439500D01*
G01X-2455100Y427800D02*
X-2456700Y424200D01*
G01D02*
X-2457600Y420100D01*
G01D02*
Y415700D01*
G01D02*
X-2456700Y411400D01*
G01D02*
X-2455100Y408000D01*
G01X-2439500Y430700D02*
X-2450400D01*
G01D02*
X-2452900Y430000D01*
G01D02*
X-2455100Y427800D01*
G01X-2457800Y764100D02*
Y738400D01*
G01Y751300D02*
X-2439500D01*
G01X-2457800Y1079200D02*
X-2457000Y1076400D01*
G01D02*
X-2455100Y1074100D01*
G01D02*
X-2452200Y1072400D01*
G01D02*
X-2448600Y1072000D01*
G01D02*
X-2445100Y1072400D01*
G01X-2457800Y1433200D02*
Y1407500D01*
G01Y1418500D02*
X-2439500Y1433200D01*
G01X-2451400Y1423600D02*
X-2439500Y1407500D01*
G01X-2445100Y-1257600D02*
X-2442100Y-1256000D01*
G01D02*
X-2440100Y-1253600D01*
G01D02*
X-2439500Y-1250800D01*
G01D02*
X-2440100Y-1248000D01*
G01D02*
X-2442100Y-1245500D01*
G01D02*
X-2445100Y-1244000D01*
G01X-2445400Y-1242800D02*
X-2442900Y-1241300D01*
G01D02*
X-2441400Y-1239100D01*
G01D02*
Y-1236600D01*
G01D02*
X-2442900Y-1234400D01*
G01D02*
X-2445400Y-1232900D01*
G01X-2445100Y-590200D02*
X-2442100Y-587400D01*
G01D02*
X-2440100Y-583300D01*
G01D02*
X-2439500Y-578400D01*
G01D02*
X-2440100Y-573400D01*
G01D02*
X-2442100Y-569200D01*
G01D02*
X-2445100Y-566400D01*
G01X-2439500Y405000D02*
Y417900D01*
G01D02*
X-2446700D01*
G01X-2439500Y764100D02*
Y738400D01*
G01X-2445100Y1072400D02*
X-2442100Y1074100D01*
G01D02*
X-2440100Y1076400D01*
G01D02*
X-2439500Y1079200D01*
G01D02*
Y1097700D01*
G01X-2426900Y-1749600D02*
X2056300D01*
G01X-2426900Y1589100D02*
Y-1749600D01*
G01Y-1646700D02*
X-1914400D01*
G01X-2426900Y1589100D02*
X2056300D01*
G01X-2412400Y-1667400D02*
X-2405000D01*
G01D02*
X-2402700Y-1666800D01*
G01X-2412400Y-1657700D02*
Y-1674800D01*
G01X-2402700Y-1666800D02*
X-2400900Y-1665100D01*
G01D02*
X-2400200Y-1662600D01*
G01D02*
X-2400900Y-1660200D01*
G01D02*
X-2402700Y-1658400D01*
G01D02*
X-2405000Y-1657700D01*
G01D02*
X-2412400D01*
G01X-2389100D02*
X-2383000Y-1674800D01*
G01X-2395300D02*
X-2389100Y-1657700D01*
G01X-2394000Y-1671100D02*
X-2384400D01*
G01X-2378200Y-1667400D02*
X-2370800D01*
G01D02*
X-2368300Y-1666800D01*
G01X-2378200Y-1657700D02*
Y-1674800D01*
G01X-2365900D02*
X-2370800Y-1667400D01*
G01X-2361000Y-1657700D02*
X-2348800D01*
G01X-2368300Y-1666800D02*
X-2366500Y-1665100D01*
G01D02*
X-2365900Y-1662600D01*
G01D02*
X-2366500Y-1660200D01*
G01D02*
X-2368300Y-1658400D01*
G01D02*
X-2370800Y-1657700D01*
G01D02*
X-2378200D01*
G01X-2354800D02*
Y-1674800D01*
G01X-2325400D02*
Y-1657700D01*
G01D02*
X-2315700Y-1674800D01*
G01D02*
Y-1657700D01*
G01X-2309500Y-1662600D02*
Y-1671100D01*
G01Y-1669900D02*
X-2308600Y-1672400D01*
G01D02*
X-2306400Y-1674200D01*
G01Y-1658400D02*
X-2308600Y-1660200D01*
G01D02*
X-2309500Y-1662600D01*
G01X-2303400Y-1674800D02*
X-2300300Y-1674200D01*
G01D02*
X-2298100Y-1672400D01*
G01D02*
X-2297200Y-1669900D01*
G01D02*
Y-1661400D01*
G01X-2306400Y-1674200D02*
X-2303400Y-1674800D01*
G01X-2297200Y-1662600D02*
X-2298100Y-1660200D01*
G01D02*
X-2300300Y-1658400D01*
G01D02*
X-2303400Y-1657700D01*
G01D02*
X-2306400Y-1658400D01*
G01X-2284400Y-1673000D02*
X-2285100Y-1671600D01*
G01D02*
X-2286600Y-1671300D01*
G01D02*
X-2287900Y-1672200D01*
G01D02*
Y-1673800D01*
G01D02*
X-2286600Y-1674800D01*
G01D02*
X-2285100Y-1674500D01*
G01D02*
X-2284400Y-1673000D01*
G01X-2202600Y-1760400D02*
X-2206300Y-1762300D01*
G01X-2202600Y1625700D02*
X-2206300Y1623800D01*
G01X-2202600Y-1786000D02*
Y-1760400D01*
G01Y1600000D02*
Y1625700D01*
G01X-2176900Y-1786000D02*
Y-1760400D01*
G01D02*
X-2180600Y-1762300D01*
G01X-2176900Y1600000D02*
Y1625700D01*
G01D02*
X-2180600Y1623800D01*
G01X-2021500Y-1646700D02*
Y-1749600D01*
G01X-1996100Y-1672900D02*
X-2000500Y-1666400D01*
G01X-2007000Y-1657700D02*
Y-1672900D01*
G01X-1998300Y-1658300D02*
X-2000500Y-1657700D01*
G01X-1996700Y-1659900D02*
X-1998300Y-1658300D01*
G01X-1996100Y-1662100D02*
X-1996700Y-1659900D01*
G01Y-1664200D02*
X-1996100Y-1662100D01*
G01X-1998300Y-1665800D02*
X-1996700Y-1664200D01*
G01X-2000500Y-1666400D02*
X-1998300Y-1665800D01*
G01X-2000500Y-1657700D02*
X-2007000D01*
G01Y-1666400D02*
X-2000500D01*
G01X-1978200Y-1755800D02*
Y-1788700D01*
G01X-1991000Y-1657700D02*
Y-1672900D01*
G01D02*
X-1980100D01*
G01X-1991000Y-1665400D02*
X-1983300D01*
G01X-1980100Y-1657700D02*
X-1991000D01*
G01X-1978200Y1628200D02*
Y1595300D01*
G01X-1969600Y-1672900D02*
X-1964200Y-1657700D01*
G01X-1975100D02*
X-1969600Y-1672900D01*
G01X-1914400Y-1646700D02*
Y-1749600D01*
G01X-1751800Y-1786000D02*
Y-1760400D01*
G01D02*
X-1755500Y-1762300D01*
G01X-1751800Y1600000D02*
Y1625700D01*
G01D02*
X-1755500Y1623800D01*
G01X-1735000Y-1770500D02*
Y-1775900D01*
G01D02*
X-1733500Y-1780700D01*
G01D02*
X-1730700Y-1784400D01*
G01Y-1762100D02*
X-1733500Y-1765700D01*
G01D02*
X-1735000Y-1770500D01*
G01Y1615500D02*
Y1610200D01*
G01D02*
X-1733500Y1605200D01*
G01D02*
X-1730700Y1601600D01*
G01Y1623900D02*
X-1733500Y1620400D01*
G01D02*
X-1735000Y1615500D01*
G01X-1716800Y-1773200D02*
X-1717700Y-1768000D01*
G01X-1730700Y-1784400D02*
X-1727000Y-1786000D01*
G01D02*
X-1723200Y-1785500D01*
G01D02*
X-1719900Y-1782800D01*
G01D02*
X-1717700Y-1778500D01*
G01D02*
X-1716800Y-1773200D01*
G01X-1717700Y-1768000D02*
X-1719900Y-1763600D01*
G01D02*
X-1723200Y-1760900D01*
G01D02*
X-1727000Y-1760500D01*
G01D02*
X-1730700Y-1762100D01*
G01Y1601600D02*
X-1727000Y1600000D01*
G01D02*
X-1723200Y1600600D01*
G01D02*
X-1719900Y1603300D01*
G01D02*
X-1717700Y1607500D01*
G01D02*
X-1716800Y1612900D01*
G01D02*
X-1717700Y1618000D01*
G01D02*
X-1719900Y1622300D01*
G01D02*
X-1723200Y1625100D01*
G01D02*
X-1727000Y1625600D01*
G01D02*
X-1730700Y1623900D01*
G01X-1525300Y-1755800D02*
Y-1788700D01*
G01Y1628200D02*
Y1595300D01*
G01X-1302700Y-1786000D02*
X-1299000D01*
G01D02*
X-1296600Y-1785500D01*
G01X-1307400Y-1770400D02*
X-1305500Y-1771900D01*
G01D02*
X-1302500Y-1772900D01*
G01D02*
X-1299000Y-1773200D01*
G01D02*
X-1295400Y-1772900D01*
G01Y-1760800D02*
X-1299000Y-1760400D01*
G01D02*
X-1302500Y-1760800D01*
G01D02*
X-1305500Y-1762300D01*
G01D02*
X-1307400Y-1764300D01*
G01D02*
X-1308100Y-1766900D01*
G01D02*
Y-1768600D01*
G01D02*
X-1307400Y-1770400D01*
G01X-1302700Y1600000D02*
X-1299000D01*
G01Y1599900D02*
X-1296600Y1600600D01*
G01X-1295400Y1625100D02*
X-1299000Y1625700D01*
G01D02*
X-1302500Y1625100D01*
G01D02*
X-1305500Y1623800D01*
G01D02*
X-1307400Y1621700D01*
G01D02*
X-1308100Y1619200D01*
G01D02*
Y1617400D01*
G01D02*
X-1307400Y1615700D01*
G01D02*
X-1305500Y1614200D01*
G01D02*
X-1302500Y1613100D01*
G01D02*
X-1299000Y1612900D01*
G01D02*
X-1295400Y1613100D01*
G01X-1296600Y-1785500D02*
X-1294400Y-1783700D01*
G01D02*
X-1292500Y-1781000D01*
G01D02*
X-1291000Y-1777300D01*
G01D02*
X-1290100Y-1773200D01*
G01D02*
X-1289800Y-1768600D01*
G01X-1295400Y-1772900D02*
X-1292500Y-1771900D01*
G01D02*
X-1290400Y-1770400D01*
G01X-1289800Y-1768600D02*
Y-1766900D01*
G01D02*
X-1290400Y-1764300D01*
G01D02*
X-1292500Y-1762300D01*
G01D02*
X-1295400Y-1760800D01*
G01X-1290400Y-1770400D02*
X-1289800Y-1768600D01*
G01X-1296600Y1600600D02*
X-1294400Y1602200D01*
G01D02*
X-1292500Y1605000D01*
G01D02*
X-1291000Y1608700D01*
G01D02*
X-1290100Y1612900D01*
G01D02*
X-1289800Y1617400D01*
G01D02*
Y1619200D01*
G01D02*
X-1290400Y1621700D01*
G01D02*
X-1292500Y1623800D01*
G01D02*
X-1295400Y1625100D01*
G01Y1613100D02*
X-1292500Y1614200D01*
G01D02*
X-1290400Y1615700D01*
G01D02*
X-1289800Y1617400D01*
G01X-1072500Y-1755800D02*
Y-1788700D01*
G01Y1628200D02*
Y1595300D01*
G01X-848900Y-1771400D02*
X-851100Y-1772600D01*
G01D02*
X-853900Y-1774800D01*
G01D02*
X-855300Y-1777800D01*
G01D02*
X-854800Y-1780900D01*
G01D02*
X-853100Y-1783500D01*
G01D02*
X-850000Y-1785500D01*
G01D02*
X-846100Y-1786000D01*
G01D02*
X-842300Y-1785500D01*
G01X-848900Y-1771400D02*
X-843300D01*
G01X-842700Y-1760900D02*
X-846100Y-1760400D01*
G01D02*
X-849500Y-1760900D01*
G01D02*
X-852200Y-1762700D01*
G01D02*
X-853400Y-1765200D01*
G01D02*
X-852900Y-1767900D01*
G01D02*
X-851000Y-1770100D01*
G01D02*
X-848900Y-1771400D01*
G01X-853900Y1611200D02*
X-855300Y1608300D01*
G01D02*
X-854800Y1605200D01*
G01D02*
X-853100Y1602500D01*
G01D02*
X-850000Y1600600D01*
G01D02*
X-846100Y1600000D01*
G01D02*
X-842300Y1600600D01*
G01X-848900Y1614600D02*
X-843300D01*
G01X-842700Y1625000D02*
X-846100Y1625700D01*
G01D02*
X-849500Y1625000D01*
G01D02*
X-852200Y1623300D01*
G01D02*
X-853400Y1620800D01*
G01D02*
X-852900Y1618200D01*
G01D02*
X-851000Y1616000D01*
G01D02*
X-848900Y1614600D01*
G01D02*
X-851100Y1613400D01*
G01D02*
X-853900Y1611200D01*
G01X-842300Y-1785500D02*
X-839200Y-1783500D01*
G01D02*
X-837300Y-1780900D01*
G01D02*
X-837000Y-1777800D01*
G01D02*
X-838300Y-1774800D01*
G01D02*
X-841100Y-1772600D01*
G01D02*
X-843300Y-1771400D01*
G01D02*
X-841200Y-1770100D01*
G01D02*
X-839200Y-1767900D01*
G01D02*
X-838700Y-1765200D01*
G01D02*
X-840100Y-1762700D01*
G01D02*
X-842700Y-1760900D01*
G01X-842300Y1600600D02*
X-839200Y1602500D01*
G01D02*
X-837300Y1605200D01*
G01D02*
X-837000Y1608300D01*
G01D02*
X-838300Y1611200D01*
G01X-843300Y1614600D02*
X-841200Y1616000D01*
G01D02*
X-839200Y1618200D01*
G01D02*
X-838700Y1620800D01*
G01D02*
X-840100Y1623300D01*
G01D02*
X-842700Y1625000D01*
G01X-838300Y1611200D02*
X-841100Y1613400D01*
G01D02*
X-843300Y1614600D01*
G01X-619600Y-1755800D02*
Y-1788700D01*
G01Y1628200D02*
Y1595300D01*
G01X-384100Y-1760400D02*
X-393300Y-1782400D01*
G01D02*
Y-1786000D01*
G01X-402400Y-1760400D02*
X-384100D01*
G01Y1625700D02*
X-393300Y1603600D01*
G01D02*
Y1600000D01*
G01X-402400Y1625700D02*
X-384100D01*
G01X-368600Y1379100D02*
Y1589100D01*
G01Y1379100D02*
X2056300D01*
G01X1545800Y1420300D02*
X-368600D01*
G01X1545800Y1461500D02*
X-368600D01*
G01X1545800Y1502700D02*
X-368600D01*
G01X1545800Y1543900D02*
X-368600D01*
G01X-345900Y1573000D02*
Y1555900D01*
G01Y1563200D02*
X-338500D01*
G01Y1573000D02*
X-345900D01*
G01X-333600Y1555900D02*
X-338500Y1563200D01*
G01X-328700Y1573000D02*
Y1555900D01*
G01D02*
X-316500D01*
G01X-338500Y1563200D02*
X-336000Y1563800D01*
G01D02*
X-334200Y1565600D01*
G01D02*
X-333600Y1568100D01*
G01D02*
X-334200Y1570600D01*
G01D02*
X-336000Y1572400D01*
G01D02*
X-338500Y1573000D01*
G01X-328700Y1564400D02*
X-320200D01*
G01X-316500Y1573000D02*
X-328700D01*
G01X-311600D02*
Y1555900D01*
G01D02*
X-299400D01*
G01X-277300D02*
Y1573000D01*
G01Y1564400D02*
X-268700D01*
G01X-277300Y1573000D02*
X-265000D01*
G01X-259300Y1558400D02*
X-257100Y1556400D01*
G01D02*
X-254000Y1555900D01*
G01D02*
X-251000Y1556400D01*
G01Y1572400D02*
X-254000Y1573000D01*
G01D02*
X-257100Y1572400D01*
G01D02*
X-259300Y1570600D01*
G01D02*
X-260200Y1568100D01*
G01D02*
Y1559600D01*
G01Y1560700D02*
X-259300Y1558400D01*
G01X-251000Y1556400D02*
X-248800Y1558400D01*
G01X-243000Y1573000D02*
Y1555900D01*
G01X-247900Y1568100D02*
X-248800Y1570600D01*
G01D02*
X-251000Y1572400D01*
G01X-248800Y1558400D02*
X-247900Y1560700D01*
G01D02*
Y1569300D01*
G01X-243000Y1563200D02*
X-235700D01*
G01D02*
X-233100Y1563800D01*
G01Y1572400D02*
X-235700Y1573000D01*
G01D02*
X-243000D01*
G01X-230800Y1555900D02*
X-235700Y1563200D01*
G01X-233100Y1563800D02*
X-231400Y1565600D01*
G01D02*
X-230800Y1568100D01*
G01D02*
X-231400Y1570600D01*
G01D02*
X-233100Y1572400D01*
G01X-208600Y1555900D02*
X-202600Y1573000D01*
G01D02*
X-196400Y1555900D01*
G01X-207500Y1559600D02*
X-197700D01*
G01X-187500Y-1755800D02*
Y-1798900D01*
G01X-191500Y1555900D02*
X-185500D01*
G01D02*
X-182400Y1556400D01*
G01D02*
X-180100Y1557900D01*
G01X-179300Y1573000D02*
X-185500D01*
G01D02*
X-188400Y1572400D01*
G01D02*
X-190800Y1570900D01*
G01D02*
X-191500Y1568700D01*
G01D02*
X-190800Y1566600D01*
G01D02*
X-188400Y1565000D01*
G01D02*
X-185500Y1564400D01*
G01X-180100Y1562400D02*
X-182400Y1563800D01*
G01D02*
X-185500Y1564400D01*
G01Y1638500D02*
Y1595300D01*
G01X-180100Y1557900D02*
X-179300Y1560100D01*
G01X-174400Y1555900D02*
Y1573000D01*
G01X-179300Y1560100D02*
X-180100Y1562400D01*
G01X-174400Y1573000D02*
X-168300Y1559600D01*
G01D02*
X-162100Y1573000D01*
G01D02*
Y1555900D01*
G01X-120900Y-1749600D02*
Y-1407900D01*
G01X916500Y-1663000D02*
X-120900D01*
G01X2056300Y-1619900D02*
X-120900D01*
G01X916500Y-1576700D02*
X-120900D01*
G01X916500Y-1533400D02*
X-120900D01*
G01X916500Y-1490100D02*
X-120900D01*
G01X916500Y-1449100D02*
X-120900D01*
G01Y-1407900D02*
X2056300D01*
G01X-115500Y1589100D02*
Y1379100D01*
G01X-107900Y-1703100D02*
X-97000D01*
G01X-102500D02*
Y-1718300D01*
G01X-107900Y-1684000D02*
X-107200Y-1685900D01*
G01D02*
X-105100Y-1687300D01*
G01D02*
X-102500Y-1687900D01*
G01X-107900Y-1695400D02*
X-102500D01*
G01D02*
X-99800Y-1694900D01*
G01D02*
X-97700Y-1693500D01*
G01D02*
X-97000Y-1691500D01*
G01D02*
X-97700Y-1689800D01*
G01D02*
X-99800Y-1688300D01*
G01D02*
X-102500Y-1687900D01*
G01X-97000Y-1680200D02*
X-102500D01*
G01D02*
X-105100Y-1680800D01*
G01D02*
X-107200Y-1682100D01*
G01D02*
X-107900Y-1684000D01*
G01Y-1634800D02*
Y-1650200D01*
G01X-97000Y-1634800D02*
Y-1650200D01*
G01X-107900Y-1642500D02*
X-97000D01*
G01X-107900Y-1597000D02*
Y-1605800D01*
G01D02*
X-107500Y-1606900D01*
G01D02*
X-106300Y-1608000D01*
G01D02*
X-104500Y-1608700D01*
G01D02*
X-102500Y-1609000D01*
G01D02*
X-97000D01*
G01Y-1593800D02*
X-102500D01*
G01D02*
X-104500Y-1593900D01*
G01D02*
X-106300Y-1594700D01*
G01D02*
X-107500Y-1595700D01*
G01D02*
X-107900Y-1597000D01*
G01Y-1522500D02*
Y-1507300D01*
G01D02*
X-102500Y-1519200D01*
G01D02*
X-97000Y-1507300D01*
G01D02*
Y-1522500D01*
G01X-107900Y-1436100D02*
Y-1420900D01*
G01D02*
X-102500Y-1432900D01*
G01D02*
X-97000Y-1420900D01*
G01D02*
Y-1436100D01*
G01X-92700Y-1711800D02*
X-86100D01*
G01D02*
X-84000Y-1711200D01*
G01D02*
X-82400Y-1709600D01*
G01D02*
X-81800Y-1707300D01*
G01D02*
X-82400Y-1705300D01*
G01D02*
X-84000Y-1703700D01*
G01D02*
X-86100Y-1703100D01*
G01D02*
X-92700D01*
G01D02*
Y-1718300D01*
G01X-81800D02*
X-86100Y-1711800D01*
G01X-77400Y-1710600D02*
X-69800D01*
G01X-66600Y-1703100D02*
X-77400D01*
G01D02*
Y-1718300D01*
G01D02*
X-66600D01*
G01X-92700Y-1680200D02*
Y-1691100D01*
G01D02*
X-92000Y-1693200D01*
G01D02*
X-89900Y-1694800D01*
G01D02*
X-87300Y-1695400D01*
G01D02*
X-84500Y-1694800D01*
G01D02*
X-82500Y-1693200D01*
G01D02*
X-81800Y-1691100D01*
G01D02*
Y-1680200D01*
G01X-77400Y-1688900D02*
X-70900D01*
G01X-77400Y-1680200D02*
Y-1695400D01*
G01X-70900Y-1680200D02*
X-77400D01*
G01X-92700Y-1650200D02*
X-87300Y-1634800D01*
G01D02*
X-81800Y-1650200D01*
G01X-77400Y-1634800D02*
Y-1650200D01*
G01X-91500Y-1646800D02*
X-83000D01*
G01X-77400Y-1643600D02*
X-70900D01*
G01Y-1634800D02*
X-77400D01*
G01X-92700Y-1609000D02*
X-87300Y-1593800D01*
G01D02*
X-81800Y-1609000D01*
G01X-91500Y-1605800D02*
X-83000D01*
G01X-76800Y-1595600D02*
X-77400Y-1597500D01*
G01D02*
X-76800Y-1599400D01*
G01X-77400Y-1609000D02*
X-72100D01*
G01X-92700Y-1522500D02*
X-87300Y-1507300D01*
G01D02*
X-81800Y-1522500D01*
G01X-91500Y-1519200D02*
X-83000D01*
G01X-77400Y-1507300D02*
X-66600D01*
G01X-92700Y-1436100D02*
X-87300Y-1420900D01*
G01D02*
X-81800Y-1436100D01*
G01X-91500Y-1432900D02*
X-83000D01*
G01X-77400Y-1420900D02*
X-66600D01*
G01X-87900Y1558400D02*
X-85500Y1556400D01*
G01D02*
X-82500Y1555900D01*
G01D02*
X-79400Y1556400D01*
G01D02*
X-77200Y1558400D01*
G01X-82500Y1561900D02*
X-75200Y1554700D01*
G01X-77200Y1570600D02*
X-79400Y1572400D01*
G01D02*
X-82500Y1573000D01*
G01D02*
X-85500Y1572400D01*
G01D02*
X-87900Y1570600D01*
G01D02*
X-88600Y1568100D01*
G01D02*
Y1560700D01*
G01D02*
X-87900Y1558400D01*
G01X-62200Y-1718300D02*
X-56700Y-1703100D01*
G01X-61000Y-1715000D02*
X-52600D01*
G01X-70900Y-1688900D02*
X-68800Y-1688300D01*
G01D02*
X-67200Y-1686700D01*
G01D02*
X-66600Y-1684600D01*
G01D02*
X-67200Y-1682400D01*
G01X-66600Y-1695400D02*
X-70900Y-1688900D01*
G01X-62200Y-1687900D02*
X-54600D01*
G01X-62200Y-1695400D02*
Y-1680200D01*
G01X-67200Y-1682400D02*
X-68800Y-1680800D01*
G01D02*
X-70900Y-1680200D01*
G01X-62200D02*
X-51400D01*
G01X-66600Y-1650200D02*
X-70900Y-1643600D01*
G01X-62200Y-1650200D02*
X-56700D01*
G01X-62200Y-1634800D02*
Y-1650200D01*
G01X-70900Y-1643600D02*
X-68800Y-1643000D01*
G01D02*
X-67200Y-1641500D01*
G01D02*
X-66600Y-1639300D01*
G01D02*
X-67200Y-1637100D01*
G01D02*
X-68800Y-1635400D01*
G01D02*
X-70900Y-1634800D01*
G01X-56700D02*
X-62200D01*
G01X-76800Y-1599400D02*
X-74700Y-1600900D01*
G01D02*
X-72100Y-1601300D01*
G01Y-1609000D02*
X-69300Y-1608400D01*
G01D02*
X-67300Y-1607100D01*
G01D02*
X-66600Y-1605200D01*
G01D02*
X-67300Y-1603200D01*
G01D02*
X-69300Y-1601900D01*
G01D02*
X-72100Y-1601300D01*
G01X-62200D02*
X-54600D01*
G01X-62200Y-1593800D02*
Y-1609000D01*
G01D02*
X-51400D01*
G01X-66600Y-1593800D02*
X-72100D01*
G01D02*
X-74700Y-1594200D01*
G01D02*
X-76800Y-1595600D01*
G01X-51400Y-1593800D02*
X-62200D01*
G01X-72100Y-1507300D02*
Y-1522500D01*
G01Y-1420900D02*
Y-1436100D01*
G01X-62200Y-1428400D02*
X-54600D01*
G01X-62200Y-1420900D02*
Y-1436100D01*
G01D02*
X-51400D01*
G01Y-1420900D02*
X-62200D01*
G01X-65400Y1573000D02*
Y1555900D01*
G01X-76300Y1568100D02*
X-77200Y1570600D01*
G01Y1558400D02*
X-76300Y1560700D01*
G01D02*
Y1568100D01*
G01X-71500Y1573000D02*
X-59200D01*
G01X-56700Y-1703100D02*
X-51400Y-1718300D01*
G01X-47000Y-1703100D02*
X-36000D01*
G01X-47000Y-1695400D02*
X-41500Y-1680200D01*
G01X-45800Y-1692100D02*
X-37200D01*
G01X-56700Y-1650200D02*
X-54300Y-1649300D01*
G01X-45900Y-1650200D02*
Y-1634800D01*
G01X-54300Y-1649300D02*
X-52600Y-1647300D01*
G01D02*
X-51500Y-1644200D01*
G01D02*
Y-1640800D01*
G01D02*
X-52600Y-1637800D01*
G01D02*
X-54300Y-1635600D01*
G01D02*
X-56700Y-1634800D01*
G01X-45900D02*
X-37200Y-1650200D01*
G01X-57900Y-1512700D02*
X-55400Y-1506200D01*
G01X-47000Y-1507300D02*
Y-1522500D01*
G01D02*
X-36000D01*
G01X-47000Y-1429500D02*
X-40500D01*
G01X-47000Y-1420900D02*
Y-1436100D01*
G01X-40500Y-1420900D02*
X-47000D01*
G01X-48100Y1564400D02*
Y1555900D01*
G01X-54300Y1573000D02*
X-48100Y1564400D01*
G01D02*
X-42100Y1573000D01*
G01X-41500Y-1703100D02*
Y-1718300D01*
G01X-31700D02*
Y-1703100D01*
G01D02*
X-26300Y-1715000D01*
G01D02*
X-20800Y-1703100D01*
G01X-41500Y-1680200D02*
X-36000Y-1695400D01*
G01X-31700Y-1683400D02*
Y-1692100D01*
G01D02*
X-31300Y-1693500D01*
G01D02*
X-30100Y-1694500D01*
G01D02*
X-28400Y-1695200D01*
G01D02*
X-26300Y-1695400D01*
G01D02*
X-20800D01*
G01Y-1680200D02*
X-26300D01*
G01D02*
X-28400Y-1680500D01*
G01D02*
X-30100Y-1681200D01*
G01D02*
X-31300Y-1682200D01*
G01D02*
X-31700Y-1683400D01*
G01X-37200Y-1650200D02*
Y-1634800D01*
G01X-31700D02*
Y-1650200D01*
G01D02*
X-20800D01*
G01X-31700Y-1642500D02*
X-24100D01*
G01X-20800Y-1634800D02*
X-31700D01*
G01Y-1609000D02*
X-26300D01*
G01D02*
X-23900Y-1608300D01*
G01X-31700Y-1593800D02*
Y-1609000D01*
G01X-23900Y-1594500D02*
X-26300Y-1593800D01*
G01D02*
X-31700D01*
G01X-40500Y-1429500D02*
X-38200Y-1429000D01*
G01D02*
X-36600Y-1427400D01*
G01D02*
X-36000Y-1425200D01*
G01D02*
X-36600Y-1423000D01*
G01D02*
X-38200Y-1421300D01*
G01X-36000Y-1436100D02*
X-40500Y-1429500D01*
G01X-26300Y-1420900D02*
Y-1436100D01*
G01X-29500D02*
X-23000D01*
G01X-38200Y-1421300D02*
X-40500Y-1420900D01*
G01X-29500D02*
X-23000D01*
G01X-20800Y-1703100D02*
Y-1718300D01*
G01X-16500Y-1710600D02*
X-8900D01*
G01X-5600Y-1703100D02*
X-16500D01*
G01D02*
Y-1718300D01*
G01D02*
X-5600D01*
G01X-16500Y-1687900D02*
X-8900D01*
G01X-16500Y-1680200D02*
Y-1695400D01*
G01D02*
X-5600D01*
G01Y-1680200D02*
X-16500D01*
G01Y-1650200D02*
X-11100D01*
G01D02*
X-8400Y-1649600D01*
G01D02*
X-6300Y-1648300D01*
G01X-5600Y-1634800D02*
X-11100D01*
G01D02*
X-13700Y-1635400D01*
G01D02*
X-15800Y-1636800D01*
G01D02*
X-16500Y-1638700D01*
G01D02*
X-15800Y-1640600D01*
G01D02*
X-13700Y-1642100D01*
G01D02*
X-11100Y-1642500D01*
G01X-6300Y-1644400D02*
X-8400Y-1643000D01*
G01D02*
X-11100Y-1642500D01*
G01X-23900Y-1608300D02*
X-22000Y-1606100D01*
G01D02*
X-21000Y-1603100D01*
G01D02*
Y-1599700D01*
G01D02*
X-22000Y-1596600D01*
G01X-16500Y-1601300D02*
X-8900D01*
G01X-16500Y-1593800D02*
Y-1609000D01*
G01D02*
X-5600D01*
G01X-22000Y-1596600D02*
X-23900Y-1594500D01*
G01X-5600Y-1593800D02*
X-16500D01*
G01Y-1522500D02*
X-11100Y-1507300D01*
G01D02*
X-5600Y-1522500D01*
G01X-15400Y-1519200D02*
X-6800D01*
G01X-16500Y-1436100D02*
X-11100Y-1420900D01*
G01D02*
X-5600Y-1436100D01*
G01X-15400Y-1432900D02*
X-6800D01*
G01X-16700Y1589100D02*
Y1379100D01*
G01X-100Y-1718300D02*
Y-1703100D01*
G01D02*
X8600Y-1718300D01*
G01D02*
Y-1703100D01*
G01X-1300Y-1650200D02*
X4100D01*
G01D02*
X6900Y-1649600D01*
G01D02*
X8900Y-1648300D01*
G01X-6300D02*
X-5600Y-1646400D01*
G01D02*
X-6300Y-1644400D01*
G01X9600Y-1634800D02*
X4100D01*
G01D02*
X1500Y-1635400D01*
G01D02*
X-600Y-1636800D01*
G01D02*
X-1300Y-1638700D01*
G01D02*
X-600Y-1640600D01*
G01D02*
X1500Y-1642100D01*
G01D02*
X4100Y-1642500D01*
G01X8900Y-1648300D02*
X9600Y-1646400D01*
G01D02*
X8900Y-1644400D01*
G01D02*
X6900Y-1643000D01*
G01D02*
X4100Y-1642500D01*
G01X-1300Y-1602500D02*
X5300D01*
G01D02*
X7400Y-1601900D01*
G01D02*
X9000Y-1600300D01*
G01D02*
X9600Y-1598100D01*
G01D02*
X9000Y-1595900D01*
G01X-1300Y-1593800D02*
Y-1609000D01*
G01X9000Y-1595900D02*
X7400Y-1594400D01*
G01D02*
X5300Y-1593800D01*
G01D02*
X-1300D01*
G01Y-1507300D02*
Y-1522500D01*
G01D02*
X9600D01*
G01X-1300Y-1420900D02*
Y-1436100D01*
G01D02*
X9600D01*
G01X-5800Y1474200D02*
Y1489900D01*
G01D02*
X-100Y1477600D01*
G01D02*
X5500Y1489900D01*
G01D02*
Y1474200D01*
G01X9900D02*
X15500Y1489900D01*
G01X-5800Y1531100D02*
Y1515400D01*
G01D02*
X5500D01*
G01X9900Y1531100D02*
Y1515400D01*
G01D02*
X21100D01*
G01X-5800Y1523200D02*
X2100D01*
G01X5500Y1531100D02*
X-5800D01*
G01X8100Y1573000D02*
Y1555900D01*
G01X1900Y1573000D02*
X14200D01*
G01X14500Y-1769100D02*
X13600Y-1773300D01*
G01D02*
X13300Y-1777800D01*
G01D02*
Y-1779700D01*
G01D02*
X14000Y-1782100D01*
G01D02*
X15900Y-1784300D01*
G01D02*
X18900Y-1785600D01*
G01D02*
X22400Y-1786000D01*
G01D02*
X26000Y-1785600D01*
G01D02*
X28900Y-1784300D01*
G01Y-1773300D02*
X26000Y-1771900D01*
G01D02*
X22400Y-1771400D01*
G01D02*
X18900Y-1771900D01*
G01D02*
X15900Y-1773300D01*
G01D02*
X14000Y-1775400D01*
G01D02*
X13300Y-1777800D01*
G01X26100Y-1760400D02*
X22400D01*
G01D02*
X20100Y-1760900D01*
G01D02*
X17900Y-1762700D01*
G01D02*
X15900Y-1765500D01*
G01D02*
X14500Y-1769100D01*
G01X13900Y-1703100D02*
X24800D01*
G01X19300D02*
Y-1718300D01*
G01Y-1593800D02*
Y-1609000D01*
G01X13900Y-1593800D02*
X24800D01*
G01X19300Y-1507300D02*
Y-1522500D01*
G01X13900Y-1507300D02*
X24800D01*
G01X15500Y1489900D02*
X21100Y1474200D01*
G01X11100Y1477600D02*
X19900D01*
G01X25500Y1489900D02*
X36800D01*
G01X25500Y1531100D02*
Y1515400D01*
G01D02*
X36800D01*
G01X25500Y1523200D02*
X33400D01*
G01X36800Y1531100D02*
X25500D01*
G01X19000Y1573000D02*
Y1555900D01*
G01D02*
X31300D01*
G01X19000Y1564400D02*
X27600D01*
G01X31300Y1573000D02*
X19000D01*
G01X13600Y1612700D02*
X13300Y1608300D01*
G01D02*
Y1606400D01*
G01D02*
X14000Y1603800D01*
G01D02*
X15900Y1601800D01*
G01D02*
X18900Y1600500D01*
G01D02*
X22400Y1600000D01*
G01D02*
X26000Y1600500D01*
G01D02*
X28900Y1601800D01*
G01X14000Y1610600D02*
X13300Y1608300D01*
G01X26100Y1625700D02*
X22400D01*
G01D02*
X20100Y1625100D01*
G01D02*
X17900Y1623300D01*
G01D02*
X15900Y1620500D01*
G01D02*
X14500Y1617000D01*
G01D02*
X13600Y1612700D01*
G01X28900D02*
X26000Y1614200D01*
G01D02*
X22400Y1614600D01*
G01D02*
X18900Y1614200D01*
G01D02*
X15900Y1612700D01*
G01D02*
X14000Y1610600D01*
G01X28900Y-1784300D02*
X31000Y-1782100D01*
G01D02*
X31700Y-1779700D01*
G01D02*
Y-1777800D01*
G01D02*
X31000Y-1775400D01*
G01D02*
X28900Y-1773300D01*
G01X29200Y-1593800D02*
Y-1609000D01*
G01Y-1601300D02*
X40000D01*
G01Y-1593800D02*
Y-1609000D01*
G01X29200Y-1515000D02*
X36800D01*
G01X29200Y-1507300D02*
Y-1522500D01*
G01D02*
X40000D01*
G01X44400Y-1516000D02*
X50900D01*
G01X44400Y-1507300D02*
Y-1522500D01*
G01X40000Y-1507300D02*
X29200D01*
G01X50900D02*
X44400D01*
G01X30300Y-1436100D02*
Y-1420900D01*
G01D02*
X39000Y-1436100D01*
G01D02*
Y-1420900D01*
G01X45200Y-1423000D02*
X44400Y-1425200D01*
G01D02*
Y-1432900D01*
G01Y-1431700D02*
X45200Y-1433900D01*
G01X31200Y1489900D02*
Y1474200D01*
G01X41200Y1482000D02*
X49000D01*
G01X41200Y1489900D02*
Y1474200D01*
G01D02*
X52400D01*
G01Y1489900D02*
X41200D01*
G01Y1527700D02*
Y1518800D01*
G01D02*
X41600Y1517500D01*
G01D02*
X42800Y1516400D01*
G01D02*
X44600Y1515700D01*
G01D02*
X46800Y1515400D01*
G01Y1531100D02*
X44600Y1530800D01*
G01D02*
X42800Y1530200D01*
G01D02*
X41600Y1529000D01*
G01D02*
X41200Y1527700D01*
G01X36800Y1558100D02*
X38100Y1556900D01*
G01D02*
X40000Y1556200D01*
G01D02*
X42400Y1555900D01*
G01D02*
X48600D01*
G01Y1573000D02*
X42400D01*
G01D02*
X40000Y1572700D01*
G01D02*
X38100Y1572000D01*
G01D02*
X36800Y1570800D01*
G01D02*
X36300Y1569300D01*
G01D02*
Y1559600D01*
G01D02*
X36800Y1558100D01*
G01X28900Y1601800D02*
X31000Y1603800D01*
G01D02*
X31700Y1606400D01*
G01D02*
Y1608300D01*
G01D02*
X31000Y1610600D01*
G01D02*
X28900Y1612700D01*
G01X49900Y-1576700D02*
Y-1749600D01*
G01X397800Y-1706300D02*
X49900D01*
G01X50900Y-1516000D02*
X53200Y-1515400D01*
G01D02*
X54800Y-1513800D01*
G01D02*
X55200Y-1511700D01*
G01D02*
X54800Y-1509500D01*
G01X55200Y-1522500D02*
X50900Y-1516000D01*
G01X60700Y-1522500D02*
Y-1507300D01*
G01X54800Y-1509500D02*
X53200Y-1507900D01*
G01D02*
X50900Y-1507300D01*
G01X60700D02*
X69400Y-1522500D01*
G01X55200Y-1425200D02*
X54600Y-1423000D01*
G01D02*
X52600Y-1421300D01*
G01X47100D02*
X45200Y-1423000D01*
G01Y-1433900D02*
X47100Y-1435500D01*
G01D02*
X49900Y-1436100D01*
G01D02*
X52600Y-1435500D01*
G01D02*
X54600Y-1433900D01*
G01D02*
X55200Y-1431700D01*
G01D02*
Y-1424100D01*
G01X52600Y-1421300D02*
X49900Y-1420900D01*
G01D02*
X47100Y-1421300D01*
G01X56800Y1481000D02*
X63500D01*
G01X56800Y1489900D02*
Y1474200D01*
G01X63500Y1489900D02*
X56800D01*
G01X46800Y1515400D02*
X52400D01*
G01Y1531100D02*
X46800D01*
G01X56800D02*
X68100D01*
G01X53500Y1573000D02*
Y1555900D01*
G01Y1564400D02*
X65700D01*
G01X62900Y-1683400D02*
Y-1692100D01*
G01D02*
X63300Y-1693500D01*
G01D02*
X64500Y-1694500D01*
G01D02*
X66300Y-1695200D01*
G01D02*
X68400Y-1695400D01*
G01D02*
X73800D01*
G01X78800Y-1682400D02*
X78100Y-1684600D01*
G01D02*
Y-1692100D01*
G01Y-1691100D02*
X78800Y-1693300D01*
G01D02*
X80900Y-1694800D01*
G01X73800Y-1680200D02*
X68400D01*
G01D02*
X66300Y-1680500D01*
G01D02*
X64500Y-1681200D01*
G01D02*
X63300Y-1682200D01*
G01D02*
X62900Y-1683400D01*
G01X80900Y-1680800D02*
X78800Y-1682400D01*
G01X69400Y-1522500D02*
Y-1507300D01*
G01X74900Y-1522500D02*
X80300Y-1507300D01*
G01X76000Y-1519200D02*
X84600D01*
G01X66700Y-1434500D02*
X65900Y-1433000D01*
G01D02*
X64200D01*
G01D02*
X63500Y-1434500D01*
G01D02*
X64200Y-1435800D01*
G01D02*
X65900D01*
G01D02*
X66700Y-1434500D01*
G01X63500Y1481000D02*
X65700Y1481600D01*
G01D02*
X67300Y1483200D01*
G01D02*
X68100Y1485400D01*
G01D02*
X67300Y1487600D01*
G01D02*
X65700Y1489300D01*
G01X68100Y1474200D02*
X63500Y1481000D01*
G01X78100Y1489900D02*
Y1474200D01*
G01X74700D02*
X81400D01*
G01X65700Y1489300D02*
X63500Y1489900D01*
G01X74700D02*
X81400D01*
G01X62500Y1531100D02*
Y1515400D01*
G01X72500Y1522200D02*
X79100D01*
G01D02*
X81400Y1522800D01*
G01X72500Y1531100D02*
Y1515400D01*
G01X83600D02*
X79100Y1522200D01*
G01X81400Y1530500D02*
X79100Y1531100D01*
G01D02*
X72500D01*
G01X65700Y1573000D02*
Y1555900D01*
G01X71800D02*
Y1573000D01*
G01D02*
X81700Y1555900D01*
G01X89000Y-1684600D02*
X88300Y-1682400D01*
G01X80900Y-1694800D02*
X83600Y-1695400D01*
G01D02*
X86400Y-1694800D01*
G01D02*
X88300Y-1693300D01*
G01D02*
X89000Y-1691100D01*
G01D02*
Y-1683400D01*
G01X93500Y-1695400D02*
X98800D01*
G01X93500Y-1680200D02*
Y-1695400D01*
G01X88300Y-1682400D02*
X86400Y-1680800D01*
G01D02*
X83600Y-1680200D01*
G01D02*
X80900Y-1680800D01*
G01X98800Y-1680200D02*
X93500D01*
G01X80300Y-1507300D02*
X85800Y-1522500D01*
G01X95500Y-1507300D02*
Y-1522500D01*
G01X90100Y-1507300D02*
X101000D01*
G01X88200Y1474200D02*
X93800Y1489900D01*
G01D02*
X99200Y1474200D01*
G01X89300Y1477600D02*
X98000D01*
G01X81400Y1522800D02*
X83000Y1524400D01*
G01X93800Y1531100D02*
Y1515400D01*
G01X90400D02*
X97000D01*
G01X83000Y1524400D02*
X83600Y1526600D01*
G01D02*
X83000Y1528800D01*
G01D02*
X81400Y1530500D01*
G01X90400Y1531100D02*
X97000D01*
G01X81700Y1555900D02*
Y1573000D01*
G01X93900D02*
Y1555900D01*
G01X90200D02*
X97500D01*
G01X90200Y1573000D02*
X97500D01*
G01X98800Y-1695400D02*
X101100Y-1694600D01*
G01D02*
X103100Y-1692600D01*
G01D02*
X104100Y-1689500D01*
G01D02*
Y-1686100D01*
G01D02*
X103100Y-1683000D01*
G01X108700Y-1687900D02*
X116200D01*
G01X108700Y-1680200D02*
Y-1695400D01*
G01D02*
X119500D01*
G01X103100Y-1683000D02*
X101100Y-1680900D01*
G01D02*
X98800Y-1680200D01*
G01X119500D02*
X108700D01*
G01X105300Y-1515000D02*
X113000D01*
G01X105300Y-1507300D02*
Y-1522500D01*
G01D02*
X116200D01*
G01Y-1507300D02*
X105300D01*
G01X103800Y1489900D02*
Y1474200D01*
G01D02*
X114900D01*
G01X103800Y1527700D02*
Y1518800D01*
G01D02*
X104200Y1517500D01*
G01D02*
X105400Y1516400D01*
G01D02*
X107200Y1515700D01*
G01D02*
X109400Y1515400D01*
G01D02*
X114900D01*
G01Y1531100D02*
X109400D01*
G01D02*
X107200Y1530800D01*
G01D02*
X105400Y1530200D01*
G01D02*
X104200Y1529000D01*
G01D02*
X103800Y1527700D01*
G01X105300Y1558100D02*
X106600Y1556900D01*
G01D02*
X108700Y1556200D01*
G01D02*
X111000Y1555900D01*
G01D02*
X117100D01*
G01Y1573000D02*
X111000D01*
G01D02*
X108700Y1572700D01*
G01D02*
X106600Y1572000D01*
G01D02*
X105300Y1570800D01*
G01D02*
X104800Y1569300D01*
G01D02*
Y1559600D01*
G01D02*
X105300Y1558100D01*
G01X119500Y1515400D02*
X124900Y1531100D01*
G01D02*
X130500Y1515400D01*
G01X120600Y1518800D02*
X129300D01*
G01X122000Y1555900D02*
X128200Y1573000D01*
G01D02*
X134200Y1555900D01*
G01X123300Y1559600D02*
X133000D01*
G01X140100Y-1695400D02*
Y-1680200D01*
G01D02*
X148800Y-1695400D01*
G01D02*
Y-1680200D01*
G01X136900Y-1522500D02*
Y-1507300D01*
G01D02*
X145600Y-1522500D01*
G01D02*
Y-1507300D01*
G01X135100Y1531100D02*
Y1515400D01*
G01D02*
X146200D01*
G01X139200Y1573000D02*
Y1555900D01*
G01D02*
X151500D01*
G01X165200Y-1684600D02*
X164500Y-1682400D01*
G01X155000D02*
X154300Y-1684600D01*
G01D02*
Y-1692100D01*
G01Y-1691100D02*
X155000Y-1693300D01*
G01D02*
X157100Y-1694800D01*
G01D02*
X159800Y-1695400D01*
G01D02*
X162600Y-1694800D01*
G01D02*
X164500Y-1693300D01*
G01D02*
X165200Y-1691100D01*
G01D02*
Y-1683400D01*
G01X164500Y-1682400D02*
X162600Y-1680800D01*
G01D02*
X159800Y-1680200D01*
G01D02*
X157100Y-1680800D01*
G01D02*
X155000Y-1682400D01*
G01X162000Y-1511700D02*
X161200Y-1509500D01*
G01X151800D02*
X151100Y-1511700D01*
G01D02*
Y-1519200D01*
G01Y-1518200D02*
X151800Y-1520300D01*
G01D02*
X153700Y-1521900D01*
G01D02*
X156500Y-1522500D01*
G01D02*
X159200Y-1521900D01*
G01D02*
X161200Y-1520300D01*
G01D02*
X162000Y-1518200D01*
G01D02*
Y-1510500D01*
G01X161200Y-1509500D02*
X159200Y-1507900D01*
G01D02*
X156500Y-1507300D01*
G01D02*
X153700Y-1507900D01*
G01D02*
X151800Y-1509500D01*
G01X156200Y1543900D02*
Y1379100D01*
G01X176600Y-1693800D02*
X175900Y-1692400D01*
G01D02*
X174200D01*
G01D02*
X173300Y-1693800D01*
G01D02*
X174200Y-1695200D01*
G01D02*
X175900D01*
G01D02*
X176600Y-1693800D01*
G01X173300Y-1520900D02*
X172500Y-1519500D01*
G01D02*
X170800D01*
G01D02*
X170100Y-1520900D01*
G01D02*
X170800Y-1522300D01*
G01D02*
X172500D01*
G01D02*
X173300Y-1520900D01*
G01X173500Y1555900D02*
X179500Y1573000D01*
G01D02*
X185800Y1555900D01*
G01X174800Y1559600D02*
X184400D01*
G01X190600Y1573000D02*
Y1555900D01*
G01Y1563200D02*
X198000D01*
G01D02*
X200500Y1563800D01*
G01D02*
X202300Y1565600D01*
G01Y1570600D02*
X200500Y1572400D01*
G01D02*
X198000Y1573000D01*
G01D02*
X190600D01*
G01X207800D02*
Y1555900D01*
G01X202300Y1565600D02*
X202900Y1568100D01*
G01D02*
X202300Y1570600D01*
G01X207800Y1563200D02*
X215100D01*
G01D02*
X217600Y1563800D01*
G01D02*
X219400Y1565600D01*
G01Y1570600D02*
X217600Y1572400D01*
G01D02*
X215100Y1573000D01*
G01D02*
X207800D01*
G01X225000D02*
Y1555900D01*
G01X237100D02*
X232300Y1563200D01*
G01X219400Y1565600D02*
X220000Y1568100D01*
G01D02*
X219400Y1570600D01*
G01X225000Y1563200D02*
X232300D01*
G01D02*
X234800Y1563800D01*
G01D02*
X236500Y1565600D01*
G01D02*
X237100Y1568100D01*
G01D02*
X236500Y1570600D01*
G01D02*
X234800Y1572400D01*
G01D02*
X232300Y1573000D01*
G01D02*
X225000D01*
G01X248900Y-1755800D02*
Y-1788700D01*
G01X242900Y1558400D02*
X245100Y1556400D01*
G01D02*
X248200Y1555900D01*
G01D02*
X251300Y1556400D01*
G01D02*
X253500Y1558400D01*
G01X254400Y1568100D02*
X253500Y1570600D01*
G01D02*
X251300Y1572400D01*
G01D02*
X248200Y1573000D01*
G01D02*
X245100Y1572400D01*
G01D02*
X242900Y1570600D01*
G01D02*
X242200Y1568100D01*
G01D02*
Y1559600D01*
G01Y1560700D02*
X242900Y1558400D01*
G01X253500D02*
X254400Y1560700D01*
G01X248900Y1628200D02*
Y1595300D01*
G01X259300Y1573000D02*
X265300Y1555900D01*
G01D02*
X271500Y1573000D01*
G01X254400Y1560700D02*
Y1569300D01*
G01X276400Y1555900D02*
X282600Y1573000D01*
G01D02*
X288700Y1555900D01*
G01X277700Y1559600D02*
X287300D01*
G01X293500Y1573000D02*
Y1555900D01*
G01D02*
X305800D01*
G01X325100Y1543900D02*
Y1379100D01*
G01X397800Y-1749600D02*
Y-1407900D01*
G01X412100Y-1708100D02*
Y-1724600D01*
G01D02*
X418000D01*
G01D02*
X420800Y-1724000D01*
G01D02*
X423000Y-1722300D01*
G01D02*
X423800Y-1719900D01*
G01D02*
X423000Y-1717500D01*
G01D02*
X420800Y-1715800D01*
G01D02*
X418000Y-1715200D01*
G01D02*
X412100D01*
G01X418000D02*
X420200Y-1714700D01*
G01D02*
X422000Y-1713400D01*
G01D02*
X422600Y-1711600D01*
G01D02*
X422000Y-1709900D01*
G01D02*
X420200Y-1708700D01*
G01D02*
X418000Y-1708100D01*
G01D02*
X412100D01*
G01X410900Y-1685500D02*
X417900D01*
G01X410900Y-1678600D02*
Y-1692400D01*
G01D02*
X420800D01*
G01X425000D02*
X429800D01*
G01X425000Y-1678600D02*
Y-1692400D01*
G01X420800Y-1678600D02*
X410900D01*
G01X429800D02*
X425000D01*
G01X412800Y-1642500D02*
X419500D01*
G01D02*
X421600Y-1641900D01*
G01D02*
X423200Y-1640500D01*
G01D02*
X423800Y-1638200D01*
G01D02*
X423200Y-1636000D01*
G01D02*
X421600Y-1634400D01*
G01D02*
X419500Y-1633800D01*
G01D02*
X412800D01*
G01D02*
Y-1649200D01*
G01X423800D02*
X419500Y-1642500D01*
G01X428100Y-1649200D02*
X433500Y-1633800D01*
G01X412800Y-1605900D02*
X418300Y-1590700D01*
G01D02*
X423800Y-1605900D01*
G01X414000Y-1602700D02*
X422600D01*
G01X412800Y-1547400D02*
Y-1562600D01*
G01D02*
X423800D01*
G01X418300Y-1504600D02*
Y-1519100D01*
G01X427600Y-1508800D02*
Y-1516000D01*
G01Y-1515000D02*
X428300Y-1517000D01*
G01X413100Y-1504600D02*
X423500D01*
G01X428300Y-1506700D02*
X427600Y-1508800D01*
G01X413100Y-1437700D02*
Y-1423300D01*
G01D02*
X418300Y-1434600D01*
G01D02*
X423500Y-1423300D01*
G01D02*
Y-1437700D01*
G01X427600Y-1423300D02*
Y-1433600D01*
G01D02*
X428300Y-1435700D01*
G01X428500Y-1708100D02*
Y-1724600D01*
G01X440300D02*
X435600Y-1717500D01*
G01X445000Y-1708100D02*
Y-1724600D01*
G01D02*
X456700D01*
G01X428500Y-1717500D02*
X435600D01*
G01D02*
X437900Y-1716900D01*
G01D02*
X439700Y-1715200D01*
G01D02*
X440300Y-1712800D01*
G01D02*
X439700Y-1710400D01*
G01D02*
X437900Y-1708800D01*
G01D02*
X435600Y-1708100D01*
G01D02*
X428500D01*
G01X445000Y-1716400D02*
X453200D01*
G01X456700Y-1708100D02*
X445000D01*
G01X429800Y-1692400D02*
X432300Y-1691500D01*
G01D02*
X434300Y-1689000D01*
G01D02*
X434800Y-1685500D01*
G01D02*
X434300Y-1681900D01*
G01X439000Y-1683900D02*
Y-1687100D01*
G01D02*
X439700Y-1689900D01*
G01D02*
X441200Y-1691800D01*
G01D02*
X442800Y-1692400D01*
G01D02*
X448900D01*
G01Y-1685500D02*
X444900D01*
G01X434300Y-1681900D02*
X432300Y-1679400D01*
G01D02*
X429800Y-1678600D01*
G01X448900D02*
X442800D01*
G01D02*
X441200Y-1679100D01*
G01D02*
X439700Y-1681100D01*
G01D02*
X439000Y-1683900D01*
G01X433500Y-1633800D02*
X439000Y-1649200D01*
G01X429200Y-1645800D02*
X437800D01*
G01X443400Y-1649200D02*
X448700D01*
G01Y-1633800D02*
X443400D01*
G01D02*
Y-1649200D01*
G01X429200Y-1605900D02*
Y-1590700D01*
G01D02*
X437900Y-1605900D01*
G01D02*
Y-1590700D01*
G01X443400Y-1596600D02*
Y-1600000D01*
G01D02*
X444300Y-1603000D01*
G01D02*
X445800Y-1605200D01*
G01Y-1591400D02*
X444300Y-1593500D01*
G01D02*
X443400Y-1596600D01*
G01X433500Y-1547400D02*
Y-1562600D01*
G01X430300D02*
X436800D01*
G01X444400D02*
Y-1547400D01*
G01X430300D02*
X436800D01*
G01X444400D02*
X453200Y-1562600D01*
G01X428300Y-1517000D02*
X430100Y-1518500D01*
G01D02*
X432800Y-1519100D01*
G01D02*
X435300Y-1518500D01*
G01D02*
X437200Y-1517000D01*
G01D02*
X437900Y-1515000D01*
G01D02*
Y-1507700D01*
G01X441900Y-1504600D02*
Y-1519100D01*
G01D02*
X452300D01*
G01X437900Y-1508800D02*
X437200Y-1506700D01*
G01D02*
X435300Y-1505200D01*
G01D02*
X432800Y-1504600D01*
G01D02*
X430100Y-1505200D01*
G01D02*
X428300Y-1506700D01*
G01Y-1435700D02*
X430100Y-1437100D01*
G01D02*
X432800Y-1437700D01*
G01D02*
X435300Y-1437100D01*
G01D02*
X437200Y-1435700D01*
G01D02*
X437900Y-1433600D01*
G01D02*
Y-1423300D01*
G01X447100D02*
X444600Y-1423900D01*
G01D02*
X442700Y-1425000D01*
G01D02*
X441900Y-1427000D01*
G01D02*
X442700Y-1428700D01*
G01D02*
X444600Y-1430100D01*
G01D02*
X447100Y-1430500D01*
G01X441900Y-1437700D02*
X447100D01*
G01X461400Y-1724600D02*
X467300Y-1708100D01*
G01X462800Y-1721100D02*
X471900D01*
G01X448900Y-1692400D02*
Y-1685500D01*
G01X452900D02*
X459900D01*
G01X452900Y-1678600D02*
Y-1692400D01*
G01D02*
X462900D01*
G01Y-1678600D02*
X452900D01*
G01X448700Y-1649200D02*
X451100Y-1648300D01*
G01D02*
X453000Y-1646200D01*
G01D02*
X454000Y-1643100D01*
G01D02*
Y-1639900D01*
G01D02*
X453000Y-1636800D01*
G01D02*
X451100Y-1634700D01*
G01D02*
X448700Y-1633800D01*
G01X460800D02*
X467300D01*
G01X460800Y-1649200D02*
X467300D01*
G01X445800Y-1605200D02*
X447700Y-1605900D01*
G01D02*
X454200D01*
G01D02*
Y-1598200D01*
G01D02*
X449900D01*
G01X458600Y-1590700D02*
Y-1605900D01*
G01D02*
X469400D01*
G01X454200Y-1590700D02*
X447700D01*
G01D02*
X445800Y-1591400D01*
G01X453200Y-1562600D02*
Y-1547400D01*
G01X458600D02*
Y-1562600D01*
G01D02*
X469400D01*
G01X458600Y-1555000D02*
X466100D01*
G01X469400Y-1547400D02*
X458600D01*
G01X456400Y-1511900D02*
X463600D01*
G01X456400Y-1504600D02*
Y-1519100D01*
G01D02*
X466700D01*
G01Y-1504600D02*
X456400D01*
G01X452300Y-1423300D02*
X447100D01*
G01Y-1437700D02*
X449800Y-1437300D01*
G01D02*
X451500Y-1436000D01*
G01D02*
X452300Y-1434000D01*
G01D02*
X451500Y-1432300D01*
G01D02*
X449800Y-1430900D01*
G01D02*
X447100Y-1430500D01*
G01X456400Y-1423300D02*
X466700D01*
G01X461600D02*
Y-1437700D01*
G01X469800Y-1788000D02*
X480800Y-1783200D01*
G01X481800Y-1773100D02*
X478800Y-1771900D01*
G01D02*
X475300Y-1771400D01*
G01D02*
X466100D01*
G01D02*
X467900Y-1760400D01*
G01D02*
X482700D01*
G01X467300Y-1708100D02*
X473200Y-1724600D01*
G01X478000Y-1708100D02*
Y-1724600D01*
G01Y-1717500D02*
X489600Y-1708100D01*
G01X466900Y-1692400D02*
X476900Y-1678600D01*
G01X464100Y-1633800D02*
Y-1649200D01*
G01X476000Y-1633800D02*
X482500D01*
G01X479300D02*
Y-1649200D01*
G01X476000D02*
X482500D01*
G01X473800Y-1598200D02*
X481400D01*
G01X473800Y-1590700D02*
Y-1605900D01*
G01D02*
X484800D01*
G01Y-1590700D02*
X473800D01*
G01Y-1562600D02*
X479300Y-1547400D01*
G01D02*
X484800Y-1562600D01*
G01X475000Y-1559400D02*
X483600D01*
G01X470900Y-1512900D02*
X476900D01*
G01D02*
X479400Y-1512000D01*
G01D02*
X480900Y-1509900D01*
G01X470900Y-1504600D02*
Y-1519100D01*
G01X481100D02*
X476900Y-1512900D01*
G01X480900Y-1507400D02*
X479400Y-1505400D01*
G01D02*
X476900Y-1504600D01*
G01D02*
X470900D01*
G01X469800Y1598100D02*
X480800Y1602800D01*
G01X481800Y1613000D02*
X478800Y1614200D01*
G01D02*
X475300Y1614600D01*
G01D02*
X466100D01*
G01D02*
X467900Y1625700D01*
G01D02*
X482700D01*
G01X480800Y-1783200D02*
X482800Y-1781900D01*
G01D02*
X484200Y-1780400D01*
G01D02*
X484600Y-1778800D01*
G01D02*
Y-1776900D01*
G01D02*
X483900Y-1774800D01*
G01D02*
X481800Y-1773100D01*
G01X481900Y-1714300D02*
X489600Y-1724600D01*
G01X494400D02*
X500300D01*
G01Y-1708100D02*
X497300Y-1708700D01*
G01D02*
X495200Y-1710200D01*
G01D02*
X494400Y-1712200D01*
G01D02*
X495200Y-1714300D01*
G01D02*
X497300Y-1715800D01*
G01D02*
X500300Y-1716400D01*
G01X480900Y-1681500D02*
Y-1689500D01*
G01D02*
X481500Y-1691000D01*
G01D02*
X483400Y-1692100D01*
G01D02*
X485900Y-1692400D01*
G01D02*
X490800D01*
G01X494800Y-1682500D02*
Y-1689500D01*
G01Y-1688400D02*
X495500Y-1690500D01*
G01D02*
X497300Y-1692000D01*
G01D02*
X499800Y-1692400D01*
G01X490800Y-1678600D02*
X485900D01*
G01D02*
X483400Y-1678800D01*
G01D02*
X481500Y-1680000D01*
G01D02*
X480900Y-1681500D01*
G01X499800Y-1678600D02*
X497300Y-1679000D01*
G01D02*
X495500Y-1680500D01*
G01D02*
X494800Y-1682500D01*
G01X489800Y-1596300D02*
X491700Y-1597800D01*
G01D02*
X494500Y-1598200D01*
G01X489000Y-1605900D02*
X494500D01*
G01D02*
X497200Y-1605300D01*
G01D02*
X499200Y-1604000D01*
G01Y-1600100D02*
X497200Y-1598800D01*
G01D02*
X494500Y-1598200D01*
G01X500000Y-1590700D02*
X494500D01*
G01D02*
X491700Y-1591100D01*
G01D02*
X489800Y-1592600D01*
G01D02*
X489000Y-1594400D01*
G01D02*
X489800Y-1596300D01*
G01X489000Y-1547400D02*
Y-1562600D01*
G01Y-1556100D02*
X495500D01*
G01D02*
X497700Y-1555600D01*
G01D02*
X499400Y-1553900D01*
G01Y-1549700D02*
X497700Y-1548000D01*
G01D02*
X495500Y-1547400D01*
G01D02*
X489000D01*
G01X500000Y-1562600D02*
X495500Y-1556100D01*
G01X485200Y-1519100D02*
X490400Y-1504600D01*
G01D02*
X495500Y-1519100D01*
G01X486400Y-1516000D02*
X494400D01*
G01X480900Y-1509900D02*
Y-1507400D01*
G01X495500Y-1423300D02*
X490400D01*
G01D02*
X487900Y-1423700D01*
G01D02*
X485900Y-1424900D01*
G01D02*
X485200Y-1426400D01*
G01D02*
Y-1434600D01*
G01D02*
X485900Y-1436100D01*
G01D02*
X487900Y-1437300D01*
G01D02*
X490400Y-1437700D01*
G01D02*
X495500D01*
G01X480800Y1602800D02*
X482800Y1604000D01*
G01D02*
X484200Y1605600D01*
G01D02*
X484600Y1607200D01*
G01D02*
Y1609200D01*
G01D02*
X483900Y1611200D01*
G01D02*
X481800Y1613000D01*
G01X500300Y-1724600D02*
X503200Y-1724000D01*
G01D02*
X505400Y-1722600D01*
G01D02*
X506200Y-1720500D01*
G01D02*
X505400Y-1718400D01*
G01X506200Y-1708100D02*
X500300D01*
G01X505400Y-1718400D02*
X503200Y-1716900D01*
G01D02*
X500300Y-1716400D01*
G01X499800Y-1692400D02*
X502300Y-1692000D01*
G01D02*
X504200Y-1690500D01*
G01D02*
X504800Y-1688400D01*
G01D02*
Y-1681500D01*
G01X508800Y-1686500D02*
X514900D01*
G01D02*
X517200Y-1685800D01*
G01X508800Y-1678600D02*
Y-1692400D01*
G01X518900D02*
X514900Y-1686500D01*
G01X504800Y-1682500D02*
X504200Y-1680500D01*
G01D02*
X502300Y-1679000D01*
G01D02*
X499800Y-1678600D01*
G01X517200Y-1679300D02*
X514900Y-1678600D01*
G01D02*
X508800D01*
G01X504200Y-1633800D02*
Y-1644700D01*
G01D02*
X505000Y-1647000D01*
G01D02*
X507000Y-1648600D01*
G01D02*
X509700Y-1649200D01*
G01D02*
X512400Y-1648600D01*
G01D02*
X514400Y-1647000D01*
G01D02*
X515200Y-1644700D01*
G01D02*
Y-1633800D01*
G01X499200Y-1604000D02*
X500000Y-1602100D01*
G01D02*
X499200Y-1600100D01*
G01X499400Y-1553900D02*
X500000Y-1551700D01*
G01D02*
X499400Y-1549700D01*
G01X500700Y-1519100D02*
Y-1504600D01*
G01D02*
X509000Y-1519100D01*
G01D02*
Y-1504600D01*
G01X514000Y-1507700D02*
Y-1516000D01*
G01D02*
X514700Y-1517500D01*
G01D02*
X516600Y-1518600D01*
G01Y-1505100D02*
X514700Y-1506100D01*
G01D02*
X514000Y-1507700D01*
G01X509900Y-1427400D02*
X509300Y-1425300D01*
G01D02*
X507300Y-1423900D01*
G01D02*
X504800Y-1423300D01*
G01D02*
X502200Y-1423900D01*
G01D02*
X500300Y-1425300D01*
G01D02*
X499700Y-1427400D01*
G01D02*
Y-1434600D01*
G01Y-1433600D02*
X500300Y-1435700D01*
G01D02*
X502200Y-1437100D01*
G01D02*
X504800Y-1437700D01*
G01D02*
X507300Y-1437100D01*
G01D02*
X509300Y-1435700D01*
G01D02*
X509900Y-1433600D01*
G01D02*
Y-1426400D01*
G01X515000Y-1437700D02*
Y-1423300D01*
G01D02*
X523300Y-1437700D01*
G01X504100Y1589100D02*
Y1379100D01*
G01X517200Y-1685800D02*
X518700Y-1683700D01*
G01X523900Y-1692400D02*
Y-1678600D01*
G01D02*
X531900Y-1692400D01*
G01D02*
Y-1678600D01*
G01X518700Y-1683700D02*
Y-1681200D01*
G01D02*
X517200Y-1679300D01*
G01X520600Y-1649200D02*
Y-1633800D01*
G01D02*
X529300Y-1649200D01*
G01D02*
Y-1633800D01*
G01X524900Y-1590700D02*
Y-1602700D01*
G01X530400Y-1604700D02*
X519500D01*
G01Y-1597200D02*
X530400D01*
G01X524900Y-1547400D02*
Y-1559400D01*
G01X530400Y-1561600D02*
X519500D01*
G01Y-1553900D02*
X530400D01*
G01X516600Y-1518600D02*
X519200Y-1519100D01*
G01D02*
X524300D01*
G01X528500Y-1511900D02*
X535700D01*
G01X528500Y-1504600D02*
Y-1519100D01*
G01D02*
X538800D01*
G01X524300Y-1504600D02*
X519200D01*
G01D02*
X516600Y-1505100D01*
G01X538800Y-1504600D02*
X528500D01*
G01X523300Y-1437700D02*
Y-1423300D01*
G01X528500Y-1430500D02*
X535700D01*
G01X528500Y-1437700D02*
Y-1423300D01*
G01D02*
X538800D01*
G01X536900Y-1685500D02*
X543800D01*
G01X536900Y-1678600D02*
Y-1692400D01*
G01D02*
X546900D01*
G01Y-1678600D02*
X536900D01*
G01X534800Y-1633800D02*
Y-1649200D01*
G01D02*
X545600D01*
G01X550000Y-1641500D02*
X557500D01*
G01X560800Y-1633800D02*
X550000D01*
G01D02*
Y-1649200D01*
G01D02*
X560800D01*
G01X542900Y-1508200D02*
X543500Y-1510100D01*
G01D02*
X545400Y-1511300D01*
G01D02*
X547900Y-1511900D01*
G01X542900Y-1519100D02*
X547900D01*
G01D02*
X550600Y-1518500D01*
G01Y-1512300D02*
X547900Y-1511900D01*
G01X553100Y-1504600D02*
X547900D01*
G01D02*
X545400Y-1505100D01*
G01D02*
X543500Y-1506400D01*
G01D02*
X542900Y-1508200D01*
G01X550600Y-1423900D02*
X547900Y-1423300D01*
G01D02*
X545400Y-1423900D01*
G01D02*
X543500Y-1425300D01*
G01D02*
X542900Y-1427400D01*
G01D02*
Y-1434600D01*
G01Y-1433600D02*
X543500Y-1435700D01*
G01D02*
X545400Y-1437100D01*
G01D02*
X547900Y-1437700D01*
G01D02*
X550600Y-1437100D01*
G01X550900Y-1686500D02*
X556800D01*
G01D02*
X559200Y-1685800D01*
G01D02*
X560600Y-1683700D01*
G01X550900Y-1678600D02*
Y-1692400D01*
G01X560800D02*
X556800Y-1686500D01*
G01X560600Y-1683700D02*
Y-1681200D01*
G01D02*
X559200Y-1679300D01*
G01D02*
X556800Y-1678600D01*
G01D02*
X550900D01*
G01X567900Y-1634400D02*
X566000Y-1635700D01*
G01D02*
X565200Y-1637700D01*
G01D02*
X566000Y-1639600D01*
G01D02*
X567900Y-1641000D01*
G01X565200Y-1649200D02*
X570700D01*
G01X550600Y-1518500D02*
X552500Y-1517200D01*
G01D02*
X553100Y-1515400D01*
G01D02*
X552500Y-1513600D01*
G01D02*
X550600Y-1512300D01*
G01X553100Y-1427400D02*
X552500Y-1425300D01*
G01D02*
X550600Y-1423900D01*
G01Y-1437100D02*
X552500Y-1435700D01*
G01D02*
X553100Y-1433600D01*
G01D02*
Y-1426400D01*
G01X557300Y-1431500D02*
X563500D01*
G01D02*
X565800Y-1430800D01*
G01D02*
X567300Y-1428700D01*
G01D02*
Y-1426200D01*
G01D02*
X565800Y-1424100D01*
G01D02*
X563500Y-1423300D01*
G01D02*
X557300D01*
G01D02*
Y-1437700D01*
G01X567600D02*
X563500Y-1431500D01*
G01X570700Y-1663000D02*
Y-1749600D01*
G01X585000Y-1717700D02*
Y-1731700D01*
G01X581900D02*
X588000D01*
G01X916500Y-1706300D02*
X570700D01*
G01X581900Y-1717700D02*
X588000D01*
G01X578100Y-1681700D02*
Y-1688700D01*
G01Y-1687700D02*
X578700Y-1689800D01*
G01D02*
X580400Y-1691300D01*
G01D02*
X582900Y-1691700D01*
G01D02*
X585500Y-1691300D01*
G01Y-1678300D02*
X582900Y-1677700D01*
G01D02*
X580400Y-1678300D01*
G01D02*
X578700Y-1679700D01*
G01D02*
X578100Y-1681700D01*
G01X576200Y-1633800D02*
X570700D01*
G01D02*
X567900Y-1634400D01*
G01Y-1641000D02*
X570700Y-1641500D01*
G01Y-1649200D02*
X573300Y-1648600D01*
G01D02*
X575400Y-1647300D01*
G01D02*
X576200Y-1645300D01*
G01D02*
X575400Y-1643400D01*
G01D02*
X573300Y-1641900D01*
G01D02*
X570700Y-1641500D01*
G01X585900Y-1633800D02*
X583100Y-1634400D01*
G01D02*
X581200Y-1635700D01*
G01D02*
X580400Y-1637700D01*
G01D02*
X581200Y-1639600D01*
G01D02*
X583100Y-1641000D01*
G01D02*
X585900Y-1641500D01*
G01X580400Y-1649200D02*
X585900D01*
G01X571700Y-1504600D02*
Y-1515000D01*
G01D02*
X572300Y-1517000D01*
G01D02*
X574200Y-1518500D01*
G01D02*
X576900Y-1519100D01*
G01D02*
X579400Y-1518500D01*
G01D02*
X581300Y-1517000D01*
G01D02*
X581900Y-1515000D01*
G01D02*
Y-1504600D01*
G01X571700Y-1437700D02*
Y-1423300D01*
G01D02*
X576900Y-1434600D01*
G01D02*
X581900Y-1423300D01*
G01D02*
Y-1437700D01*
G01X578200Y1589100D02*
Y1379100D01*
G01X594900Y-1731700D02*
Y-1717700D01*
G01D02*
X603000Y-1731700D01*
G01X585500Y-1691300D02*
X587400Y-1689800D01*
G01D02*
X588000Y-1687700D01*
G01D02*
Y-1680800D01*
G01X592000Y-1677700D02*
Y-1687700D01*
G01D02*
X592700Y-1689800D01*
G01D02*
X594500Y-1691300D01*
G01D02*
X597000Y-1691700D01*
G01D02*
X599500Y-1691300D01*
G01D02*
X601400Y-1689800D01*
G01D02*
X602000Y-1687700D01*
G01D02*
Y-1677700D01*
G01X588000Y-1681700D02*
X587400Y-1679700D01*
G01D02*
X585500Y-1678300D01*
G01X591400Y-1633800D02*
X585900D01*
G01Y-1649200D02*
X588600Y-1648600D01*
G01D02*
X590600Y-1647300D01*
G01D02*
X591400Y-1645300D01*
G01D02*
X590600Y-1643400D01*
G01D02*
X588600Y-1641900D01*
G01D02*
X585900Y-1641500D01*
G01X587100Y-1519100D02*
Y-1504600D01*
G01D02*
X595300Y-1519100D01*
G01D02*
Y-1504600D01*
G01X600500D02*
Y-1519100D01*
G01D02*
X610900D01*
G01X600500Y-1423300D02*
X610900D01*
G01X588600Y1555900D02*
X594800D01*
G01D02*
X597400Y1556700D01*
G01D02*
X599500Y1559100D01*
G01X588600Y1573000D02*
Y1555900D01*
G01X599500Y1559100D02*
X600700Y1562500D01*
G01D02*
Y1566300D01*
G01D02*
X599500Y1569700D01*
G01D02*
X597400Y1572100D01*
G01D02*
X594800Y1573000D01*
G01D02*
X588600D01*
G01X603000Y-1731700D02*
Y-1717700D01*
G01X610400Y-1718300D02*
X608600Y-1719500D01*
G01D02*
X607900Y-1721200D01*
G01D02*
X608600Y-1723000D01*
G01D02*
X610400Y-1724300D01*
G01D02*
X612900Y-1724800D01*
G01X607900Y-1731700D02*
X612900D01*
G01D02*
X615400Y-1731300D01*
G01D02*
X617300Y-1729900D01*
G01D02*
X617900Y-1728200D01*
G01D02*
X617300Y-1726500D01*
G01D02*
X615400Y-1725200D01*
G01D02*
X612900Y-1724800D01*
G01X617900Y-1717700D02*
X612900D01*
G01D02*
X610400Y-1718300D01*
G01X611000Y-1677700D02*
Y-1691700D01*
G01X620000D02*
X625000D01*
G01X606000Y-1677700D02*
X616000D01*
G01X620600Y-1679400D02*
X620000Y-1681200D01*
G01D02*
X620600Y-1683000D01*
G01X612000Y-1649200D02*
Y-1633800D01*
G01D02*
X620700Y-1649200D01*
G01X614800Y-1511900D02*
X622100D01*
G01X614800Y-1504600D02*
Y-1519100D01*
G01D02*
X625200D01*
G01Y-1504600D02*
X614800D01*
G01X605700Y-1423300D02*
Y-1437700D01*
G01X622700Y-1423900D02*
X620000Y-1423300D01*
G01D02*
X617500Y-1423900D01*
G01D02*
X615600Y-1425300D01*
G01D02*
X614800Y-1427400D01*
G01D02*
Y-1434600D01*
G01Y-1433600D02*
X615600Y-1435700D01*
G01D02*
X617500Y-1437100D01*
G01D02*
X620000Y-1437700D01*
G01D02*
X622700Y-1437100D01*
G01X605800Y1555900D02*
X611900Y1573000D01*
G01D02*
X618100Y1555900D01*
G01X607000Y1559600D02*
X616800D01*
G01X626900Y-1717700D02*
Y-1731700D01*
G01X624000D02*
X629900D01*
G01X636000D02*
X641000D01*
G01X636000Y-1717700D02*
Y-1731700D01*
G01X624000Y-1717700D02*
X629900D01*
G01X641000D02*
X636000D01*
G01X620600Y-1683000D02*
X622500Y-1684300D01*
G01D02*
X625000Y-1684800D01*
G01Y-1691700D02*
X627500Y-1691300D01*
G01D02*
X629300Y-1689900D01*
G01D02*
X630000Y-1688200D01*
G01D02*
X629300Y-1686500D01*
G01D02*
X627500Y-1685200D01*
G01D02*
X625000Y-1684800D01*
G01X636000Y-1691700D02*
X642000D01*
G01X630000Y-1677700D02*
X625000D01*
G01D02*
X622500Y-1678300D01*
G01D02*
X620600Y-1679400D01*
G01X636000Y-1677700D02*
X642000D01*
G01X620700Y-1649200D02*
Y-1633800D01*
G01X637000Y-1638200D02*
X636200Y-1636000D01*
G01D02*
X634300Y-1634400D01*
G01D02*
X631500Y-1633800D01*
G01D02*
X628900Y-1634400D01*
G01D02*
X626800Y-1636000D01*
G01D02*
X626100Y-1638200D01*
G01D02*
Y-1645800D01*
G01Y-1644700D02*
X626800Y-1647000D01*
G01D02*
X628900Y-1648600D01*
G01D02*
X631500Y-1649200D01*
G01D02*
X634300Y-1648600D01*
G01D02*
X636200Y-1647000D01*
G01D02*
X637000Y-1644700D01*
G01D02*
Y-1637200D01*
G01X629300Y-1508200D02*
X630000Y-1510100D01*
G01D02*
X631800Y-1511300D01*
G01D02*
X634500Y-1511900D01*
G01X629300Y-1519100D02*
X634500D01*
G01D02*
X637000Y-1518500D01*
G01D02*
X638900Y-1517200D01*
G01Y-1513600D02*
X637000Y-1512300D01*
G01D02*
X634500Y-1511900D01*
G01X639600Y-1504600D02*
X634500D01*
G01D02*
X631800Y-1505100D01*
G01D02*
X630000Y-1506400D01*
G01D02*
X629300Y-1508200D01*
G01X625200Y-1427400D02*
X624400Y-1425300D01*
G01D02*
X622700Y-1423900D01*
G01Y-1437100D02*
X624400Y-1435700D01*
G01D02*
X625200Y-1433600D01*
G01D02*
Y-1426400D01*
G01X629000Y1573000D02*
Y1555900D01*
G01X623000Y1573000D02*
X635200D01*
G01X641000Y-1731700D02*
X643500Y-1730800D01*
G01D02*
X645300Y-1728200D01*
G01D02*
X646000Y-1724800D01*
G01D02*
X645300Y-1721200D01*
G01D02*
X643500Y-1718700D01*
G01X650000Y-1724800D02*
X656900D01*
G01X650000Y-1717700D02*
Y-1731700D01*
G01D02*
X659900D01*
G01X643500Y-1718700D02*
X641000Y-1717700D01*
G01X659900D02*
X650000D01*
G01X639100Y-1677700D02*
Y-1691700D01*
G01X648100D02*
X652900D01*
G01D02*
X655400Y-1690800D01*
G01X648100Y-1677700D02*
Y-1691700D01*
G01X655400Y-1678700D02*
X652900Y-1677700D01*
G01D02*
X648100D01*
G01X641400Y-1633800D02*
X652200D01*
G01X646700D02*
Y-1649200D01*
G01X638900Y-1517200D02*
X639600Y-1515400D01*
G01D02*
X638900Y-1513600D01*
G01X643800Y-1508200D02*
X644400Y-1510100D01*
G01D02*
X646300Y-1511300D01*
G01D02*
X648800Y-1511900D01*
G01X643800Y-1519100D02*
X648800D01*
G01D02*
X651500Y-1518500D01*
G01D02*
X653400Y-1517200D01*
G01D02*
X654000Y-1515400D01*
G01D02*
X653400Y-1513600D01*
G01D02*
X651500Y-1512300D01*
G01D02*
X648800Y-1511900D01*
G01X654000Y-1504600D02*
X648800D01*
G01D02*
X646300Y-1505100D01*
G01D02*
X644400Y-1506400D01*
G01D02*
X643800Y-1508200D01*
G01Y-1430500D02*
X650900D01*
G01X654000Y-1423300D02*
X643800D01*
G01D02*
Y-1437700D01*
G01D02*
X654000D01*
G01X640100Y1573000D02*
Y1555900D01*
G01D02*
X652300D01*
G01X640100Y1564400D02*
X648700D01*
G01X652300Y1573000D02*
X640100D01*
G01X655400Y-1690800D02*
X657400Y-1688200D01*
G01D02*
X658000Y-1684800D01*
G01D02*
X657400Y-1681200D01*
G01X661900Y-1684800D02*
X669000D01*
G01X661900Y-1677700D02*
Y-1691700D01*
G01D02*
X672000D01*
G01X657400Y-1681200D02*
X655400Y-1678700D01*
G01X672000Y-1677700D02*
X661900D01*
G01X656600Y-1641500D02*
X664200D01*
G01X667400Y-1633800D02*
X656600D01*
G01D02*
Y-1649200D01*
G01D02*
X667400D01*
G01X671800D02*
X677300D01*
G01Y-1633800D02*
X671800D01*
G01D02*
Y-1649200D01*
G01X659100Y-1437700D02*
Y-1423300D01*
G01D02*
X667400Y-1437700D01*
G01D02*
Y-1423300D01*
G01X677900Y-1731700D02*
Y-1717700D01*
G01D02*
X682900Y-1728800D01*
G01D02*
X687900Y-1717700D01*
G01D02*
Y-1731700D01*
G01X677300Y-1649200D02*
X679700Y-1648300D01*
G01D02*
X681600Y-1646200D01*
G01D02*
X682600Y-1643100D01*
G01D02*
Y-1639900D01*
G01D02*
X681600Y-1636800D01*
G01D02*
X679700Y-1634700D01*
G01D02*
X677300Y-1633800D01*
G01X673600Y-1519100D02*
Y-1504600D01*
G01D02*
X681700Y-1519100D01*
G01D02*
Y-1504600D01*
G01X686900Y-1508800D02*
Y-1516000D01*
G01Y-1515000D02*
X687600Y-1517000D01*
G01D02*
X689600Y-1518500D01*
G01D02*
X692100Y-1519100D01*
G01Y-1504600D02*
X689600Y-1505200D01*
G01D02*
X687600Y-1506700D01*
G01D02*
X686900Y-1508800D01*
G01X682800Y-1423300D02*
X676700D01*
G01D02*
X674900Y-1424000D01*
G01D02*
X673500Y-1426100D01*
G01D02*
X672600Y-1428900D01*
G01D02*
Y-1432100D01*
G01D02*
X673500Y-1434900D01*
G01D02*
X674900Y-1437000D01*
G01D02*
X676700Y-1437700D01*
G01D02*
X682800D01*
G01D02*
Y-1430500D01*
G01D02*
X678800D01*
G01X701800Y-1755800D02*
Y-1788700D01*
G01X691900Y-1731700D02*
X696900Y-1717700D01*
G01D02*
X702000Y-1731700D01*
G01X692900Y-1728800D02*
X700900D01*
G01X705900Y-1731700D02*
X716000Y-1717700D01*
G01Y-1731700D02*
X705900Y-1717700D01*
G01X690000Y-1691700D02*
Y-1677700D01*
G01D02*
X695000Y-1688700D01*
G01D02*
X700000Y-1677700D01*
G01D02*
Y-1691700D01*
G01X704000D02*
X709000Y-1677700D01*
G01X705100Y-1688700D02*
X712900D01*
G01X692100Y-1519100D02*
X694700Y-1518500D01*
G01D02*
X696500Y-1517000D01*
G01D02*
X697200Y-1515000D01*
G01D02*
Y-1507700D01*
G01X706500Y-1504600D02*
Y-1519100D01*
G01X697200Y-1508800D02*
X696500Y-1506700D01*
G01D02*
X694700Y-1505200D01*
G01D02*
X692100Y-1504600D01*
G01X701400D02*
X711700D01*
G01Y-1423300D02*
X706500D01*
G01D02*
X703900Y-1423900D01*
G01D02*
X702100Y-1425000D01*
G01D02*
X701400Y-1427000D01*
G01D02*
X702100Y-1428700D01*
G01D02*
X703900Y-1430100D01*
G01D02*
X706500Y-1430500D01*
G01X701400Y-1437700D02*
X706500D01*
G01D02*
X709000Y-1437300D01*
G01Y-1430900D02*
X706500Y-1430500D01*
G01X701800Y1628200D02*
Y1595300D01*
G01X709000Y-1677700D02*
X713900Y-1691700D01*
G01X717900D02*
X727900Y-1677700D01*
G01Y-1691700D02*
X717900Y-1677700D01*
G01X715700Y-1511900D02*
X722900D01*
G01X715700Y-1504600D02*
Y-1519100D01*
G01D02*
X726000D01*
G01Y-1504600D02*
X715700D01*
G01X709000Y-1437300D02*
X711000Y-1436000D01*
G01D02*
X711700Y-1434000D01*
G01D02*
X711000Y-1432300D01*
G01D02*
X709000Y-1430900D01*
G01X715700Y-1431500D02*
X721900D01*
G01D02*
X724400Y-1430800D01*
G01D02*
X725900Y-1428700D01*
G01Y-1426200D02*
X724400Y-1424100D01*
G01D02*
X721900Y-1423300D01*
G01D02*
X715700D01*
G01D02*
Y-1437700D01*
G01X730200Y-1519100D02*
X735300D01*
G01D02*
X737800Y-1518100D01*
G01D02*
X739800Y-1515400D01*
G01D02*
X740500Y-1511900D01*
G01D02*
X739800Y-1508200D01*
G01X730200Y-1504600D02*
Y-1519100D01*
G01X739800Y-1508200D02*
X737800Y-1505500D01*
G01D02*
X735300Y-1504600D01*
G01D02*
X730200D01*
G01X725900Y-1428700D02*
Y-1426200D01*
G01X730200Y-1430500D02*
X737400D01*
G01X740500Y-1423300D02*
X730200D01*
G01D02*
Y-1437700D01*
G01D02*
X740500D01*
G01X743600Y-1533400D02*
Y-1749600D01*
G01X754800Y-1423300D02*
X749600D01*
G01D02*
X747100Y-1423700D01*
G01D02*
X745200Y-1424900D01*
G01D02*
X744600Y-1426400D01*
G01D02*
Y-1434600D01*
G01D02*
X745200Y-1436100D01*
G01D02*
X747100Y-1437300D01*
G01D02*
X749600Y-1437700D01*
G01D02*
X754800D01*
G01X759400Y1589100D02*
Y1379100D01*
G01X765700Y-1430500D02*
X764900Y-1429200D01*
G01D02*
X763400D01*
G01D02*
X762600Y-1430500D01*
G01D02*
X763400Y-1431800D01*
G01D02*
X764900D01*
G01D02*
X765700Y-1430500D01*
G01Y-1435700D02*
X764900Y-1434300D01*
G01D02*
X763400D01*
G01D02*
X762600Y-1435700D01*
G01D02*
X763400Y-1437000D01*
G01D02*
X764900D01*
G01D02*
X765700Y-1435700D01*
G01X769700Y1573000D02*
Y1555900D01*
G01D02*
X782000D01*
G01X769700Y1564400D02*
X778300D01*
G01X782000Y1573000D02*
X769700D01*
G01X787400Y1558100D02*
X788800Y1556900D01*
G01D02*
X790700Y1556200D01*
G01D02*
X793100Y1555900D01*
G01D02*
X799100D01*
G01Y1573000D02*
X793100D01*
G01D02*
X790700Y1572700D01*
G01D02*
X788800Y1572000D01*
G01D02*
X787400Y1570800D01*
G01D02*
X786900Y1569300D01*
G01D02*
Y1559600D01*
G01D02*
X787400Y1558100D01*
G01X822400Y1555900D02*
Y1573000D01*
G01D02*
X832200Y1555900D01*
G01D02*
Y1573000D01*
G01X839100Y1558400D02*
X841500Y1556400D01*
G01D02*
X844400Y1555900D01*
G01D02*
X847500Y1556400D01*
G01Y1572400D02*
X844400Y1573000D01*
G01D02*
X841500Y1572400D01*
G01D02*
X839100Y1570600D01*
G01D02*
X838400Y1568100D01*
G01D02*
Y1559600D01*
G01Y1560700D02*
X839100Y1558400D01*
G01X847500Y1556400D02*
X849800Y1558400D01*
G01X863500Y1557600D02*
X862800Y1559100D01*
G01X859900Y1558500D02*
Y1556900D01*
G01D02*
X861300Y1555900D01*
G01D02*
X862800Y1556300D01*
G01D02*
X863500Y1557600D01*
G01X850600Y1568100D02*
X849800Y1570600D01*
G01D02*
X847500Y1572400D01*
G01X849800Y1558400D02*
X850600Y1560700D01*
G01D02*
Y1569300D01*
G01X862800Y1559100D02*
X861300Y1559600D01*
G01D02*
X859900Y1558500D01*
G01X931900Y-1786000D02*
Y-1760400D01*
G01X919000Y-1764000D02*
Y-1776900D01*
G01D02*
X937500D01*
G01X916500Y-1749600D02*
Y-1407900D01*
G01X930400Y-1721200D02*
X934200D01*
G01X930400Y-1710900D02*
Y-1721200D01*
G01Y-1705700D02*
Y-1695400D01*
G01D02*
X934200Y-1703500D01*
G01Y-1710900D02*
X930400D01*
G01Y-1685200D02*
X935700D01*
G01X930400Y-1690200D02*
Y-1680000D01*
G01Y-1674900D02*
X934200Y-1664500D01*
G01X931300Y-1672600D02*
X937200D01*
G01X930400Y-1680000D02*
X938100D01*
G01X932000Y-1659400D02*
X936400D01*
G01X930400Y-1633700D02*
X938100D01*
G01X932000Y-1649200D02*
X936400D01*
G01X931900Y1600000D02*
Y1625700D01*
G01X919000Y1622000D02*
Y1609200D01*
G01D02*
X937500D01*
G01X934200Y-1721200D02*
X936100Y-1720500D01*
G01D02*
X937500Y-1718600D01*
G01X941000Y-1710900D02*
Y-1721200D01*
G01D02*
X948500D01*
G01X934200Y-1703500D02*
X938100Y-1695400D01*
G01D02*
Y-1705700D01*
G01X941700Y-1695400D02*
Y-1702800D01*
G01D02*
X942500Y-1704500D01*
G01D02*
X944400Y-1705600D01*
G01D02*
X946800D01*
G01D02*
X948500Y-1704500D01*
G01D02*
X949300Y-1702800D01*
G01D02*
Y-1695400D01*
G01X937500Y-1718600D02*
X938100Y-1716100D01*
G01D02*
X937500Y-1713400D01*
G01D02*
X936100Y-1711600D01*
G01D02*
X934200Y-1710900D01*
G01X941000Y-1716100D02*
X946300D01*
G01X948500Y-1710900D02*
X941000D01*
G01X941500Y-1683000D02*
Y-1688200D01*
G01Y-1687400D02*
X942200Y-1689000D01*
G01D02*
X944100Y-1690100D01*
G01D02*
X946500D01*
G01D02*
X948400Y-1689000D01*
G01D02*
X949100Y-1687400D01*
G01D02*
Y-1682200D01*
G01X934200Y-1664500D02*
X938100Y-1674900D01*
G01X949100Y-1683000D02*
X948400Y-1681200D01*
G01D02*
X946500Y-1680200D01*
G01D02*
X944100D01*
G01D02*
X942200Y-1681200D01*
G01D02*
X941500Y-1683000D01*
G01X934200Y-1649200D02*
Y-1659400D01*
G01X947100Y-1649200D02*
Y-1659400D01*
G01X934200Y-1633700D02*
Y-1644000D01*
G01X941000Y-1633700D02*
Y-1644000D01*
G01Y-1638800D02*
X948500D01*
G01Y-1633700D02*
Y-1644000D01*
G01X943200Y-1649200D02*
X950800D01*
G01X951600Y-1710900D02*
Y-1721200D01*
G01X962300D02*
X966000Y-1710900D01*
G01X953100Y-1705700D02*
X956800D01*
G01D02*
X959200Y-1705300D01*
G01D02*
X960500Y-1704000D01*
G01D02*
Y-1702300D01*
G01D02*
X959200Y-1701000D01*
G01X968200Y-1695400D02*
Y-1705700D01*
G01X951600Y-1716800D02*
X956200D01*
G01D02*
X958000Y-1716200D01*
G01D02*
X959000Y-1714700D01*
G01D02*
Y-1713000D01*
G01D02*
X958000Y-1711500D01*
G01D02*
X956200Y-1710900D01*
G01D02*
X951600D01*
G01X966000D02*
X969800Y-1721200D01*
G01X963000Y-1719000D02*
X968900D01*
G01X952500Y-1685900D02*
X957100D01*
G01D02*
X958900Y-1685300D01*
G01D02*
X960100Y-1683900D01*
G01X952500Y-1680000D02*
Y-1690200D01*
G01X960200D02*
X957100Y-1685900D01*
G01X963600Y-1690200D02*
Y-1680000D01*
G01D02*
X967400Y-1688200D01*
G01D02*
X971300Y-1680000D01*
G01X960600Y-1695400D02*
X956800D01*
G01D02*
X954600Y-1696000D01*
G01D02*
X953300Y-1697200D01*
G01D02*
Y-1698800D01*
G01D02*
X954600Y-1700100D01*
G01D02*
X956800Y-1700600D01*
G01X959200Y-1701000D02*
X956800Y-1700600D01*
G01X964500Y-1695400D02*
X972000D01*
G01X956100Y-1670400D02*
X960600D01*
G01D02*
X962400Y-1669800D01*
G01D02*
X963500Y-1668400D01*
G01D02*
Y-1666600D01*
G01X956100Y-1664500D02*
Y-1674900D01*
G01X963600D02*
X960600Y-1670400D01*
G01X960100Y-1683900D02*
Y-1682100D01*
G01D02*
X958900Y-1680600D01*
G01D02*
X957100Y-1680000D01*
G01D02*
X952500D01*
G01X959900Y-1649200D02*
X957700Y-1649600D01*
G01D02*
X956200Y-1650900D01*
G01D02*
Y-1652400D01*
G01D02*
X957700Y-1653700D01*
G01D02*
X959900Y-1654300D01*
G01X956100Y-1659400D02*
X959900D01*
G01D02*
X962100Y-1658900D01*
G01D02*
X963500Y-1657600D01*
G01D02*
Y-1656100D01*
G01D02*
X962100Y-1654800D01*
G01D02*
X959900Y-1654300D01*
G01X963500Y-1666600D02*
X962400Y-1665100D01*
G01D02*
X960600Y-1664500D01*
G01D02*
X956100D01*
G01X953100Y-1633700D02*
X957700D01*
G01X955300D02*
Y-1644000D01*
G01X953100D02*
X957700D01*
G01X969800Y-1633700D02*
X966000D01*
G01D02*
X963700Y-1634100D01*
G01D02*
X962400Y-1635400D01*
G01D02*
Y-1637100D01*
G01D02*
X963700Y-1638400D01*
G01D02*
X966000Y-1638800D01*
G01X962300Y-1644000D02*
X966000D01*
G01D02*
X968200Y-1643400D01*
G01D02*
X969700Y-1642200D01*
G01Y-1640600D02*
X968200Y-1639300D01*
G01D02*
X966000Y-1638800D01*
G01X963600Y-1649200D02*
X959900D01*
G01X972800Y-1710900D02*
Y-1721200D01*
G01X980400D02*
X977300Y-1716800D01*
G01X972800D02*
X977300D01*
G01D02*
X979100Y-1716200D01*
G01D02*
X980300Y-1714700D01*
G01D02*
Y-1713000D01*
G01D02*
X979100Y-1711500D01*
G01D02*
X977300Y-1710900D01*
G01D02*
X972800D01*
G01X983400D02*
X990900D01*
G01X971300Y-1680000D02*
Y-1690200D01*
G01X974700D02*
X978500Y-1680000D01*
G01D02*
X982400Y-1690200D01*
G01X975600Y-1688200D02*
X981500D01*
G01X968900Y-1669700D02*
X974200D01*
G01X968900Y-1664500D02*
Y-1674900D01*
G01D02*
X976400D01*
G01X982500Y-1665700D02*
X981800Y-1667500D01*
G01D02*
Y-1671900D01*
G01D02*
X982500Y-1673700D01*
G01D02*
X984400Y-1674700D01*
G01D02*
X986600D01*
G01X985500Y-1671200D02*
X990000Y-1675600D01*
G01X981800Y-1649200D02*
Y-1656400D01*
G01D02*
X982500Y-1658200D01*
G01D02*
X984400Y-1659200D01*
G01D02*
X986600D01*
G01X976400Y-1664500D02*
X968900D01*
G01X986600Y-1664700D02*
X984400D01*
G01D02*
X982500Y-1665700D01*
G01X969700Y-1642200D02*
Y-1640600D01*
G01X983400Y-1644000D02*
X987200D01*
G01Y-1633700D02*
X983400D01*
G01D02*
Y-1644000D01*
G01X987200Y-1710900D02*
Y-1721200D01*
G01X994000D02*
Y-1710900D01*
G01X1001500D02*
Y-1721200D01*
G01X987100Y-1695400D02*
Y-1705700D01*
G01D02*
X990900D01*
G01D02*
X993100Y-1705100D01*
G01D02*
X994500Y-1703700D01*
G01D02*
Y-1701900D01*
G01D02*
X993100Y-1700400D01*
G01X998400Y-1695400D02*
Y-1705700D01*
G01D02*
X1006000D01*
G01X994000Y-1710900D02*
X997900Y-1719000D01*
G01D02*
X1001500Y-1710900D01*
G01X986600Y-1690200D02*
Y-1680000D01*
G01D02*
X992700Y-1690200D01*
G01D02*
Y-1680000D01*
G01X997000Y-1682200D02*
Y-1688200D01*
G01D02*
X997400Y-1689200D01*
G01D02*
X998700Y-1689900D01*
G01D02*
X1000700Y-1690200D01*
G01D02*
X1004500D01*
G01X993100Y-1700400D02*
X990900Y-1699800D01*
G01D02*
X987100D01*
G01X990900D02*
X992700Y-1699400D01*
G01D02*
X993700Y-1698300D01*
G01D02*
Y-1697000D01*
G01D02*
X992700Y-1695800D01*
G01D02*
X990900Y-1695400D01*
G01D02*
X987100D01*
G01X998400Y-1700600D02*
X1003800D01*
G01X1006000Y-1695400D02*
X998400D01*
G01X989300Y-1667500D02*
X988600Y-1665700D01*
G01X986600Y-1674700D02*
X988600Y-1673700D01*
G01D02*
X989300Y-1671900D01*
G01D02*
Y-1667500D01*
G01X994600Y-1664500D02*
Y-1671900D01*
G01D02*
X995300Y-1673700D01*
G01D02*
X997100Y-1674700D01*
G01D02*
X999500D01*
G01D02*
X1001400Y-1673700D01*
G01D02*
X1002100Y-1671900D01*
G01D02*
Y-1664500D01*
G01X1004500Y-1680000D02*
X1000700D01*
G01D02*
X998700Y-1680300D01*
G01D02*
X997400Y-1681100D01*
G01D02*
X997000Y-1682200D01*
G01X986600Y-1659200D02*
X988600Y-1658200D01*
G01D02*
X989300Y-1656400D01*
G01D02*
Y-1649200D01*
G01X998300D02*
X996100Y-1649600D01*
G01D02*
X994800Y-1650900D01*
G01D02*
Y-1652400D01*
G01D02*
X996100Y-1653700D01*
G01D02*
X998300Y-1654300D01*
G01X994600Y-1659400D02*
X998300D01*
G01D02*
X1000500Y-1658900D01*
G01D02*
X1002000Y-1657600D01*
G01D02*
Y-1656100D01*
G01D02*
X1000500Y-1654800D01*
G01D02*
X998300Y-1654300D01*
G01X988600Y-1665700D02*
X986600Y-1664700D01*
G01X987200Y-1644000D02*
X989100Y-1643300D01*
G01D02*
X990500Y-1641300D01*
G01D02*
X990900Y-1638800D01*
G01D02*
X990500Y-1636300D01*
G01D02*
X989100Y-1634400D01*
G01D02*
X987200Y-1633700D01*
G01X1001500Y-1636600D02*
X1000800Y-1634800D01*
G01D02*
X998900Y-1633800D01*
G01D02*
X996700D01*
G01D02*
X994800Y-1634800D01*
G01D02*
X994000Y-1636600D01*
G01D02*
Y-1641800D01*
G01Y-1641000D02*
X994800Y-1642800D01*
G01D02*
X996700Y-1643900D01*
G01D02*
X998900D01*
G01D02*
X1000800Y-1642800D01*
G01D02*
X1001500Y-1641000D01*
G01D02*
Y-1635900D01*
G01X1002100Y-1649200D02*
X998300D01*
G01X989300Y-1507900D02*
X1084500D01*
G01X989300Y-1416200D02*
Y-1507900D01*
G01X1001100Y-1477000D02*
X1001500Y-1480400D01*
G01D02*
X1002600Y-1483500D01*
G01D02*
X1004400Y-1486500D01*
G01X1001100Y-1477000D02*
X1011700D01*
G01X1001800Y-1455200D02*
X1002900Y-1458400D01*
G01D02*
X1004600Y-1461200D01*
G01X1004900Y-1437600D02*
X1003200Y-1440400D01*
G01D02*
X1002000Y-1443500D01*
G01D02*
X1001700Y-1446700D01*
G01X1001500Y-1451800D02*
X1001800Y-1455200D01*
G01X1001500Y-1451800D02*
X1001700Y-1446700D01*
G01X1084500Y-1416200D02*
X989300D01*
G01X1004600Y-1710900D02*
Y-1721200D01*
G01D02*
X1012200D01*
G01X1016000D02*
Y-1710900D01*
G01D02*
X1022100Y-1721200D01*
G01X1004600Y-1716100D02*
X1010000D01*
G01X1012200Y-1710900D02*
X1004600D01*
G01X1008000Y-1685200D02*
X1013200D01*
G01X1008000Y-1680000D02*
Y-1690200D01*
G01D02*
X1015600D01*
G01X1007500Y-1669700D02*
X1012600D01*
G01X1007500Y-1664500D02*
Y-1674900D01*
G01D02*
X1015000D01*
G01X1020400Y-1666300D02*
Y-1667900D01*
G01D02*
X1021800Y-1669300D01*
G01X1020200Y-1674900D02*
X1024000D01*
G01X1015600Y-1680000D02*
X1008000D01*
G01X1007500Y-1654300D02*
X1012600D01*
G01X1007500Y-1649200D02*
Y-1659400D01*
G01D02*
X1015000D01*
G01Y-1664500D02*
X1007500D01*
G01X1021800Y-1665100D02*
X1020400Y-1666300D01*
G01X1012200Y-1633700D02*
X1008300D01*
G01D02*
X1006400Y-1634000D01*
G01D02*
X1005100Y-1634800D01*
G01D02*
X1004600Y-1635900D01*
G01D02*
Y-1641800D01*
G01D02*
X1005100Y-1642800D01*
G01D02*
X1006400Y-1643700D01*
G01D02*
X1008300Y-1644000D01*
G01D02*
X1012200D01*
G01X1015100Y-1633700D02*
Y-1641000D01*
G01D02*
X1015900Y-1642800D01*
G01D02*
X1017800Y-1643900D01*
G01D02*
X1020200D01*
G01D02*
X1022100Y-1642800D01*
G01X1015000Y-1649200D02*
X1007500D01*
G01X1016000Y-1492100D02*
X1039500D01*
G01X1016000Y-1481400D02*
X1039900D01*
G01X1011700Y-1477000D02*
X1012000Y-1478800D01*
G01D02*
X1012900Y-1480100D01*
G01D02*
X1014400Y-1481100D01*
G01D02*
X1016000Y-1481400D01*
G01X1004400Y-1486500D02*
X1006700Y-1488800D01*
G01D02*
X1009700Y-1490600D01*
G01D02*
X1012800Y-1491600D01*
G01D02*
X1016000Y-1492100D01*
G01X1016500Y-1467000D02*
X1039500D01*
G01X1004600Y-1461200D02*
X1007000Y-1463600D01*
G01D02*
X1010000Y-1465500D01*
G01D02*
X1013100Y-1466500D01*
G01D02*
X1016500Y-1467000D01*
G01Y-1456800D02*
X1039500D01*
G01X1016500Y-1442200D02*
X1039600D01*
G01X1016500D02*
X1014700Y-1442500D01*
G01D02*
X1013100Y-1443500D01*
G01D02*
X1012000Y-1445100D01*
G01D02*
X1011700Y-1446900D01*
G01Y-1452100D02*
Y-1446900D01*
G01Y-1452100D02*
X1012000Y-1453800D01*
G01D02*
X1013100Y-1455400D01*
G01D02*
X1014700Y-1456500D01*
G01D02*
X1016500Y-1456800D01*
G01X1016600Y-1432100D02*
X1041900D01*
G01X1016600D02*
X1013400Y-1432400D01*
G01D02*
X1010100Y-1433600D01*
G01D02*
X1007300Y-1435200D01*
G01D02*
X1004900Y-1437600D01*
G01X1022100Y-1721200D02*
Y-1710900D01*
G01X1029600D02*
Y-1721200D01*
G01X1021000Y-1695400D02*
Y-1705700D01*
G01X1028700D02*
X1025600Y-1701300D01*
G01X1032400Y-1695400D02*
Y-1705700D01*
G01D02*
X1039900D01*
G01X1025800Y-1710900D02*
X1033300D01*
G01X1030200Y-1683000D02*
Y-1688200D01*
G01Y-1687400D02*
X1030800Y-1689000D01*
G01D02*
X1032700Y-1690100D01*
G01D02*
X1035100D01*
G01D02*
X1037000Y-1689000D01*
G01D02*
X1037700Y-1687400D01*
G01D02*
Y-1682200D01*
G01X1021000Y-1701300D02*
X1025600D01*
G01D02*
X1027400Y-1700700D01*
G01D02*
X1028600Y-1699200D01*
G01D02*
Y-1697500D01*
G01D02*
X1027400Y-1696000D01*
G01D02*
X1025600Y-1695400D01*
G01D02*
X1021000D01*
G01X1032400Y-1700600D02*
X1037700D01*
G01X1039900Y-1695400D02*
X1032400D01*
G01X1021800Y-1669300D02*
X1024000Y-1669700D01*
G01Y-1674900D02*
X1026200Y-1674400D01*
G01D02*
X1027500Y-1673100D01*
G01D02*
Y-1671500D01*
G01D02*
X1026200Y-1670100D01*
G01D02*
X1024000Y-1669700D01*
G01X1036800Y-1664500D02*
Y-1674900D01*
G01X1037700Y-1683000D02*
X1037000Y-1681200D01*
G01D02*
X1035100Y-1680200D01*
G01D02*
X1032700D01*
G01D02*
X1030800Y-1681200D01*
G01D02*
X1030200Y-1683000D01*
G01X1036800Y-1649200D02*
Y-1659400D01*
G01X1034600D02*
X1039100D01*
G01X1027800Y-1664500D02*
X1024000D01*
G01D02*
X1021800Y-1665100D01*
G01X1033000Y-1664500D02*
X1040700D01*
G01X1022100Y-1642800D02*
X1022800Y-1641000D01*
G01D02*
Y-1633700D01*
G01X1025800Y-1644000D02*
Y-1633700D01*
G01D02*
X1029600Y-1641800D01*
G01D02*
X1033300Y-1633700D01*
G01D02*
Y-1644000D01*
G01X1036400Y-1638800D02*
X1041700D01*
G01X1043900Y-1633700D02*
X1036400D01*
G01D02*
Y-1644000D01*
G01D02*
X1043900D01*
G01X1034600Y-1649200D02*
X1039100D01*
G01X1025000Y1379100D02*
Y1589100D01*
G01X1041300Y-1720000D02*
X1040700Y-1719200D01*
G01D02*
X1039600D01*
G01D02*
X1039100Y-1720000D01*
G01D02*
X1039600Y-1721100D01*
G01D02*
X1040700D01*
G01D02*
X1041300Y-1720000D01*
G01X1043800Y-1705700D02*
Y-1695400D01*
G01X1055100D02*
Y-1705700D01*
G01D02*
X1062700D01*
G01X1041300Y-1685200D02*
X1046400D01*
G01X1041300Y-1690200D02*
Y-1680000D01*
G01X1043800Y-1700600D02*
X1049100D01*
G01X1043800Y-1695400D02*
X1051300D01*
G01X1055100Y-1700600D02*
X1060500D01*
G01X1062700Y-1695400D02*
X1055100D01*
G01X1041300Y-1680000D02*
X1048800D01*
G01X1049700Y-1649200D02*
X1047500Y-1649600D01*
G01D02*
X1046000Y-1650900D01*
G01D02*
Y-1652400D01*
G01D02*
X1047500Y-1653700D01*
G01D02*
X1049700Y-1654300D01*
G01X1045800Y-1659400D02*
X1049700D01*
G01D02*
X1051900Y-1658900D01*
G01D02*
X1053200Y-1657600D01*
G01D02*
Y-1656100D01*
G01D02*
X1051900Y-1654800D01*
G01D02*
X1049700Y-1654300D01*
G01X1047800Y-1644000D02*
Y-1633700D01*
G01D02*
X1053800Y-1644000D01*
G01D02*
Y-1633700D01*
G01X1053400Y-1649200D02*
X1049700D01*
G01X1054600Y-1471700D02*
Y-1477000D01*
G01X1044400Y-1471700D02*
Y-1477000D01*
G01X1039500Y-1492100D02*
X1042900Y-1491600D01*
G01D02*
X1046000Y-1490600D01*
G01D02*
X1048900Y-1488800D01*
G01D02*
X1051300Y-1486500D01*
G01D02*
X1053100Y-1483500D01*
G01D02*
X1054100Y-1480400D01*
G01D02*
X1054600Y-1477000D01*
G01X1039900Y-1481400D02*
X1041700Y-1481100D01*
G01D02*
X1043000Y-1480100D01*
G01D02*
X1044100Y-1478800D01*
G01D02*
X1044400Y-1477000D01*
G01X1054600Y-1471700D02*
X1054100Y-1468400D01*
G01D02*
X1053100Y-1465200D01*
G01D02*
X1051300Y-1462400D01*
G01D02*
X1048900Y-1460000D01*
G01D02*
X1046000Y-1458300D01*
G01D02*
X1042900Y-1457200D01*
G01X1044400Y-1471700D02*
X1044100Y-1469900D01*
G01D02*
X1042900Y-1468300D01*
G01D02*
X1041400Y-1467300D01*
G01D02*
X1039500Y-1467000D01*
G01X1044500Y-1449000D02*
X1054600D01*
G01Y-1444800D02*
Y-1449000D01*
G01Y-1444800D02*
X1053700Y-1441700D01*
G01D02*
X1052300Y-1438800D01*
G01X1044500Y-1446900D02*
X1044100Y-1445100D01*
G01D02*
X1043000Y-1443500D01*
G01D02*
X1041600Y-1442500D01*
G01D02*
X1039600Y-1442200D01*
G01X1044500Y-1446900D02*
Y-1449000D01*
G01X1042900Y-1457200D02*
X1039500Y-1456800D01*
G01X1052300Y-1438800D02*
X1050300Y-1436300D01*
G01D02*
X1047800Y-1434300D01*
G01D02*
X1045000Y-1432900D01*
G01D02*
X1041900Y-1432100D01*
G01X1066500Y-1695400D02*
Y-1705700D01*
G01X1074000D02*
X1070900Y-1701300D01*
G01X1063400Y-1680000D02*
X1064200Y-1690200D01*
G01D02*
X1067100Y-1682200D01*
G01D02*
X1070200Y-1690200D01*
G01D02*
X1070900Y-1680000D01*
G01X1066500Y-1701300D02*
X1070900D01*
G01D02*
X1072700Y-1700700D01*
G01D02*
X1073900Y-1699200D01*
G01Y-1697500D02*
X1072700Y-1696000D01*
G01D02*
X1070900Y-1695400D01*
G01D02*
X1066500D01*
G01X1058700Y-1669700D02*
X1064000D01*
G01X1058700Y-1674900D02*
Y-1664500D01*
G01X1072300Y-1665700D02*
X1071500Y-1667500D01*
G01D02*
Y-1672600D01*
G01Y-1671900D02*
X1072300Y-1673700D01*
G01D02*
X1074200Y-1674700D01*
G01X1071500Y-1659400D02*
X1075400Y-1649200D01*
G01X1072300Y-1657100D02*
X1078300D01*
G01X1058700Y-1664500D02*
X1066200D01*
G01X1074200Y-1664700D02*
X1072300Y-1665700D01*
G01X1057500Y-1633700D02*
X1065200D01*
G01X1061300D02*
Y-1644000D01*
G01X1061600Y-1492100D02*
X1072100D01*
G01X1061600Y-1432100D02*
Y-1492100D01*
G01X1072100D02*
Y-1432100D01*
G01D02*
X1061600D01*
G01X1077700Y-1695400D02*
Y-1705700D01*
G01X1085400D02*
X1082300Y-1701300D01*
G01X1089100Y-1695400D02*
Y-1705700D01*
G01D02*
X1096600D01*
G01X1074500Y-1683000D02*
Y-1688200D01*
G01Y-1687400D02*
X1075200Y-1689000D01*
G01D02*
X1077000Y-1690100D01*
G01D02*
X1079400D01*
G01D02*
X1081300Y-1689000D01*
G01D02*
X1082000Y-1687400D01*
G01D02*
Y-1682200D01*
G01X1085600Y-1685900D02*
X1090000D01*
G01D02*
X1091900Y-1685300D01*
G01X1085600Y-1680000D02*
Y-1690200D01*
G01X1093100D02*
X1090000Y-1685900D01*
G01X1073900Y-1699200D02*
Y-1697500D01*
G01X1077700Y-1701300D02*
X1082300D01*
G01D02*
X1084100Y-1700700D01*
G01D02*
X1085300Y-1699200D01*
G01D02*
Y-1697500D01*
G01D02*
X1084100Y-1696000D01*
G01D02*
X1082300Y-1695400D01*
G01D02*
X1077700D01*
G01X1089100Y-1700600D02*
X1094400D01*
G01X1096600Y-1695400D02*
X1089100D01*
G01X1079100Y-1667500D02*
X1078300Y-1665700D01*
G01X1074200Y-1674700D02*
X1076400D01*
G01D02*
X1078300Y-1673700D01*
G01D02*
X1079100Y-1671900D01*
G01D02*
Y-1666700D01*
G01X1084400Y-1670400D02*
X1089000D01*
G01D02*
X1090700Y-1669800D01*
G01D02*
X1091800Y-1668400D01*
G01X1084400Y-1664500D02*
Y-1674900D01*
G01X1091900D02*
X1089000Y-1670400D01*
G01X1082000Y-1683000D02*
X1081300Y-1681200D01*
G01D02*
X1079400Y-1680200D01*
G01D02*
X1077000D01*
G01D02*
X1075200Y-1681200D01*
G01D02*
X1074500Y-1683000D01*
G01X1091900Y-1680600D02*
X1090000Y-1680000D01*
G01D02*
X1085600D01*
G01X1075400Y-1649200D02*
X1079100Y-1659400D01*
G01X1084400Y-1649200D02*
Y-1656400D01*
G01D02*
X1085100Y-1658200D01*
G01D02*
X1087000Y-1659200D01*
G01D02*
X1089300D01*
G01D02*
X1091200Y-1658200D01*
G01X1078300Y-1665700D02*
X1076400Y-1664700D01*
G01D02*
X1074200D01*
G01X1091800Y-1666600D02*
X1090700Y-1665100D01*
G01D02*
X1089000Y-1664500D01*
G01D02*
X1084400D01*
G01X1080200Y-1633700D02*
X1084800D01*
G01X1082600D02*
Y-1644000D01*
G01X1080200D02*
X1084800D01*
G01X1090900Y-1634100D02*
X1089600Y-1635400D01*
G01D02*
Y-1637100D01*
G01D02*
X1090900Y-1638400D01*
G01X1089400Y-1644000D02*
X1093100D01*
G01X1084500Y-1507900D02*
Y-1416200D01*
G01X1100500Y-1705700D02*
X1104200D01*
G01D02*
X1106100Y-1705000D01*
G01D02*
X1107600Y-1703200D01*
G01D02*
X1108000Y-1700600D01*
G01X1100500Y-1695400D02*
Y-1705700D01*
G01X1091900Y-1685300D02*
X1092900Y-1683900D01*
G01X1096600Y-1680000D02*
Y-1690200D01*
G01Y-1685900D02*
X1104200Y-1680000D01*
G01X1099100Y-1683900D02*
X1104200Y-1690200D01*
G01X1108000Y-1700600D02*
X1107600Y-1698000D01*
G01D02*
X1106100Y-1696100D01*
G01D02*
X1104200Y-1695400D01*
G01D02*
X1100500D01*
G01X1091800Y-1668400D02*
Y-1666600D01*
G01X1092900Y-1683900D02*
Y-1682100D01*
G01D02*
X1091900Y-1680600D01*
G01X1091200Y-1658200D02*
X1091900Y-1656400D01*
G01D02*
Y-1649200D01*
G01X1100900D02*
Y-1659400D01*
G01X1096900Y-1633700D02*
X1093100D01*
G01D02*
X1090900Y-1634100D01*
G01Y-1638400D02*
X1093100Y-1638800D01*
G01Y-1644000D02*
X1095300Y-1643400D01*
G01D02*
X1096800Y-1642200D01*
G01D02*
Y-1640600D01*
G01D02*
X1095300Y-1639300D01*
G01D02*
X1093100Y-1638800D01*
G01X1097200Y-1649200D02*
X1104800D01*
G01X1099000Y1589100D02*
Y1379100D01*
G01X1118800Y-1685200D02*
X1124100D01*
G01X1118800Y-1690200D02*
Y-1680000D01*
G01X1123100Y-1695400D02*
X1130700D01*
G01X1117600Y-1667500D02*
X1116900Y-1665700D01*
G01X1110700D02*
X1110100Y-1667500D01*
G01D02*
Y-1671900D01*
G01D02*
X1110700Y-1673700D01*
G01D02*
X1112600Y-1674700D01*
G01D02*
X1114900D01*
G01D02*
X1116900Y-1673700D01*
G01D02*
X1117600Y-1671900D01*
G01D02*
Y-1667500D01*
G01X1113800Y-1671200D02*
X1118300Y-1675600D01*
G01X1122800Y-1664500D02*
Y-1671900D01*
G01D02*
X1123500Y-1673700D01*
G01D02*
X1125400Y-1674700D01*
G01D02*
X1127800D01*
G01X1118800Y-1680000D02*
X1126300D01*
G01X1110100Y-1649200D02*
Y-1659400D01*
G01Y-1654300D02*
X1117600D01*
G01Y-1649200D02*
Y-1659400D01*
G01X1125400Y-1649300D02*
X1123500Y-1650400D01*
G01D02*
X1122800Y-1652100D01*
G01D02*
Y-1657100D01*
G01Y-1656400D02*
X1123500Y-1658200D01*
G01D02*
X1125400Y-1659200D01*
G01D02*
X1127800D01*
G01X1116900Y-1665700D02*
X1114900Y-1664700D01*
G01D02*
X1112600D01*
G01D02*
X1110700Y-1665700D01*
G01X1110500Y-1633700D02*
X1118200D01*
G01X1114400D02*
Y-1644000D01*
G01X1121100Y-1633700D02*
Y-1644000D01*
G01Y-1638800D02*
X1128700D01*
G01X1127800Y-1649300D02*
X1125400D01*
G01X1109300Y1555900D02*
X1115500D01*
G01D02*
X1118200Y1556700D01*
G01D02*
X1120300Y1559100D01*
G01X1109300Y1573000D02*
Y1555900D01*
G01X1120300Y1559100D02*
X1121400Y1562500D01*
G01D02*
Y1566300D01*
G01D02*
X1120300Y1569700D01*
G01D02*
X1118200Y1572100D01*
G01D02*
X1115500Y1573000D01*
G01D02*
X1109300D01*
G01X1126900Y-1695400D02*
Y-1705700D01*
G01X1134400Y-1698300D02*
Y-1703500D01*
G01Y-1702800D02*
X1135200Y-1704500D01*
G01D02*
X1137100Y-1705600D01*
G01D02*
X1139500D01*
G01D02*
X1141400Y-1704500D01*
G01D02*
X1142000Y-1702800D01*
G01D02*
Y-1697600D01*
G01X1129900Y-1683000D02*
Y-1688200D01*
G01Y-1687400D02*
X1130600Y-1689000D01*
G01D02*
X1132500Y-1690100D01*
G01D02*
X1134700D01*
G01D02*
X1136700Y-1689000D01*
G01D02*
X1137400Y-1687400D01*
G01D02*
Y-1682200D01*
G01X1140900Y-1685900D02*
X1145500D01*
G01X1140900Y-1680000D02*
Y-1690200D01*
G01X1142000Y-1698300D02*
X1141400Y-1696700D01*
G01D02*
X1139500Y-1695500D01*
G01D02*
X1137100D01*
G01D02*
X1135200Y-1696700D01*
G01D02*
X1134400Y-1698300D01*
G01X1127800Y-1674700D02*
X1129700Y-1673700D01*
G01D02*
X1130500Y-1671900D01*
G01D02*
Y-1664500D01*
G01X1136400Y-1665700D02*
X1135600Y-1667500D01*
G01D02*
Y-1672600D01*
G01Y-1671900D02*
X1136400Y-1673700D01*
G01D02*
X1138300Y-1674700D01*
G01D02*
X1140600D01*
G01D02*
X1142600Y-1673700D01*
G01D02*
X1143300Y-1671900D01*
G01X1137400Y-1683000D02*
X1136700Y-1681200D01*
G01D02*
X1134700Y-1680200D01*
G01D02*
X1132500D01*
G01D02*
X1130600Y-1681200D01*
G01D02*
X1129900Y-1683000D01*
G01X1145500Y-1680000D02*
X1140900D01*
G01X1130500Y-1652100D02*
X1129700Y-1650400D01*
G01D02*
X1127800Y-1649300D01*
G01Y-1659200D02*
X1129700Y-1658200D01*
G01D02*
X1130500Y-1656400D01*
G01D02*
Y-1651400D01*
G01X1135600Y-1654900D02*
X1140200D01*
G01D02*
X1142000Y-1654500D01*
G01D02*
X1143200Y-1653000D01*
G01Y-1651100D02*
X1142000Y-1649600D01*
G01D02*
X1140200Y-1649200D01*
G01X1135600D02*
Y-1659400D01*
G01X1143300D02*
X1140200Y-1654900D01*
G01X1143300Y-1667500D02*
X1142600Y-1665700D01*
G01D02*
X1140600Y-1664700D01*
G01D02*
X1138300D01*
G01D02*
X1136400Y-1665700D01*
G01X1128700Y-1633700D02*
Y-1644000D01*
G01X1131800Y-1638800D02*
X1137100D01*
G01X1139300Y-1633700D02*
X1131800D01*
G01D02*
Y-1644000D01*
G01D02*
X1139300D01*
G01X1140200Y-1649200D02*
X1135600D01*
G01X1126600Y1555900D02*
X1132700Y1573000D01*
G01D02*
X1138900Y1555900D01*
G01X1127800Y1559600D02*
X1137500D01*
G01X1154700Y-1755800D02*
Y-1788700D01*
G01X1145500Y-1685900D02*
X1147300Y-1685300D01*
G01D02*
X1148300Y-1683900D01*
G01X1148500Y-1690200D02*
X1145500Y-1685900D01*
G01X1157200Y-1695400D02*
X1164700D01*
G01X1143300Y-1671900D02*
Y-1666700D01*
G01X1152300Y-1664500D02*
Y-1674900D01*
G01X1148300Y-1683900D02*
Y-1682100D01*
G01D02*
X1147300Y-1680600D01*
G01D02*
X1145500Y-1680000D01*
G01X1143200Y-1653000D02*
Y-1651100D01*
G01X1152300Y-1649200D02*
Y-1659400D01*
G01X1149900D02*
X1154500D01*
G01X1148500Y-1664500D02*
X1156000D01*
G01X1152900Y-1639600D02*
X1157500D01*
G01D02*
X1159200Y-1639000D01*
G01D02*
X1160400Y-1637500D01*
G01D02*
Y-1635700D01*
G01D02*
X1159200Y-1634300D01*
G01D02*
X1157500Y-1633700D01*
G01D02*
X1152900D01*
G01D02*
Y-1644000D01*
G01X1149900Y-1649200D02*
X1154500D01*
G01X1159400Y-1407900D02*
Y-1619900D01*
G01X1435200Y-1453100D02*
X1159400D01*
G01X1149800Y1573000D02*
Y1555900D01*
G01X1143700Y1573000D02*
X1156000D01*
G01X1154700Y1628200D02*
Y1595300D01*
G01X1160900Y-1695400D02*
Y-1705700D01*
G01X1168400Y-1695400D02*
Y-1705700D01*
G01X1176100Y-1695400D02*
Y-1705700D01*
G01X1163100Y-1682200D02*
Y-1688200D01*
G01D02*
X1163500Y-1689200D01*
G01D02*
X1165000Y-1689900D01*
G01D02*
X1166900Y-1690200D01*
G01D02*
X1170600D01*
G01X1174200Y-1685200D02*
X1179500D01*
G01X1174200Y-1680000D02*
Y-1690200D01*
G01D02*
X1181700D01*
G01X1168400Y-1700600D02*
X1176100D01*
G01X1161300Y-1674900D02*
X1165200Y-1664500D01*
G01D02*
X1168800Y-1674900D01*
G01X1162200Y-1672600D02*
X1168100D01*
G01X1170600Y-1680000D02*
X1166900D01*
G01D02*
X1165000Y-1680300D01*
G01D02*
X1163500Y-1681100D01*
G01D02*
X1163100Y-1682200D01*
G01X1181700Y-1680000D02*
X1174200D01*
G01X1168800Y-1649200D02*
X1161300Y-1659400D01*
G01D02*
X1168800D01*
G01X1174200Y-1654300D02*
X1179500D01*
G01X1174200Y-1649200D02*
Y-1659400D01*
G01D02*
X1181700D01*
G01X1174200Y-1664500D02*
X1181700D01*
G01X1163500Y-1639600D02*
X1168100D01*
G01D02*
X1169900Y-1639000D01*
G01D02*
X1170900Y-1637500D01*
G01D02*
Y-1635700D01*
G01D02*
X1169900Y-1634300D01*
G01D02*
X1168100Y-1633700D01*
G01D02*
X1163500D01*
G01D02*
Y-1644000D01*
G01X1171100D02*
X1168100Y-1639600D01*
G01X1179000Y-1633800D02*
X1176800D01*
G01D02*
X1174900Y-1634800D01*
G01D02*
X1174200Y-1636600D01*
G01D02*
Y-1641800D01*
G01Y-1641000D02*
X1174900Y-1642800D01*
G01D02*
X1176800Y-1643900D01*
G01D02*
X1179000D01*
G01X1161300Y-1649200D02*
X1168800D01*
G01X1181700D02*
X1174200D01*
G01X1175800Y-1422800D02*
X1173100Y-1423400D01*
G01D02*
X1171100Y-1424700D01*
G01D02*
X1170500Y-1426700D01*
G01D02*
X1171100Y-1428600D01*
G01D02*
X1173100Y-1430100D01*
G01D02*
X1175800Y-1430500D01*
G01X1170500Y-1438200D02*
X1175800D01*
G01D02*
X1178600Y-1437600D01*
G01Y-1430900D02*
X1175800Y-1430500D01*
G01X1181200Y-1422800D02*
X1175800D01*
G01X1160900Y1573000D02*
Y1555900D01*
G01D02*
X1173100D01*
G01X1160900Y1564400D02*
X1169400D01*
G01X1173100Y1573000D02*
X1160900D01*
G01X1179800Y-1695400D02*
Y-1705700D01*
G01D02*
X1187300D01*
G01X1185200Y-1680000D02*
Y-1690200D01*
G01D02*
X1192800D01*
G01X1179800Y-1700600D02*
X1185100D01*
G01X1187300Y-1695400D02*
X1179800D01*
G01X1178000Y-1664500D02*
Y-1674900D01*
G01X1190700Y-1664500D02*
Y-1674900D01*
G01X1188500D02*
X1193100D01*
G01X1187000Y-1659400D02*
X1190700D01*
G01D02*
X1192600Y-1658800D01*
G01D02*
X1194100Y-1656800D01*
G01D02*
X1194500Y-1654300D01*
G01D02*
X1194100Y-1651700D01*
G01D02*
X1192600Y-1649800D01*
G01D02*
X1190700Y-1649200D01*
G01X1187000D02*
Y-1659400D01*
G01X1188500Y-1664500D02*
X1193100D01*
G01X1181700Y-1636600D02*
X1180900Y-1634800D01*
G01D02*
X1179000Y-1633800D01*
G01Y-1643900D02*
X1180900Y-1642800D01*
G01D02*
X1181700Y-1641000D01*
G01D02*
Y-1635900D01*
G01X1184800Y-1639600D02*
X1189200D01*
G01D02*
X1191000Y-1639000D01*
G01D02*
X1192200Y-1637500D01*
G01D02*
Y-1635700D01*
G01D02*
X1191000Y-1634300D01*
G01D02*
X1189200Y-1633700D01*
G01D02*
X1184800D01*
G01D02*
Y-1644000D01*
G01X1190700Y-1649200D02*
X1187000D01*
G01X1184800Y-1527500D02*
X1192200D01*
G01X1188500D02*
Y-1537800D01*
G01X1195100Y-1527500D02*
Y-1537800D01*
G01Y-1532700D02*
X1202500D01*
G01X1178600Y-1437600D02*
X1180500Y-1436300D01*
G01D02*
X1181200Y-1434300D01*
G01D02*
X1180500Y-1432400D01*
G01D02*
X1178600Y-1430900D01*
G01X1191100Y-1422800D02*
X1188900Y-1423100D01*
G01D02*
X1187300Y-1423900D01*
G01D02*
X1186100Y-1424900D01*
G01D02*
X1185700Y-1426200D01*
G01D02*
Y-1434900D01*
G01D02*
X1186100Y-1436100D01*
G01D02*
X1187300Y-1437100D01*
G01D02*
X1188900Y-1437900D01*
G01D02*
X1191100Y-1438200D01*
G01D02*
X1196500D01*
G01Y-1422800D02*
X1191100D01*
G01X1202500Y-1697600D02*
Y-1703500D01*
G01D02*
X1203000Y-1704700D01*
G01D02*
X1204400Y-1705400D01*
G01D02*
X1206200Y-1705700D01*
G01D02*
X1210000D01*
G01X1196300Y-1685200D02*
X1201600D01*
G01X1196300Y-1680000D02*
Y-1690200D01*
G01D02*
X1203800D01*
G01X1207500Y-1683400D02*
X1209000Y-1684600D01*
G01D02*
X1211200Y-1685200D01*
G01X1207400Y-1690200D02*
X1211200D01*
G01D02*
X1213400Y-1689800D01*
G01Y-1685600D02*
X1211200Y-1685200D01*
G01X1210000Y-1695400D02*
X1206200D01*
G01D02*
X1204400Y-1695700D01*
G01D02*
X1203000Y-1696600D01*
G01D02*
X1202500Y-1697600D01*
G01X1207400Y-1667500D02*
X1206600Y-1665700D01*
G01X1200600D02*
X1199800Y-1667500D01*
G01D02*
Y-1672600D01*
G01Y-1671900D02*
X1200600Y-1673700D01*
G01D02*
X1202400Y-1674700D01*
G01D02*
X1204700D01*
G01D02*
X1206600Y-1673700D01*
G01D02*
X1207400Y-1671900D01*
G01D02*
Y-1666700D01*
G01X1203800Y-1680000D02*
X1196300D01*
G01X1214900D02*
X1211200D01*
G01D02*
X1209000Y-1680500D01*
G01D02*
X1207500Y-1681800D01*
G01D02*
Y-1683400D01*
G01X1212700Y-1654300D02*
X1217900D01*
G01X1212700Y-1659400D02*
Y-1649200D01*
G01X1206600Y-1665700D02*
X1204700Y-1664700D01*
G01D02*
X1202400D01*
G01D02*
X1200600Y-1665700D01*
G01X1195300Y-1638800D02*
X1200600D01*
G01X1203000Y-1633700D02*
X1195300D01*
G01D02*
Y-1644000D01*
G01D02*
X1203000D01*
G01X1205900Y-1639600D02*
X1210500D01*
G01D02*
X1212300Y-1639000D01*
G01D02*
X1213300Y-1637500D01*
G01Y-1635700D02*
X1212300Y-1634300D01*
G01D02*
X1210500Y-1633700D01*
G01D02*
X1205900D01*
G01D02*
Y-1644000D01*
G01X1213400D02*
X1210500Y-1639600D01*
G01X1212700Y-1649200D02*
X1220200D01*
G01X1202500Y-1527500D02*
Y-1537800D01*
G01X1206900Y-1527500D02*
X1211400D01*
G01X1209200D02*
Y-1537800D01*
G01X1206900D02*
X1211400D01*
G01X1200900Y-1438200D02*
X1206300Y-1422800D01*
G01D02*
X1211800Y-1438200D01*
G01X1202100Y-1434900D02*
X1210600D01*
G01X1213900Y-1695400D02*
Y-1705700D01*
G01D02*
X1221400D01*
G01X1225100Y-1695400D02*
Y-1705700D01*
G01D02*
X1232800D01*
G01X1213400Y-1689800D02*
X1214800Y-1688400D01*
G01D02*
Y-1687000D01*
G01D02*
X1213400Y-1685600D01*
G01X1222300Y-1680000D02*
Y-1690200D01*
G01X1213900Y-1700600D02*
X1219000D01*
G01X1221400Y-1695400D02*
X1213900D01*
G01X1213400Y-1674900D02*
Y-1664500D01*
G01D02*
X1219500Y-1674900D01*
G01D02*
Y-1664500D01*
G01X1218500Y-1680000D02*
X1226000D01*
G01X1228100Y-1649300D02*
X1226100Y-1650400D01*
G01D02*
X1225400Y-1652100D01*
G01D02*
Y-1657100D01*
G01Y-1656400D02*
X1226100Y-1658200D01*
G01D02*
X1228100Y-1659200D01*
G01D02*
X1230400D01*
G01X1213300Y-1637500D02*
Y-1635700D01*
G01X1216500Y-1633700D02*
X1224100D01*
G01X1220400D02*
Y-1644000D01*
G01X1227200Y-1633700D02*
X1230900Y-1638800D01*
G01X1230400Y-1649300D02*
X1228100D01*
G01X1227500Y-1575800D02*
X1228200Y-1579900D01*
G01D02*
X1229800Y-1583900D01*
G01D02*
X1232200Y-1587600D01*
G01Y-1559500D02*
X1229800Y-1563200D01*
G01D02*
X1228200Y-1567200D01*
G01D02*
X1227500Y-1571400D01*
G01D02*
Y-1575800D01*
G01X1236600Y-1573600D02*
X1223200D01*
G01X1215600Y-1533400D02*
X1220100D01*
G01D02*
X1221900Y-1532800D01*
G01D02*
X1222900Y-1531300D01*
G01D02*
Y-1529600D01*
G01D02*
X1221900Y-1528100D01*
G01D02*
X1220100Y-1527500D01*
G01D02*
X1215600D01*
G01D02*
Y-1537800D01*
G01X1223000D02*
X1220100Y-1533400D01*
G01X1226000Y-1537800D02*
X1229700D01*
G01D02*
X1231400Y-1537100D01*
G01Y-1528200D02*
X1229700Y-1527500D01*
G01D02*
X1226000D01*
G01D02*
Y-1537800D01*
G01X1216100Y-1422800D02*
Y-1438200D01*
G01D02*
X1227000D01*
G01X1236500Y-1695400D02*
Y-1705700D01*
G01D02*
X1244000D01*
G01X1233400Y-1680000D02*
Y-1690200D01*
G01X1231000D02*
X1235600D01*
G01X1240600Y-1682200D02*
Y-1688200D01*
G01D02*
X1241200Y-1689200D01*
G01D02*
X1242500Y-1689900D01*
G01D02*
X1244400Y-1690200D01*
G01D02*
X1248100D01*
G01X1236500Y-1700600D02*
X1241800D01*
G01X1244000Y-1695400D02*
X1236500D01*
G01X1245900Y-1667500D02*
X1245200Y-1665700D01*
G01X1239000D02*
X1238200Y-1667500D01*
G01D02*
Y-1672600D01*
G01Y-1671900D02*
X1239000Y-1673700D01*
G01D02*
X1240900Y-1674700D01*
G01D02*
X1243300D01*
G01D02*
X1245200Y-1673700D01*
G01D02*
X1245900Y-1671900D01*
G01D02*
Y-1666700D01*
G01X1231000Y-1680000D02*
X1235600D01*
G01X1248100D02*
X1244400D01*
G01D02*
X1242500Y-1680300D01*
G01D02*
X1241200Y-1681100D01*
G01D02*
X1240600Y-1682200D01*
G01X1233100Y-1652100D02*
X1232300Y-1650400D01*
G01D02*
X1230400Y-1649300D01*
G01Y-1659200D02*
X1232300Y-1658200D01*
G01D02*
X1233100Y-1656400D01*
G01D02*
Y-1651400D01*
G01X1238200Y-1654900D02*
X1242800D01*
G01D02*
X1244600Y-1654500D01*
G01D02*
X1245800Y-1653000D01*
G01D02*
Y-1651100D01*
G01D02*
X1244600Y-1649600D01*
G01D02*
X1242800Y-1649200D01*
G01X1238200D02*
Y-1659400D01*
G01X1245900D02*
X1242800Y-1654900D01*
G01X1245200Y-1665700D02*
X1243300Y-1664700D01*
G01D02*
X1240900D01*
G01D02*
X1239000Y-1665700D01*
G01X1230900Y-1638800D02*
Y-1644000D01*
G01Y-1638800D02*
X1234700Y-1633700D01*
G01X1242800Y-1649200D02*
X1238200D01*
G01X1232200Y-1587600D02*
X1235100Y-1590700D01*
G01D02*
X1238700Y-1593200D01*
G01D02*
X1242500Y-1595000D01*
G01D02*
X1246700Y-1596000D01*
G01D02*
X1251100Y-1596200D01*
G01X1234000Y-1577300D02*
X1235100Y-1580700D01*
G01D02*
X1237100Y-1583800D01*
G01D02*
X1239700Y-1586400D01*
G01D02*
X1242800Y-1588300D01*
G01D02*
X1246200Y-1589700D01*
G01D02*
X1249900Y-1590000D01*
G01X1239700Y-1560700D02*
X1237100Y-1563200D01*
G01D02*
X1235100Y-1566500D01*
G01D02*
X1234000Y-1569900D01*
G01D02*
X1233500Y-1573600D01*
G01D02*
X1234000Y-1577300D01*
G01X1255700Y-1573600D02*
X1244300D01*
G01X1251100Y-1551000D02*
X1246700Y-1551100D01*
G01D02*
X1242500Y-1552200D01*
G01D02*
X1238700Y-1553900D01*
G01D02*
X1235100Y-1556400D01*
G01D02*
X1232200Y-1559500D01*
G01X1249900Y-1557000D02*
X1246200Y-1557500D01*
G01D02*
X1242800Y-1558700D01*
G01D02*
X1239700Y-1560700D01*
G01X1231400Y-1537100D02*
X1232900Y-1535300D01*
G01D02*
X1233400Y-1532700D01*
G01D02*
X1232900Y-1530200D01*
G01D02*
X1231400Y-1528200D01*
G01X1246700Y-1537800D02*
X1250200Y-1527500D01*
G01X1247400Y-1535600D02*
X1253200D01*
G01X1244400Y-1505700D02*
Y-1493200D01*
G01Y-1505700D02*
X1347400D01*
G01X1248900Y-1477300D02*
X1247000Y-1474600D01*
G01X1241800D02*
X1239900Y-1477300D01*
G01D02*
X1239300Y-1481000D01*
G01D02*
X1239900Y-1484500D01*
G01D02*
X1241800Y-1487200D01*
G01D02*
X1244400Y-1488100D01*
G01D02*
X1247000Y-1487200D01*
G01D02*
X1248900Y-1484500D01*
G01X1247000Y-1474600D02*
X1244400Y-1473800D01*
G01D02*
X1241800Y-1474600D01*
G01X1231300Y-1430500D02*
X1239000D01*
G01X1231300Y-1422800D02*
Y-1438200D01*
G01D02*
X1242200D01*
G01Y-1422800D02*
X1231300D01*
G01X1247800Y-1705700D02*
X1251500D01*
G01D02*
X1253900Y-1705300D01*
G01D02*
X1255200Y-1704000D01*
G01D02*
Y-1702300D01*
G01D02*
X1253900Y-1701000D01*
G01X1262900Y-1695400D02*
Y-1705700D01*
G01X1251700Y-1690200D02*
X1255500Y-1680000D01*
G01D02*
X1259200Y-1690200D01*
G01X1252600Y-1688200D02*
X1258500D01*
G01X1255400Y-1695400D02*
X1251500D01*
G01D02*
X1249300Y-1696000D01*
G01D02*
X1248000Y-1697200D01*
G01D02*
Y-1698800D01*
G01D02*
X1249300Y-1700100D01*
G01D02*
X1251500Y-1700600D01*
G01X1253900Y-1701000D02*
X1251500Y-1700600D01*
G01X1259200Y-1695400D02*
X1266700D01*
G01X1251100Y-1670400D02*
X1255700D01*
G01D02*
X1257400Y-1669800D01*
G01D02*
X1258500Y-1668400D01*
G01D02*
Y-1666600D01*
G01X1251100Y-1664500D02*
Y-1674900D01*
G01X1258600D02*
X1255700Y-1670400D01*
G01X1263900Y-1654900D02*
X1268500D01*
G01X1263900Y-1649200D02*
Y-1659400D01*
G01X1258500Y-1666600D02*
X1257400Y-1665100D01*
G01D02*
X1255700Y-1664500D01*
G01D02*
X1251100D01*
G01X1256000Y-1636600D02*
X1255200Y-1634800D01*
G01D02*
X1253300Y-1633800D01*
G01D02*
X1250900D01*
G01D02*
X1249000Y-1634800D01*
G01D02*
X1248300Y-1636600D01*
G01D02*
Y-1641800D01*
G01Y-1641000D02*
X1249000Y-1642800D01*
G01D02*
X1250900Y-1643900D01*
G01D02*
X1253300D01*
G01D02*
X1255200Y-1642800D01*
G01D02*
X1256000Y-1641000D01*
G01D02*
Y-1635900D01*
G01X1258900Y-1638800D02*
X1264200D01*
G01X1258900Y-1644000D02*
Y-1633700D01*
G01D02*
X1266400D01*
G01X1268500Y-1649200D02*
X1263900D01*
G01X1249900Y-1586900D02*
Y-1600300D01*
G01X1251100Y-1596200D02*
X1255200Y-1595600D01*
G01D02*
X1259400Y-1594100D01*
G01D02*
X1263000Y-1592000D01*
G01D02*
X1266300Y-1589200D01*
G01X1249900Y-1590000D02*
X1253600Y-1589700D01*
G01D02*
X1257100Y-1588300D01*
G01D02*
X1260200Y-1586400D01*
G01D02*
X1262900Y-1583800D01*
G01D02*
X1264800Y-1580700D01*
G01D02*
X1266000Y-1577300D01*
G01Y-1569900D02*
X1264800Y-1566500D01*
G01D02*
X1262900Y-1563200D01*
G01D02*
X1260200Y-1560700D01*
G01X1249900Y-1567800D02*
Y-1579300D01*
G01X1276800Y-1573600D02*
X1263300D01*
G01X1266300Y-1557900D02*
X1263000Y-1555100D01*
G01D02*
X1259400Y-1552900D01*
G01D02*
X1255200Y-1551600D01*
G01D02*
X1251100Y-1551000D01*
G01X1260200Y-1560700D02*
X1257100Y-1558700D01*
G01D02*
X1253600Y-1557500D01*
G01D02*
X1249900Y-1557000D01*
G01Y-1546800D02*
Y-1560300D01*
G01X1250200Y-1527500D02*
X1253900Y-1537800D01*
G01X1257600D02*
Y-1527500D01*
G01D02*
X1263500Y-1537800D01*
G01D02*
Y-1527500D01*
G01X1265000Y-1505700D02*
Y-1493200D01*
G01X1249600Y-1481000D02*
X1248900Y-1477300D01*
G01Y-1484500D02*
X1249600Y-1481000D01*
G01X1327400D02*
X1264200D01*
G01X1327400D02*
X1264200D01*
G01D02*
X1327400D01*
G01X1253600Y-1430500D02*
X1252900Y-1429000D01*
G01D02*
X1251200D01*
G01D02*
X1250300Y-1430500D01*
G01D02*
X1251200Y-1432000D01*
G01D02*
X1252900D01*
G01D02*
X1253600Y-1430500D01*
G01Y-1436000D02*
X1252900Y-1434500D01*
G01D02*
X1251200D01*
G01D02*
X1250300Y-1436000D01*
G01D02*
X1251200Y-1437300D01*
G01D02*
X1252900D01*
G01D02*
X1253600Y-1436000D01*
G01X1274300Y-1695400D02*
Y-1705700D01*
G01X1272100D02*
X1276500D01*
G01X1281800Y-1697600D02*
Y-1703500D01*
G01D02*
X1282400Y-1704700D01*
G01D02*
X1283700Y-1705400D01*
G01X1267600Y-1689200D02*
X1267200Y-1688300D01*
G01D02*
X1266000D01*
G01D02*
X1265400Y-1689200D01*
G01D02*
X1266000Y-1690100D01*
G01D02*
X1267200D01*
G01D02*
X1267600Y-1689200D01*
G01X1272100Y-1695400D02*
X1276500D01*
G01X1283700Y-1695700D02*
X1282400Y-1696600D01*
G01D02*
X1281800Y-1697600D01*
G01X1276800Y-1669700D02*
X1282100D01*
G01X1276800Y-1674900D02*
Y-1664500D01*
G01X1268500Y-1654900D02*
X1270300Y-1654500D01*
G01D02*
X1271300Y-1653000D01*
G01D02*
Y-1651100D01*
G01D02*
X1270300Y-1649600D01*
G01D02*
X1268500Y-1649200D01*
G01X1271500Y-1659400D02*
X1268500Y-1654900D01*
G01X1276800Y-1654300D02*
X1282100D01*
G01X1276800Y-1649200D02*
Y-1659400D01*
G01D02*
X1284300D01*
G01X1276800Y-1664500D02*
X1284300D01*
G01X1283900Y-1633700D02*
X1281900Y-1634000D01*
G01D02*
X1280600Y-1634800D01*
G01D02*
X1280200Y-1635900D01*
G01D02*
Y-1641800D01*
G01D02*
X1280600Y-1642800D01*
G01D02*
X1281900Y-1643700D01*
G01D02*
X1283900Y-1644000D01*
G01X1284300Y-1649200D02*
X1276800D01*
G01X1266300Y-1589200D02*
X1269000Y-1585800D01*
G01D02*
X1271000Y-1582000D01*
G01D02*
X1272200Y-1577900D01*
G01X1272600Y-1573600D02*
X1272200Y-1569300D01*
G01D02*
X1271000Y-1565200D01*
G01D02*
X1269000Y-1561300D01*
G01X1272200Y-1577900D02*
X1272600Y-1573600D01*
G01X1266400D02*
X1266000Y-1569900D01*
G01Y-1577300D02*
X1266400Y-1573600D01*
G01X1269000Y-1561300D02*
X1266300Y-1557900D01*
G01X1274600Y-1527500D02*
X1270100D01*
G01D02*
X1268700Y-1528200D01*
G01D02*
X1267600Y-1530200D01*
G01D02*
X1267200Y-1532700D01*
G01D02*
X1267600Y-1535300D01*
G01D02*
X1268700Y-1537100D01*
G01D02*
X1270100Y-1537800D01*
G01D02*
X1274600D01*
G01D02*
Y-1532700D01*
G01D02*
X1271600D01*
G01X1277500Y-1527500D02*
Y-1537800D01*
G01D02*
X1284800D01*
G01X1267300Y-1481000D02*
X1282800Y-1483700D01*
G01X1267300Y-1481000D02*
X1282800Y-1483700D01*
G01X1267300Y-1481000D02*
X1282800Y-1478200D01*
G01X1267300Y-1481000D02*
X1282800Y-1478200D01*
G01X1280200Y1589100D02*
Y1379100D01*
G01X1283700Y-1705400D02*
X1285600Y-1705700D01*
G01D02*
X1289300D01*
G01X1293200D02*
X1297000Y-1695400D01*
G01D02*
X1300700Y-1705700D01*
G01X1293900Y-1703500D02*
X1300000D01*
G01X1284900Y-1690200D02*
X1288700Y-1680000D01*
G01D02*
X1292400Y-1690200D01*
G01X1285800Y-1688200D02*
X1291700D01*
G01X1296000Y-1680000D02*
Y-1690200D01*
G01D02*
X1303700D01*
G01X1289300Y-1695400D02*
X1285600D01*
G01D02*
X1283700Y-1695700D01*
G01X1297200Y-1667500D02*
X1296400Y-1665700D01*
G01X1290400D02*
X1289600Y-1667500D01*
G01D02*
Y-1672600D01*
G01Y-1671900D02*
X1290400Y-1673700D01*
G01D02*
X1292100Y-1674700D01*
G01D02*
X1294500D01*
G01D02*
X1296400Y-1673700D01*
G01D02*
X1297200Y-1671900D01*
G01D02*
Y-1666700D01*
G01X1293300Y-1649200D02*
X1291100Y-1649600D01*
G01D02*
X1289800Y-1650900D01*
G01D02*
Y-1652400D01*
G01D02*
X1291100Y-1653700D01*
G01D02*
X1293300Y-1654300D01*
G01X1289600Y-1659400D02*
X1293300D01*
G01D02*
X1295500Y-1658900D01*
G01D02*
X1297000Y-1657600D01*
G01D02*
Y-1656100D01*
G01D02*
X1295500Y-1654800D01*
G01D02*
X1293300Y-1654300D01*
G01X1296400Y-1665700D02*
X1294500Y-1664700D01*
G01D02*
X1292100D01*
G01D02*
X1290400Y-1665700D01*
G01X1287700Y-1633700D02*
X1283900D01*
G01Y-1644000D02*
X1287700D01*
G01X1290700Y-1638800D02*
X1296000D01*
G01X1298300Y-1633700D02*
X1290700D01*
G01D02*
Y-1644000D01*
G01D02*
X1298300D01*
G01X1297200Y-1649200D02*
X1293300D01*
G01X1287700Y-1532700D02*
X1292900D01*
G01X1295100Y-1527500D02*
X1287700D01*
G01D02*
Y-1537800D01*
G01D02*
X1295100D01*
G01X1285500Y-1505700D02*
Y-1493200D01*
G01X1315800Y-1695400D02*
Y-1705700D01*
G01X1307000Y-1680000D02*
Y-1690200D01*
G01D02*
X1314700D01*
G01X1315800Y-1701300D02*
X1320300D01*
G01Y-1695400D02*
X1315800D01*
G01X1302500Y-1670400D02*
X1306900D01*
G01D02*
X1308700Y-1669800D01*
G01D02*
X1309900Y-1668400D01*
G01D02*
Y-1666600D01*
G01X1302500Y-1664500D02*
Y-1674900D01*
G01X1310000D02*
X1306900Y-1670400D01*
G01X1302500Y-1654900D02*
X1306900D01*
G01D02*
X1308700Y-1654500D01*
G01D02*
X1309900Y-1653000D01*
G01D02*
Y-1651100D01*
G01D02*
X1308700Y-1649600D01*
G01D02*
X1306900Y-1649200D01*
G01X1302500D02*
Y-1659400D01*
G01X1317800Y-1649300D02*
X1315900Y-1650400D01*
G01D02*
X1315200Y-1652100D01*
G01D02*
Y-1657100D01*
G01Y-1656400D02*
X1315900Y-1658200D01*
G01D02*
X1317800Y-1659200D01*
G01X1309900Y-1666600D02*
X1308700Y-1665100D01*
G01D02*
X1306900Y-1664500D01*
G01D02*
X1302500D01*
G01X1301300Y-1633700D02*
Y-1644000D01*
G01D02*
X1308800D01*
G01X1311900Y-1638800D02*
X1317200D01*
G01X1319500Y-1633700D02*
X1311900D01*
G01D02*
Y-1644000D01*
G01D02*
X1319500D01*
G01X1306900Y-1649200D02*
X1302500D01*
G01X1327900Y-1573600D02*
X1309900D01*
G01X1308400Y-1533400D02*
X1312800D01*
G01D02*
X1314400Y-1532800D01*
G01D02*
X1315600Y-1531300D01*
G01D02*
Y-1529600D01*
G01D02*
X1314400Y-1528100D01*
G01D02*
X1312800Y-1527500D01*
G01D02*
X1308400D01*
G01D02*
Y-1537800D01*
G01X1306200Y-1505700D02*
Y-1493200D01*
G01X1324300Y-1481000D02*
X1308800Y-1478200D01*
G01X1324300Y-1481000D02*
X1308800Y-1478200D01*
G01X1324300Y-1481000D02*
X1308800Y-1483700D01*
G01X1324300Y-1481000D02*
X1308800Y-1483700D01*
G01X1327100Y-1695400D02*
Y-1702800D01*
G01D02*
X1327900Y-1704500D01*
G01D02*
X1329800Y-1705600D01*
G01D02*
X1332100D01*
G01D02*
X1334100Y-1704500D01*
G01D02*
X1334700Y-1702800D01*
G01D02*
Y-1695400D01*
G01X1329200Y-1683000D02*
Y-1687400D01*
G01D02*
X1329900Y-1689000D01*
G01D02*
X1331900Y-1690100D01*
G01D02*
X1334200D01*
G01D02*
X1336100Y-1689000D01*
G01X1333000Y-1686700D02*
X1337600Y-1691000D01*
G01X1320300Y-1701300D02*
X1322100Y-1700700D01*
G01D02*
X1323300Y-1699200D01*
G01D02*
Y-1697500D01*
G01D02*
X1322100Y-1696000D01*
G01D02*
X1320300Y-1695400D01*
G01X1331900Y-1664500D02*
Y-1674900D01*
G01X1336100Y-1681200D02*
X1334200Y-1680200D01*
G01D02*
X1331900D01*
G01D02*
X1329900Y-1681200D01*
G01D02*
X1329200Y-1683000D01*
G01X1322800Y-1652100D02*
X1322100Y-1650400D01*
G01D02*
X1320200Y-1649300D01*
G01X1317800Y-1659200D02*
X1320200D01*
G01D02*
X1322100Y-1658200D01*
G01D02*
X1322800Y-1656400D01*
G01D02*
Y-1651400D01*
G01X1328800Y-1659400D02*
Y-1649200D01*
G01D02*
X1334800Y-1659400D01*
G01X1328000Y-1664500D02*
X1335700D01*
G01X1330100Y-1633700D02*
X1326200D01*
G01D02*
X1324000Y-1634100D01*
G01D02*
X1322700Y-1635400D01*
G01D02*
Y-1637100D01*
G01D02*
X1324000Y-1638400D01*
G01D02*
X1326200Y-1638800D01*
G01X1322600Y-1644000D02*
X1326200D01*
G01D02*
X1328500Y-1643400D01*
G01D02*
X1329900Y-1642200D01*
G01D02*
Y-1640600D01*
G01D02*
X1328500Y-1639300D01*
G01D02*
X1326200Y-1638800D01*
G01X1333000Y-1633700D02*
X1340700D01*
G01X1320200Y-1649300D02*
X1317800D01*
G01X1319900Y-1557000D02*
Y-1590000D01*
G01D02*
X1361100Y-1596200D01*
G01Y-1551000D02*
X1319900Y-1557000D01*
G01X1318600Y-1533400D02*
X1323000D01*
G01D02*
X1324800Y-1532800D01*
G01D02*
X1325800Y-1531300D01*
G01D02*
Y-1529600D01*
G01D02*
X1324800Y-1528100D01*
G01D02*
X1323000Y-1527500D01*
G01D02*
X1318600D01*
G01D02*
Y-1537800D01*
G01X1325900D02*
X1323000Y-1533400D01*
G01X1335500Y-1528700D02*
X1333800Y-1527700D01*
G01D02*
X1331400D01*
G01D02*
X1329600Y-1528700D01*
G01D02*
X1328900Y-1530500D01*
G01D02*
Y-1535600D01*
G01Y-1534900D02*
X1329600Y-1536700D01*
G01D02*
X1331400Y-1537700D01*
G01D02*
X1333800D01*
G01D02*
X1335500Y-1536700D01*
G01X1326700Y-1505700D02*
Y-1493200D01*
G01X1338500Y-1695400D02*
Y-1705700D01*
G01X1346000D02*
X1343100Y-1701300D01*
G01X1349900Y-1697600D02*
Y-1703500D01*
G01D02*
X1350300Y-1704700D01*
G01D02*
X1351800Y-1705400D01*
G01D02*
X1353600Y-1705700D01*
G01X1336100Y-1689000D02*
X1336900Y-1687400D01*
G01D02*
Y-1683000D01*
G01X1340300Y-1680000D02*
Y-1687400D01*
G01D02*
X1341000Y-1689000D01*
G01D02*
X1342900Y-1690100D01*
G01D02*
X1345300D01*
G01D02*
X1347200Y-1689000D01*
G01D02*
X1347900Y-1687400D01*
G01D02*
Y-1680000D01*
G01X1351300Y-1685200D02*
X1356700D01*
G01X1351300Y-1680000D02*
Y-1690200D01*
G01D02*
X1359000D01*
G01X1338500Y-1701300D02*
X1343100D01*
G01D02*
X1344800Y-1700700D01*
G01D02*
X1345900Y-1699200D01*
G01D02*
Y-1697500D01*
G01D02*
X1344800Y-1696000D01*
G01D02*
X1343100Y-1695400D01*
G01D02*
X1338500D01*
G01X1353600D02*
X1351800Y-1695700D01*
G01D02*
X1350300Y-1696600D01*
G01D02*
X1349900Y-1697600D01*
G01X1340900Y-1664500D02*
Y-1674900D01*
G01Y-1669700D02*
X1348400D01*
G01Y-1664500D02*
Y-1674900D01*
G01X1336900Y-1683000D02*
X1336100Y-1681200D01*
G01X1359000Y-1680000D02*
X1351300D01*
G01X1334800Y-1659400D02*
Y-1649200D01*
G01X1340900Y-1659400D02*
X1344700D01*
G01D02*
X1346600Y-1658800D01*
G01D02*
X1347900Y-1656800D01*
G01D02*
X1348400Y-1654300D01*
G01D02*
X1347900Y-1651700D01*
G01D02*
X1346600Y-1649800D01*
G01D02*
X1344700Y-1649200D01*
G01X1340900D02*
Y-1659400D01*
G01X1336900Y-1633700D02*
Y-1644000D01*
G01X1345100Y-1633700D02*
X1349700D01*
G01X1347500D02*
Y-1644000D01*
G01X1345100D02*
X1349700D01*
G01X1344700Y-1649200D02*
X1340900D01*
G01X1349100Y-1573600D02*
X1336400D01*
G01X1336300Y-1530500D02*
X1335500Y-1528700D01*
G01Y-1536700D02*
X1336300Y-1534900D01*
G01D02*
Y-1529700D01*
G01X1339200Y-1534900D02*
X1340000Y-1536700D01*
G01D02*
X1341700Y-1537700D01*
G01D02*
X1344000D01*
G01D02*
X1345900Y-1536700D01*
G01D02*
X1346600Y-1534900D01*
G01D02*
Y-1527500D01*
G01X1349600Y-1532700D02*
X1354600D01*
G01X1356800Y-1527500D02*
X1349600D01*
G01D02*
Y-1537800D01*
G01D02*
X1356800D01*
G01X1347400Y-1505700D02*
Y-1493200D01*
G01X1353600Y-1705700D02*
X1357400D01*
G01X1361200Y-1695400D02*
Y-1705700D01*
G01X1368800Y-1695400D02*
Y-1705700D01*
G01X1362700Y-1683400D02*
X1364000Y-1684600D01*
G01D02*
X1366300Y-1685200D01*
G01X1362400Y-1690200D02*
X1366300D01*
G01D02*
X1368500Y-1689800D01*
G01D02*
X1369800Y-1688400D01*
G01Y-1687000D02*
X1368500Y-1685600D01*
G01D02*
X1366300Y-1685200D01*
G01X1357400Y-1695400D02*
X1353600D01*
G01X1361200Y-1700600D02*
X1368800D01*
G01X1353700Y-1669700D02*
X1359000D01*
G01X1353700Y-1664500D02*
Y-1674900D01*
G01D02*
X1361200D01*
G01X1370100Y-1680000D02*
X1366300D01*
G01D02*
X1364000Y-1680500D01*
G01D02*
X1362700Y-1681800D01*
G01D02*
Y-1683400D01*
G01X1357500Y-1649200D02*
Y-1659400D01*
G01X1355200D02*
X1359800D01*
G01X1367300D02*
Y-1649200D01*
G01D02*
X1373300Y-1659400D01*
G01X1361200Y-1664500D02*
X1353700D01*
G01X1361800Y-1633700D02*
X1358100D01*
G01D02*
X1356200Y-1634000D01*
G01D02*
X1354700Y-1634800D01*
G01D02*
X1354300Y-1635900D01*
G01D02*
Y-1641800D01*
G01D02*
X1354700Y-1642800D01*
G01D02*
X1356200Y-1643700D01*
G01D02*
X1358100Y-1644000D01*
G01D02*
X1361800D01*
G01X1364900D02*
X1368600Y-1633700D01*
G01D02*
X1372500Y-1644000D01*
G01X1365700Y-1641800D02*
X1371600D01*
G01X1355200Y-1649200D02*
X1359800D01*
G01X1361100Y-1596200D02*
Y-1551000D01*
G01X1375600Y-1573600D02*
X1357500D01*
G01X1367100Y-1527500D02*
X1363500D01*
G01D02*
X1361700Y-1527800D01*
G01D02*
X1360400Y-1528700D01*
G01D02*
X1359800Y-1529700D01*
G01D02*
Y-1535600D01*
G01D02*
X1360400Y-1536800D01*
G01D02*
X1361700Y-1537500D01*
G01D02*
X1363500Y-1537800D01*
G01D02*
X1367100D01*
G01X1371900Y-1784300D02*
X1378500Y-1785800D01*
G01D02*
X1382400Y-1786000D01*
G01D02*
X1386000Y-1784900D01*
G01D02*
X1388800Y-1782600D01*
G01X1388000Y-1773900D02*
X1384900Y-1772000D01*
G01D02*
X1381000Y-1771400D01*
G01Y-1771300D02*
X1384600Y-1770400D01*
G01D02*
X1387200Y-1768600D01*
G01X1388000Y-1764200D02*
X1386000Y-1762100D01*
G01D02*
X1382900Y-1760800D01*
G01D02*
X1379300Y-1760400D01*
G01D02*
X1375400Y-1760800D01*
G01D02*
X1372300Y-1762300D01*
G01X1372500Y-1705700D02*
X1376300Y-1695400D01*
G01D02*
X1380100Y-1705700D01*
G01X1373300Y-1703500D02*
X1379300D01*
G01X1383800Y-1705700D02*
X1387700D01*
G01X1369800Y-1688400D02*
Y-1687000D01*
G01X1377300Y-1680000D02*
Y-1690200D01*
G01X1386200D02*
X1390600D01*
G01X1387700Y-1695400D02*
X1385500Y-1696000D01*
G01D02*
X1384000Y-1697200D01*
G01D02*
Y-1698800D01*
G01D02*
X1385500Y-1700100D01*
G01D02*
X1387700Y-1700600D01*
G01X1379400Y-1670400D02*
X1384000D01*
G01D02*
X1385700Y-1669800D01*
G01D02*
X1386800Y-1668400D01*
G01D02*
Y-1666600D01*
G01X1379400Y-1664500D02*
Y-1674900D01*
G01X1373500Y-1680000D02*
X1381200D01*
G01X1386200D02*
X1390600D01*
G01X1373300Y-1659400D02*
Y-1649200D01*
G01X1382400D02*
X1380900Y-1649800D01*
G01D02*
X1379800Y-1651700D01*
G01D02*
X1379400Y-1654300D01*
G01D02*
X1379800Y-1656800D01*
G01D02*
X1380900Y-1658800D01*
G01D02*
X1382400Y-1659400D01*
G01D02*
X1386900D01*
G01D02*
Y-1654300D01*
G01D02*
X1384000D01*
G01X1386800Y-1666600D02*
X1385700Y-1665100D01*
G01D02*
X1384000Y-1664500D01*
G01D02*
X1379400D01*
G01X1386900Y-1649200D02*
X1382400D01*
G01X1370100Y-1527500D02*
X1377500D01*
G01X1373800D02*
Y-1537800D01*
G01X1381900Y-1527500D02*
X1386200D01*
G01X1384100D02*
Y-1537800D01*
G01X1381900D02*
X1386200D01*
G01X1371900Y1601800D02*
X1378500Y1600200D01*
G01D02*
X1382400Y1600000D01*
G01D02*
X1386000Y1601200D01*
G01D02*
X1388800Y1603300D01*
G01X1381000Y1614800D02*
X1384600Y1615700D01*
G01D02*
X1387200Y1617400D01*
G01X1388000Y1621900D02*
X1386000Y1623800D01*
G01D02*
X1382900Y1625300D01*
G01D02*
X1379300Y1625700D01*
G01D02*
X1375400Y1625300D01*
G01D02*
X1372300Y1623800D01*
G01X1388000Y1612100D02*
X1384900Y1614000D01*
G01D02*
X1381000Y1614600D01*
G01X1388800Y-1782600D02*
X1390200Y-1779800D01*
G01D02*
X1389900Y-1776600D01*
G01D02*
X1388000Y-1773900D01*
G01X1387200Y-1768600D02*
X1388400Y-1766400D01*
G01D02*
X1388000Y-1764200D01*
G01X1387700Y-1705700D02*
X1389900Y-1705300D01*
G01D02*
X1391200Y-1704000D01*
G01D02*
Y-1702300D01*
G01D02*
X1389900Y-1701000D01*
G01X1398900Y-1695400D02*
Y-1705700D01*
G01X1396700D02*
X1401300D01*
G01X1388400Y-1680000D02*
Y-1690200D01*
G01X1395800Y-1683000D02*
Y-1688200D01*
G01Y-1687400D02*
X1396400Y-1689000D01*
G01D02*
X1398300Y-1690100D01*
G01D02*
X1400700D01*
G01D02*
X1402600Y-1689000D01*
G01D02*
X1403300Y-1687400D01*
G01D02*
Y-1682200D01*
G01X1391400Y-1695400D02*
X1387700D01*
G01X1389900Y-1701000D02*
X1387700Y-1700600D01*
G01X1396700Y-1695400D02*
X1401300D01*
G01X1392200Y-1669700D02*
X1397600D01*
G01X1392200Y-1664500D02*
Y-1674900D01*
G01D02*
X1399800D01*
G01X1403300Y-1683000D02*
X1402600Y-1681200D01*
G01D02*
X1400700Y-1680200D01*
G01D02*
X1398300D01*
G01D02*
X1396400Y-1681200D01*
G01D02*
X1395800Y-1683000D01*
G01X1399800Y-1664500D02*
X1392200D01*
G01X1387500Y-1633700D02*
X1392100D01*
G01X1389900D02*
Y-1644000D01*
G01X1387500D02*
X1392100D01*
G01X1397400D02*
Y-1633700D01*
G01D02*
X1403500Y-1644000D01*
G01D02*
Y-1633700D01*
G01X1398000Y-1530500D02*
X1397300Y-1528700D01*
G01D02*
X1395500Y-1527700D01*
G01D02*
X1393300D01*
G01D02*
X1391400Y-1528700D01*
G01D02*
X1390600Y-1530500D01*
G01D02*
Y-1535600D01*
G01Y-1534900D02*
X1391400Y-1536700D01*
G01D02*
X1393300Y-1537700D01*
G01D02*
X1395500D01*
G01D02*
X1397300Y-1536700D01*
G01D02*
X1398000Y-1534900D01*
G01D02*
Y-1529700D01*
G01X1401700Y-1537800D02*
Y-1527500D01*
G01D02*
X1407600Y-1537800D01*
G01X1388800Y1603300D02*
X1390200Y1606200D01*
G01D02*
X1389900Y1609300D01*
G01D02*
X1388000Y1612100D01*
G01X1387200Y1617400D02*
X1388400Y1619500D01*
G01D02*
X1388000Y1621900D01*
G01X1407300Y-1705700D02*
Y-1695400D01*
G01D02*
X1413400Y-1705700D01*
G01D02*
Y-1695400D01*
G01X1417800Y-1700600D02*
X1418200Y-1703200D01*
G01D02*
X1419400Y-1705000D01*
G01D02*
X1420900Y-1705700D01*
G01D02*
X1425500D01*
G01X1407600Y-1690200D02*
Y-1680000D01*
G01D02*
X1413700Y-1690200D01*
G01D02*
Y-1680000D01*
G01X1418100Y-1683400D02*
X1419400Y-1684600D01*
G01D02*
X1421600Y-1685200D01*
G01X1417900Y-1690200D02*
X1421600D01*
G01D02*
X1423800Y-1689800D01*
G01Y-1685600D02*
X1421600Y-1685200D01*
G01X1425500Y-1695400D02*
X1420900D01*
G01D02*
X1419400Y-1696100D01*
G01D02*
X1418200Y-1698000D01*
G01D02*
X1417800Y-1700600D01*
G01X1405100Y-1670400D02*
X1409500D01*
G01D02*
X1411300Y-1669800D01*
G01D02*
X1412500Y-1668400D01*
G01D02*
Y-1666600D01*
G01X1405100Y-1664500D02*
Y-1674900D01*
G01X1412600D02*
X1409500Y-1670400D01*
G01X1418700Y-1669700D02*
X1424700D01*
G01X1425500Y-1680000D02*
X1421600D01*
G01D02*
X1419400Y-1680500D01*
G01D02*
X1418100Y-1681800D01*
G01D02*
Y-1683400D01*
G01X1408800Y-1649200D02*
Y-1659400D01*
G01X1420400Y-1649300D02*
X1418500Y-1650400D01*
G01D02*
X1417800Y-1652100D01*
G01D02*
Y-1657100D01*
G01Y-1656400D02*
X1418500Y-1658200D01*
G01D02*
X1420400Y-1659200D01*
G01D02*
X1422800D01*
G01X1412500Y-1666600D02*
X1411300Y-1665100D01*
G01D02*
X1409500Y-1664500D01*
G01D02*
X1405100D01*
G01X1414800Y-1633700D02*
X1411000D01*
G01D02*
X1409200Y-1634000D01*
G01D02*
X1407700Y-1634800D01*
G01D02*
X1407300Y-1635900D01*
G01D02*
Y-1641800D01*
G01D02*
X1407700Y-1642800D01*
G01D02*
X1409200Y-1643700D01*
G01D02*
X1411000Y-1644000D01*
G01D02*
X1414800D01*
G01X1422200Y-1641900D02*
X1421000D01*
G01D02*
X1420400Y-1642800D01*
G01D02*
X1421000Y-1643900D01*
G01D02*
X1422200D01*
G01X1405100Y-1649200D02*
X1412600D01*
G01X1422800Y-1649300D02*
X1420400D01*
G01X1407600Y-1537800D02*
Y-1527500D01*
G01X1435200Y-1749600D02*
Y-1407900D01*
G01Y-1702200D02*
X2056300D01*
G01X1425500Y-1705700D02*
Y-1700600D01*
G01X1423800Y-1689800D02*
X1425300Y-1688400D01*
G01D02*
Y-1687000D01*
G01D02*
X1423800Y-1685600D01*
G01X1425500Y-1700600D02*
X1422400D01*
G01X1435200Y-1661000D02*
X2056300D01*
G01X1425500Y-1652100D02*
X1424700Y-1650400D01*
G01D02*
X1422800Y-1649300D01*
G01Y-1659200D02*
X1424700Y-1658200D01*
G01D02*
X1425500Y-1656400D01*
G01D02*
Y-1651400D01*
G01X1422800Y-1642800D02*
X1422200Y-1641900D01*
G01Y-1643900D02*
X1422800Y-1642800D01*
G01X2056300Y-1578700D02*
X1435200D01*
G01Y-1536500D02*
X2056300D01*
G01X1435200Y-1494300D02*
X2056300D01*
G01X1454400Y-1718400D02*
Y-1727100D01*
G01D02*
X1454900Y-1728500D01*
G01D02*
X1456000Y-1729500D01*
G01D02*
X1457800Y-1730200D01*
G01Y-1715500D02*
X1456000Y-1716200D01*
G01D02*
X1454900Y-1717200D01*
G01D02*
X1454400Y-1718400D01*
G01Y-1689200D02*
X1459900Y-1674000D01*
G01X1455600Y-1685900D02*
X1464200D01*
G01X1457800Y-1633100D02*
X1456000Y-1633800D01*
G01D02*
X1454900Y-1634800D01*
G01D02*
X1454400Y-1636200D01*
G01D02*
Y-1644700D01*
G01D02*
X1454900Y-1646100D01*
G01D02*
X1456000Y-1647100D01*
G01D02*
X1457800Y-1647800D01*
G01X1454400Y-1606900D02*
X1459900D01*
G01X1454400Y-1591700D02*
Y-1606900D01*
G01X1459900Y-1591700D02*
X1454400D01*
G01X1450400Y-1511400D02*
X1461200D01*
G01X1455700D02*
Y-1526600D01*
G01X1449700Y-1428400D02*
X1457100D01*
G01X1449700Y-1418700D02*
Y-1435800D01*
G01X1457100Y-1418700D02*
X1449700D01*
G01X1457800Y-1730200D02*
X1459900Y-1730400D01*
G01D02*
X1465300D01*
G01X1469800Y-1715200D02*
Y-1730400D01*
G01D02*
X1480500D01*
G01X1465300Y-1715200D02*
X1459900D01*
G01D02*
X1457800Y-1715500D01*
G01X1459900Y-1674000D02*
X1465300Y-1689200D01*
G01X1469800Y-1674000D02*
Y-1689200D01*
G01Y-1682700D02*
X1476300D01*
G01Y-1674000D02*
X1469800D01*
G01X1465300Y-1632800D02*
X1459900D01*
G01D02*
X1457800Y-1633100D01*
G01Y-1647800D02*
X1459900Y-1648100D01*
G01D02*
X1465300D01*
G01X1469800Y-1632800D02*
Y-1648100D01*
G01Y-1640500D02*
X1480500D01*
G01X1459900Y-1606900D02*
X1462200Y-1606200D01*
G01D02*
X1464200Y-1604000D01*
G01D02*
X1465200Y-1601000D01*
G01D02*
Y-1597600D01*
G01D02*
X1464200Y-1594500D01*
G01X1469800Y-1599300D02*
X1477300D01*
G01X1469800Y-1591700D02*
Y-1606900D01*
G01D02*
X1480500D01*
G01X1464200Y-1594500D02*
X1462200Y-1592500D01*
G01D02*
X1459900Y-1591700D01*
G01X1480500D02*
X1469800D01*
G01X1467700Y-1511400D02*
X1474300D01*
G01X1471100D02*
Y-1526600D01*
G01X1467700D02*
X1474300D01*
G01X1457100Y-1428400D02*
X1459400Y-1427800D01*
G01D02*
X1461200Y-1426100D01*
G01D02*
X1461900Y-1423600D01*
G01D02*
X1461200Y-1421200D01*
G01X1466800Y-1435800D02*
X1473000Y-1418700D01*
G01X1468100Y-1432100D02*
X1477700D01*
G01X1461200Y-1421200D02*
X1459400Y-1419400D01*
G01D02*
X1457100Y-1418700D01*
G01X1473000D02*
X1479100Y-1435800D01*
G01X1485000Y-1730400D02*
X1490400Y-1715200D01*
G01X1486200Y-1727100D02*
X1494700D01*
G01X1490400Y-1715200D02*
X1495800Y-1730400D01*
G01X1485000Y-1674000D02*
Y-1689200D01*
G01X1476300Y-1682700D02*
X1478500Y-1682100D01*
G01D02*
X1480000Y-1680500D01*
G01D02*
X1480500Y-1678400D01*
G01D02*
X1480000Y-1676200D01*
G01D02*
X1478500Y-1674600D01*
G01D02*
X1476300Y-1674000D01*
G01X1485000Y-1682700D02*
X1491500D01*
G01D02*
X1493700Y-1682100D01*
G01Y-1674600D02*
X1491500Y-1674000D01*
G01D02*
X1485000D01*
G01X1480500Y-1632800D02*
Y-1648100D01*
G01X1485000Y-1640500D02*
X1492500D01*
G01X1495800Y-1632800D02*
X1485000D01*
G01D02*
Y-1648100D01*
G01D02*
X1495800D01*
G01X1485000Y-1595400D02*
X1485700Y-1597300D01*
G01D02*
X1487600Y-1598800D01*
G01D02*
X1490400Y-1599300D01*
G01X1485000Y-1606900D02*
X1490400D01*
G01D02*
X1493100Y-1606400D01*
G01Y-1599900D02*
X1490400Y-1599300D01*
G01X1495800Y-1591700D02*
X1490400D01*
G01D02*
X1487600Y-1592200D01*
G01D02*
X1485700Y-1593700D01*
G01D02*
X1485000Y-1595400D01*
G01X1480800Y-1511400D02*
X1491800D01*
G01X1486300D02*
Y-1526600D01*
G01X1483900Y-1428400D02*
X1491300D01*
G01D02*
X1493800Y-1427800D01*
G01X1483900Y-1418700D02*
Y-1435800D01*
G01X1496200D02*
X1491300Y-1428400D01*
G01X1493800Y-1419400D02*
X1491300Y-1418700D01*
G01D02*
X1483900D01*
G01X1500200Y-1719000D02*
X1500900Y-1720900D01*
G01D02*
X1502800Y-1722300D01*
G01D02*
X1505600Y-1722800D01*
G01X1500200Y-1730400D02*
X1505600D01*
G01D02*
X1508300Y-1729900D01*
G01D02*
X1510400Y-1728500D01*
G01Y-1724800D02*
X1508300Y-1723300D01*
G01D02*
X1505600Y-1722800D01*
G01X1511100Y-1715200D02*
X1505600D01*
G01D02*
X1502800Y-1715800D01*
G01D02*
X1500900Y-1717100D01*
G01D02*
X1500200Y-1719000D01*
G01Y-1674000D02*
Y-1689200D01*
G01X1511100D02*
X1506700Y-1682700D01*
G01X1493700Y-1682100D02*
X1495200Y-1680500D01*
G01D02*
X1495800Y-1678400D01*
G01D02*
X1495200Y-1676200D01*
G01D02*
X1493700Y-1674600D01*
G01X1500200Y-1682700D02*
X1506700D01*
G01D02*
X1508900Y-1682100D01*
G01D02*
X1510500Y-1680500D01*
G01Y-1676200D02*
X1508900Y-1674600D01*
G01D02*
X1506700Y-1674000D01*
G01D02*
X1500200D01*
G01X1511100Y-1632800D02*
X1505600D01*
G01D02*
X1503600Y-1633100D01*
G01D02*
X1501800Y-1633800D01*
G01D02*
X1500600Y-1634800D01*
G01D02*
X1500200Y-1636200D01*
G01D02*
Y-1644700D01*
G01D02*
X1500600Y-1646100D01*
G01D02*
X1501800Y-1647100D01*
G01D02*
X1503600Y-1647800D01*
G01D02*
X1505600Y-1648100D01*
G01D02*
X1511100D01*
G01X1493100Y-1606400D02*
X1495000Y-1605000D01*
G01D02*
X1495800Y-1603100D01*
G01D02*
X1495000Y-1601200D01*
G01D02*
X1493100Y-1599900D01*
G01X1505600Y-1591700D02*
Y-1606900D01*
G01X1502400D02*
X1508900D01*
G01X1502400Y-1591700D02*
X1508900D01*
G01X1496000Y-1511400D02*
Y-1526600D01*
G01D02*
X1507000D01*
G01X1493800Y-1427800D02*
X1495600Y-1426100D01*
G01D02*
X1496200Y-1423600D01*
G01D02*
X1495600Y-1421200D01*
G01X1507300Y-1418700D02*
Y-1435800D01*
G01X1495600Y-1421200D02*
X1493800Y-1419400D01*
G01X1501100Y-1418700D02*
X1513300D01*
G01X1510400Y-1728500D02*
X1511100Y-1726500D01*
G01D02*
X1510400Y-1724800D01*
G01X1515400Y-1719000D02*
X1516100Y-1720900D01*
G01D02*
X1518000Y-1722300D01*
G01D02*
X1520900Y-1722800D01*
G01X1515400Y-1730400D02*
X1520900D01*
G01D02*
X1523500Y-1729900D01*
G01D02*
X1525600Y-1728500D01*
G01D02*
X1526300Y-1726500D01*
G01D02*
X1525600Y-1724800D01*
G01D02*
X1523500Y-1723300D01*
G01D02*
X1520900Y-1722800D01*
G01X1526300Y-1715200D02*
X1520900D01*
G01D02*
X1518000Y-1715800D01*
G01D02*
X1516100Y-1717100D01*
G01D02*
X1515400Y-1719000D01*
G01Y-1678400D02*
Y-1685900D01*
G01Y-1684900D02*
X1516100Y-1687100D01*
G01D02*
X1518000Y-1688600D01*
G01D02*
X1520900Y-1689200D01*
G01D02*
X1523500Y-1688600D01*
G01D02*
X1525600Y-1687100D01*
G01D02*
X1526300Y-1684900D01*
G01D02*
Y-1677200D01*
G01X1510500Y-1680500D02*
X1511100Y-1678400D01*
G01D02*
X1510500Y-1676200D01*
G01X1526300Y-1678400D02*
X1525600Y-1676200D01*
G01D02*
X1523500Y-1674600D01*
G01D02*
X1520900Y-1674000D01*
G01D02*
X1518000Y-1674600D01*
G01D02*
X1516100Y-1676200D01*
G01D02*
X1515400Y-1678400D01*
G01Y-1632800D02*
Y-1648100D01*
G01Y-1641500D02*
X1526300Y-1632800D01*
G01X1519100Y-1638500D02*
X1526300Y-1648100D01*
G01X1516300Y-1594500D02*
X1515500Y-1597600D01*
G01D02*
Y-1601000D01*
G01D02*
X1516300Y-1604000D01*
G01D02*
X1517900Y-1606200D01*
G01D02*
X1519800Y-1606900D01*
G01D02*
X1526300D01*
G01D02*
Y-1599300D01*
G01D02*
X1521900D01*
G01X1526300Y-1591700D02*
X1519800D01*
G01D02*
X1517900Y-1592500D01*
G01D02*
X1516300Y-1594500D01*
G01X1511300Y-1518900D02*
X1518900D01*
G01X1522200Y-1511400D02*
X1511300D01*
G01D02*
Y-1526600D01*
G01D02*
X1522200D01*
G01X1530600Y-1674000D02*
X1536100Y-1689200D01*
G01D02*
X1541500Y-1674000D01*
G01X1530600Y-1640500D02*
X1538300D01*
G01X1541500Y-1632800D02*
X1530600D01*
G01D02*
Y-1648100D01*
G01D02*
X1541500D01*
G01X1531800Y-1606900D02*
Y-1591700D01*
G01D02*
X1540500Y-1606900D01*
G01D02*
Y-1591700D01*
G01X1536700Y-1435800D02*
Y-1418700D01*
G01D02*
X1546400Y-1435800D01*
G01X1545800Y-1674000D02*
Y-1689200D01*
G01D02*
X1556700D01*
G01X1561200D02*
X1566500D01*
G01X1561200Y-1674000D02*
Y-1689200D01*
G01X1545800Y-1681700D02*
X1553500D01*
G01X1556700Y-1674000D02*
X1545800D01*
G01X1566500D02*
X1561200D01*
G01X1545800Y-1648100D02*
X1551300D01*
G01D02*
X1553600Y-1647300D01*
G01D02*
X1555600Y-1645200D01*
G01D02*
X1556600Y-1642100D01*
G01D02*
Y-1638800D01*
G01D02*
X1555600Y-1635700D01*
G01D02*
X1553600Y-1633700D01*
G01D02*
X1551300Y-1632800D01*
G01D02*
X1545800D01*
G01D02*
Y-1648100D01*
G01Y-1599300D02*
X1553500D01*
G01X1545800Y-1591700D02*
Y-1606900D01*
G01D02*
X1556700D01*
G01X1561200Y-1600400D02*
X1567700D01*
G01X1561200Y-1591700D02*
Y-1606900D01*
G01X1556700Y-1591700D02*
X1545800D01*
G01X1567700D02*
X1561200D01*
G01X1546400Y-1435800D02*
Y-1418700D01*
G01X1553500Y-1421200D02*
X1552600Y-1423600D01*
G01D02*
Y-1432100D01*
G01Y-1430900D02*
X1553500Y-1433400D01*
G01D02*
X1555700Y-1435200D01*
G01D02*
X1558700Y-1435800D01*
G01D02*
X1561800Y-1435200D01*
G01Y-1419400D02*
X1558700Y-1418700D01*
G01D02*
X1555700Y-1419400D01*
G01D02*
X1553500Y-1421200D01*
G01X1545800Y1379100D02*
Y1589100D01*
G01X1556100Y1444700D02*
X1562200D01*
G01X1556100Y1461800D02*
Y1444700D01*
G01X1562200Y1461800D02*
X1556100D01*
G01X1545800Y1478000D02*
X2056300D01*
G01X1566500Y-1689200D02*
X1568800Y-1688400D01*
G01D02*
X1570800Y-1686400D01*
G01D02*
X1571800Y-1683300D01*
G01D02*
Y-1679900D01*
G01D02*
X1570800Y-1676900D01*
G01D02*
X1568800Y-1674700D01*
G01D02*
X1566500Y-1674000D01*
G01X1567700Y-1600400D02*
X1569700Y-1599900D01*
G01D02*
X1571400Y-1598200D01*
G01D02*
X1571900Y-1596000D01*
G01Y-1606900D02*
X1567700Y-1600400D01*
G01X1571900Y-1596000D02*
X1571400Y-1593800D01*
G01D02*
X1569700Y-1592300D01*
G01D02*
X1567700Y-1591700D01*
G01X1564900Y-1423600D02*
X1564000Y-1421200D01*
G01X1561800Y-1435200D02*
X1564000Y-1433400D01*
G01D02*
X1564900Y-1430900D01*
G01D02*
Y-1422400D01*
G01X1577700Y-1434000D02*
X1577000Y-1432600D01*
G01D02*
X1575500Y-1432300D01*
G01D02*
X1574200Y-1433200D01*
G01D02*
Y-1434800D01*
G01D02*
X1575500Y-1435800D01*
G01D02*
X1577000Y-1435500D01*
G01D02*
X1577700Y-1434000D01*
G01X1564000Y-1421200D02*
X1561800Y-1419400D01*
G01X1562200Y1444700D02*
X1564900Y1445600D01*
G01D02*
X1567100Y1447900D01*
G01D02*
X1568300Y1451300D01*
G01D02*
Y1455200D01*
G01X1573300Y1453200D02*
X1581800D01*
G01X1573300Y1461800D02*
Y1444700D01*
G01D02*
X1585500D01*
G01X1568300Y1455200D02*
X1567100Y1458600D01*
G01D02*
X1564900Y1461100D01*
G01D02*
X1562200Y1461800D01*
G01X1585500D02*
X1573300D01*
G01X1565300Y1568400D02*
X1572500D01*
G01D02*
X1575000Y1569000D01*
G01D02*
X1576800Y1570800D01*
G01D02*
X1577400Y1573300D01*
G01D02*
X1576800Y1575800D01*
G01X1565300Y1578200D02*
Y1561000D01*
G01X1576800Y1575800D02*
X1575000Y1577600D01*
G01D02*
X1572500Y1578200D01*
G01D02*
X1565300D01*
G01X1590400Y1461800D02*
X1596600Y1444700D01*
G01X1582400Y1561000D02*
X1588500Y1578200D01*
G01D02*
X1594700Y1561000D01*
G01X1583800Y1564700D02*
X1593400D01*
G01X1607500Y-1755800D02*
Y-1788700D01*
G01X1606100Y-1578700D02*
Y-1749600D01*
G01X1596600Y1444700D02*
X1602700Y1461800D01*
G01X1607500Y1453200D02*
X1616100D01*
G01X1607500Y1461800D02*
Y1444700D01*
G01D02*
X1619800D01*
G01Y1461800D02*
X1607500D01*
G01X1599600Y1568400D02*
X1606900D01*
G01D02*
X1609300Y1569000D01*
G01D02*
X1611100Y1570800D01*
G01D02*
X1611800Y1573300D01*
G01D02*
X1611100Y1575800D01*
G01X1599600Y1578200D02*
Y1561000D01*
G01X1611800D02*
X1606900Y1568400D01*
G01X1611100Y1575800D02*
X1609300Y1577600D01*
G01D02*
X1606900Y1578200D01*
G01D02*
X1599600D01*
G01X1607500Y1628200D02*
Y1595300D01*
G01X1624700Y1461800D02*
Y1444700D01*
G01D02*
X1636900D01*
G01X1622900Y1578200D02*
Y1561000D01*
G01X1616700Y1578200D02*
X1628900D01*
G01X1641900Y1456900D02*
Y1448400D01*
G01Y1449500D02*
X1642700Y1447200D01*
G01D02*
X1644900Y1445400D01*
G01D02*
X1648000Y1444700D01*
G01D02*
X1651100Y1445400D01*
G01Y1461200D02*
X1648000Y1461800D01*
G01D02*
X1644900Y1461200D01*
G01D02*
X1642700Y1459400D01*
G01D02*
X1641900Y1456900D01*
G01X1651100Y1445400D02*
X1653300Y1447200D01*
G01D02*
X1654200Y1449500D01*
G01D02*
Y1458100D01*
G01X1659100Y1452100D02*
X1666400D01*
G01X1659100Y1461800D02*
Y1444700D01*
G01X1654200Y1456900D02*
X1653300Y1459400D01*
G01D02*
X1651100Y1461200D01*
G01X1666400Y1461800D02*
X1659100D01*
G01X1652300Y1561000D02*
Y1578200D01*
G01D02*
X1662000Y1561000D01*
G01D02*
Y1578200D01*
G01X1666400Y1452100D02*
X1668800Y1452600D01*
G01D02*
X1670600Y1454600D01*
G01X1676200Y1444700D02*
Y1461800D01*
G01D02*
X1682200Y1448400D01*
G01D02*
X1688400Y1461800D01*
G01X1670600Y1454600D02*
X1671300Y1456900D01*
G01D02*
X1670600Y1459400D01*
G01D02*
X1668800Y1461200D01*
G01D02*
X1666400Y1461800D01*
G01X1680500Y1573300D02*
X1679600Y1575800D01*
G01X1669000D02*
X1668200Y1573300D01*
G01D02*
Y1564700D01*
G01Y1565900D02*
X1669000Y1563500D01*
G01D02*
X1671200Y1561600D01*
G01D02*
X1674300Y1561000D01*
G01D02*
X1677400Y1561600D01*
G01D02*
X1679600Y1563500D01*
G01D02*
X1680500Y1565900D01*
G01D02*
Y1574500D01*
G01X1679600Y1575800D02*
X1677400Y1577600D01*
G01D02*
X1674300Y1578200D01*
G01D02*
X1671200Y1577600D01*
G01D02*
X1669000Y1575800D01*
G01X1688400Y1461800D02*
Y1444700D01*
G01X1693300Y1453200D02*
X1701900D01*
G01X1693300Y1461800D02*
Y1444700D01*
G01D02*
X1705600D01*
G01Y1461800D02*
X1693300D01*
G01Y1562800D02*
X1692600Y1564300D01*
G01D02*
X1691000Y1564700D01*
G01D02*
X1689800Y1563700D01*
G01D02*
Y1562100D01*
G01D02*
X1691000Y1561000D01*
G01D02*
X1692600Y1561500D01*
G01D02*
X1693300Y1562800D01*
G01X1711800Y1444700D02*
Y1461800D01*
G01D02*
X1721500Y1444700D01*
G01D02*
Y1461800D01*
G01X1733800D02*
Y1444700D01*
G01X1727600Y1461800D02*
X1739800D01*
G01X1754400Y-1407900D02*
Y-1494300D01*
G01X1767200Y-1427400D02*
X1773700D01*
G01X1767200Y-1418700D02*
Y-1433900D01*
G01X1773700Y-1418700D02*
X1767200D01*
G01X1763200Y1444700D02*
Y1461800D01*
G01D02*
X1772900Y1444700D01*
G01X1783200Y-1426400D02*
X1790900D01*
G01X1783200Y-1418700D02*
Y-1433900D01*
G01D02*
X1794100D01*
G01X1773700Y-1427400D02*
X1775900Y-1426800D01*
G01D02*
X1777500Y-1425200D01*
G01D02*
X1778100Y-1423100D01*
G01D02*
X1777500Y-1420900D01*
G01X1778100Y-1433900D02*
X1773700Y-1427400D01*
G01X1794100Y-1418700D02*
X1783200D01*
G01X1777500Y-1420900D02*
X1775900Y-1419300D01*
G01D02*
X1773700Y-1418700D01*
G01X1772900Y1444700D02*
Y1461800D01*
G01X1779100Y1456900D02*
Y1448400D01*
G01Y1449500D02*
X1780000Y1447200D01*
G01D02*
X1782200Y1445400D01*
G01D02*
X1785200Y1444700D01*
G01D02*
X1788300Y1445400D01*
G01Y1461200D02*
X1785200Y1461800D01*
G01D02*
X1782200Y1461200D01*
G01D02*
X1780000Y1459400D01*
G01D02*
X1779100Y1456900D01*
G01X1799100Y-1418700D02*
X1804600Y-1433900D01*
G01D02*
X1810000Y-1418700D01*
G01X1788300Y1445400D02*
X1790500Y1447200D01*
G01D02*
X1791400Y1449500D01*
G01D02*
Y1458100D01*
G01X1804200Y1446600D02*
X1803500Y1447900D01*
G01D02*
X1802000Y1448400D01*
G01D02*
X1800700Y1447300D01*
G01D02*
Y1445700D01*
G01D02*
X1802000Y1444700D01*
G01D02*
X1803500Y1445100D01*
G01D02*
X1804200Y1446600D01*
G01X1791400Y1456900D02*
X1790500Y1459400D01*
G01D02*
X1788300Y1461200D01*
G01X1823100Y1605500D02*
X1822700Y1603600D01*
G01D02*
Y1600000D01*
G01D02*
X1841100D01*
G01X1823500Y1621400D02*
X1822700Y1618300D01*
G01X1837700Y-1774400D02*
X1841000Y-1772500D01*
G01X1837700Y-1774400D02*
X1827700Y-1778100D01*
G01D02*
X1826200Y-1779100D01*
G01D02*
X1825200Y-1780600D01*
G01D02*
X1824700Y-1782400D01*
G01D02*
Y-1786000D01*
G01D02*
X1843200D01*
G01X1841700Y-1763800D02*
X1838900Y-1761500D01*
G01D02*
X1835200Y-1760500D01*
G01D02*
X1831400Y-1760600D01*
G01D02*
X1828000Y-1762100D01*
G01D02*
X1825600Y-1764600D01*
G01D02*
X1824700Y-1767700D01*
G01X1823400Y-1578700D02*
Y-1749600D01*
G01Y-1576800D02*
Y-1583600D01*
G01Y-1407900D02*
Y-1494300D01*
G01X1835800Y1611700D02*
X1825600Y1608000D01*
G01D02*
X1824100Y1606900D01*
G01D02*
X1823100Y1605500D01*
G01X1835700Y1611700D02*
X1838900Y1613600D01*
G01D02*
X1840700Y1616200D01*
G01X1841000Y1619400D02*
X1839600Y1622300D01*
G01D02*
X1836800Y1624500D01*
G01D02*
X1833100Y1625600D01*
G01D02*
X1829300Y1625400D01*
G01D02*
X1825900Y1623900D01*
G01D02*
X1823500Y1621400D01*
G01X1841000Y-1772500D02*
X1842700Y-1769800D01*
G01D02*
X1843000Y-1766700D01*
G01D02*
X1841700Y-1763800D01*
G01X1840700Y1616200D02*
X1841000Y1619400D01*
G01X1949200Y1478000D02*
Y1379100D01*
G01X1959500Y1456900D02*
Y1449500D01*
G01D02*
X1960400Y1447200D01*
G01D02*
X1962600Y1445400D01*
G01Y1461200D02*
X1960400Y1459400D01*
G01D02*
X1959500Y1456900D01*
G01X1949200Y1589100D02*
Y1478000D01*
G01X1959500Y1578200D02*
Y1563000D01*
G01Y1569500D02*
X1966000D01*
G01Y1578200D02*
X1959500D01*
G01X1962600Y1445400D02*
X1965700Y1444700D01*
G01D02*
X1968700Y1445400D01*
G01D02*
X1971100Y1447200D01*
G01D02*
X1971800Y1449500D01*
G01D02*
Y1456900D01*
G01X1965700Y1450900D02*
X1973000Y1443500D01*
G01X1976700Y1444700D02*
X1988900Y1461800D01*
G01X1971800Y1456900D02*
X1971100Y1459400D01*
G01D02*
X1968700Y1461200D01*
G01D02*
X1965700Y1461800D01*
G01D02*
X1962600Y1461200D01*
G01X1970400Y1563000D02*
X1966000Y1569500D01*
G01X1970400Y1573800D02*
X1969800Y1576000D01*
G01Y1571700D02*
X1970400Y1573800D01*
G01X1968200Y1570100D02*
X1969800Y1571700D01*
G01X1966000Y1569500D02*
X1968200Y1570100D01*
G01X1975500Y1570500D02*
X1983200D01*
G01X1975500Y1578200D02*
Y1563000D01*
G01D02*
X1986400D01*
G01X1968200Y1577600D02*
X1966000Y1578200D01*
G01X1969800Y1576000D02*
X1968200Y1577600D01*
G01X1986400Y1578200D02*
X1975500D01*
G01X1993800Y1444700D02*
Y1461800D01*
G01D02*
X2000000Y1448400D01*
G01X1996900Y1563000D02*
X2002300Y1578200D01*
G01X1991400D02*
X1996900Y1563000D01*
G01X2000000Y1448400D02*
X2006000Y1461800D01*
G01D02*
Y1444700D01*
G01X2056300Y1589100D02*
Y-1749600D01*
G01X2062500Y-1412000D02*
X2095400D01*
G01X2062500Y-1078500D02*
X2095400D01*
G01X2062500Y-745100D02*
X2095400D01*
G01X2062500Y-411500D02*
X2095400D01*
G01X2062500Y-82400D02*
X2105700D01*
G01X2062500Y251200D02*
X2095400D01*
G01X2062500Y584600D02*
X2095400D01*
G01X2062500Y918100D02*
X2095400D01*
G01X2062500Y1251500D02*
X2095400D01*
G01X2071000Y-1735700D02*
X2070400Y-1737200D01*
G01D02*
X2071000Y-1738800D01*
G01D02*
X2072600Y-1739800D01*
G01D02*
X2074700Y-1740300D01*
G01X2070400Y-1746500D02*
X2074700D01*
G01D02*
X2076900Y-1746000D01*
G01D02*
X2078500Y-1745000D01*
G01D02*
X2079100Y-1743400D01*
G01D02*
X2078500Y-1741900D01*
G01D02*
X2076900Y-1740700D01*
G01D02*
X2074700Y-1740300D01*
G01X2070400Y-1728000D02*
X2074700D01*
G01D02*
X2076900Y-1727100D01*
G01D02*
X2078500Y-1724900D01*
G01D02*
X2079100Y-1721800D01*
G01D02*
X2078500Y-1718700D01*
G01X2070400Y-1715600D02*
Y-1728000D01*
G01X2079100Y-1734100D02*
X2074700D01*
G01D02*
X2072600Y-1734500D01*
G01D02*
X2071000Y-1735700D01*
G01X2070400Y-1704100D02*
X2075600D01*
G01D02*
X2077700Y-1703500D01*
G01D02*
X2079000Y-1701700D01*
G01X2070400Y-1697000D02*
Y-1709400D01*
G01X2078500Y-1718700D02*
X2076900Y-1716400D01*
G01D02*
X2074700Y-1715600D01*
G01D02*
X2070400D01*
G01X2079000Y-1701700D02*
Y-1699500D01*
G01D02*
X2077700Y-1697700D01*
G01D02*
X2075600Y-1697000D01*
G01D02*
X2070400D01*
G01X2068700Y-1593700D02*
X2077800Y-1568000D01*
G01D02*
X2087100Y-1593700D01*
G01X2070600Y-1588200D02*
X2085000D01*
G01X2068700Y-1232300D02*
Y-1258000D01*
G01D02*
X2077800D01*
G01D02*
X2081400Y-1257600D01*
G01D02*
X2084300Y-1256000D01*
G01D02*
X2086400Y-1253600D01*
G01Y-1248000D02*
X2084300Y-1245500D01*
G01D02*
X2081400Y-1244000D01*
G01D02*
X2077800Y-1243400D01*
G01D02*
X2068700D01*
G01X2077800D02*
X2081100Y-1242800D01*
G01D02*
X2083600Y-1241300D01*
G01D02*
X2085000Y-1239100D01*
G01Y-1236600D02*
X2083600Y-1234400D01*
G01D02*
X2081100Y-1232900D01*
G01D02*
X2077800Y-1232300D01*
G01D02*
X2068700D01*
G01Y-904400D02*
Y-919200D01*
G01D02*
X2069400Y-921200D01*
G01D02*
X2071300Y-923000D01*
G01D02*
X2074400Y-924200D01*
G01D02*
X2077800Y-924600D01*
G01D02*
X2087100D01*
G01X2074400Y-899400D02*
X2071300Y-900600D01*
G01D02*
X2069400Y-902300D01*
G01D02*
X2068700Y-904400D01*
G01X2087100Y-898900D02*
X2077800D01*
G01D02*
X2074400Y-899400D01*
G01X2068700Y-591200D02*
X2077800D01*
G01D02*
X2081400Y-590200D01*
G01D02*
X2084300Y-587400D01*
G01D02*
X2086400Y-583300D01*
G01X2068700Y-565400D02*
Y-591200D01*
G01X2086400Y-573400D02*
X2084300Y-569200D01*
G01D02*
X2081400Y-566400D01*
G01D02*
X2077800Y-565400D01*
G01D02*
X2068700D01*
G01Y-232000D02*
Y-257700D01*
G01D02*
X2087100D01*
G01X2068700Y-244800D02*
X2081500D01*
G01X2087100Y-232000D02*
X2068700D01*
G01Y71500D02*
Y97300D01*
G01Y84300D02*
X2081500D01*
G01X2068700Y97300D02*
X2087100D01*
G01X2071300Y408000D02*
X2073500Y405800D01*
G01D02*
X2076000Y405000D01*
G01D02*
X2087100D01*
G01X2071300Y427800D02*
X2069700Y424200D01*
G01D02*
X2068800Y420100D01*
G01D02*
Y415700D01*
G01D02*
X2069700Y411400D01*
G01D02*
X2071300Y408000D01*
G01X2087100Y417900D02*
X2079700D01*
G01X2087100Y430700D02*
X2076000D01*
G01D02*
X2073500Y430000D01*
G01D02*
X2071300Y427800D01*
G01X2068700Y764100D02*
Y738400D01*
G01Y751300D02*
X2087100D01*
G01X2068700Y1079200D02*
X2069400Y1076400D01*
G01D02*
X2071300Y1074100D01*
G01D02*
X2074400Y1072400D01*
G01D02*
X2077800Y1072000D01*
G01D02*
X2081400Y1072400D01*
G01D02*
X2084300Y1074100D01*
G01D02*
X2086400Y1076400D01*
G01X2068700Y1433200D02*
Y1407500D01*
G01Y1418500D02*
X2087100Y1433200D01*
G01X2075000Y1423600D02*
X2087100Y1407500D01*
G01X2086400Y-1253600D02*
X2087100Y-1250800D01*
G01D02*
X2086400Y-1248000D01*
G01X2085000Y-1239100D02*
Y-1236600D01*
G01X2086400Y-583300D02*
X2087100Y-578400D01*
G01D02*
X2086400Y-573400D01*
G01X2087100Y405000D02*
Y417900D01*
G01Y764100D02*
Y738400D01*
G01X2086400Y1076400D02*
X2087100Y1079200D01*
G01D02*
Y1097700D01*
G54D17*
X22834Y340080D03*
X26378D03*
X28150Y343150D03*
X24606D03*
X29922Y340080D03*
X33466D03*
X37010D03*
X40554D03*
X44098D03*
X45870Y343150D03*
X42326D03*
X38782D03*
X35238D03*
X31694D03*
X873950Y298500D03*
G54D27*
G01X-2400850Y-1730000D02*
Y-1705000D01*
X-2392975D01*
X-2390455Y-1706250D01*
X-2388880Y-1707917D01*
X-2388250Y-1711250D01*
X-2388880Y-1714584D01*
X-2390770Y-1716666D01*
X-2392975Y-1717917D01*
X-2400850D01*
G01X-2392975D02*
X-2388250Y-1730000D01*
G01X-2365570D02*
Y-1705000D01*
X-2377225Y-1722917D01*
X-2361475D01*
G01X-2344150Y-1705000D02*
X-2346670Y-1705833D01*
X-2348560Y-1707917D01*
X-2349820Y-1710416D01*
X-2350765Y-1713750D01*
X-2351080Y-1717500D01*
X-2350765Y-1721250D01*
X-2349820Y-1724584D01*
X-2348560Y-1727084D01*
X-2346670Y-1729167D01*
X-2344150Y-1730000D01*
X-2341630Y-1729167D01*
X-2339740Y-1727084D01*
X-2338480Y-1724584D01*
X-2337535Y-1721250D01*
X-2337220Y-1717500D01*
X-2337535Y-1713750D01*
X-2338480Y-1710416D01*
X-2339740Y-1707917D01*
X-2341630Y-1705833D01*
X-2344150Y-1705000D01*
G01X-2318950D02*
X-2321470Y-1705833D01*
X-2323360Y-1707917D01*
X-2324620Y-1710416D01*
X-2325565Y-1713750D01*
X-2325880Y-1717500D01*
X-2325565Y-1721250D01*
X-2324620Y-1724584D01*
X-2323360Y-1727084D01*
X-2321470Y-1729167D01*
X-2318950Y-1730000D01*
X-2316430Y-1729167D01*
X-2314540Y-1727084D01*
X-2313280Y-1724584D01*
X-2312335Y-1721250D01*
X-2312020Y-1717500D01*
X-2312335Y-1713750D01*
X-2313280Y-1710416D01*
X-2314540Y-1707917D01*
X-2316430Y-1705833D01*
X-2318950Y-1705000D01*
G01X-2299735Y-1719584D02*
X-2297530Y-1716666D01*
X-2295640Y-1715000D01*
X-2293120Y-1714167D01*
X-2290915Y-1715000D01*
X-2289340Y-1716666D01*
X-2288080Y-1719167D01*
X-2287765Y-1722083D01*
X-2288080Y-1724584D01*
X-2289340Y-1727084D01*
X-2291230Y-1729167D01*
X-2293435Y-1730000D01*
X-2295955Y-1729167D01*
X-2298160Y-1726667D01*
X-2299420Y-1722917D01*
X-2299735Y-1718750D01*
X-2299105Y-1713334D01*
X-2298160Y-1710416D01*
X-2296585Y-1707500D01*
X-2294380Y-1705417D01*
X-2292175Y-1705000D01*
X-2289970Y-1705833D01*
X-2288395Y-1707917D01*
G01X-2272645Y-1721667D02*
X-2264455D01*
G01X-2240830Y-1716666D02*
X-2239570Y-1715417D01*
X-2238625Y-1713334D01*
X-2237995Y-1710416D01*
X-2238625Y-1707917D01*
X-2239885Y-1706250D01*
X-2242090Y-1705000D01*
X-2250595D01*
Y-1730000D01*
X-2240200D01*
X-2237995Y-1728334D01*
X-2236735Y-1725833D01*
X-2236105Y-1722917D01*
X-2236735Y-1720001D01*
X-2238625Y-1717500D01*
X-2240830Y-1716666D01*
X-2250595D01*
G01X-2218150Y-1705000D02*
X-2220670Y-1705833D01*
X-2222560Y-1707917D01*
X-2223820Y-1710416D01*
X-2224765Y-1713750D01*
X-2225080Y-1717500D01*
X-2224765Y-1721250D01*
X-2223820Y-1724584D01*
X-2222560Y-1727084D01*
X-2220670Y-1729167D01*
X-2218150Y-1730000D01*
X-2215630Y-1729167D01*
X-2213740Y-1727084D01*
X-2212480Y-1724584D01*
X-2211535Y-1721250D01*
X-2211220Y-1717500D01*
X-2211535Y-1713750D01*
X-2212480Y-1710416D01*
X-2213740Y-1707917D01*
X-2215630Y-1705833D01*
X-2218150Y-1705000D01*
G01X-2192950D02*
X-2195470Y-1705833D01*
X-2197360Y-1707917D01*
X-2198620Y-1710416D01*
X-2199565Y-1713750D01*
X-2199880Y-1717500D01*
X-2199565Y-1721250D01*
X-2198620Y-1724584D01*
X-2197360Y-1727084D01*
X-2195470Y-1729167D01*
X-2192950Y-1730000D01*
X-2190430Y-1729167D01*
X-2188540Y-1727084D01*
X-2187280Y-1724584D01*
X-2186335Y-1721250D01*
X-2186020Y-1717500D01*
X-2186335Y-1713750D01*
X-2187280Y-1710416D01*
X-2188540Y-1707917D01*
X-2190430Y-1705833D01*
X-2192950Y-1705000D01*
G01X-2167750D02*
X-2170270Y-1705833D01*
X-2172160Y-1707917D01*
X-2173420Y-1710416D01*
X-2174365Y-1713750D01*
X-2174680Y-1717500D01*
X-2174365Y-1721250D01*
X-2173420Y-1724584D01*
X-2172160Y-1727084D01*
X-2170270Y-1729167D01*
X-2167750Y-1730000D01*
X-2165230Y-1729167D01*
X-2163340Y-1727084D01*
X-2162080Y-1724584D01*
X-2161135Y-1721250D01*
X-2160820Y-1717500D01*
X-2161135Y-1713750D01*
X-2162080Y-1710416D01*
X-2163340Y-1707917D01*
X-2165230Y-1705833D01*
X-2167750Y-1705000D01*
G01X-2142550Y-1730000D02*
Y-1705000D01*
X-2146330Y-1710000D01*
G01Y-1730000D02*
X-2138771D01*
G01X-2121445Y-1721667D02*
X-2113255D01*
G01X-2092150Y-1705000D02*
X-2094670Y-1705833D01*
X-2096560Y-1707917D01*
X-2097820Y-1710416D01*
X-2098765Y-1713750D01*
X-2099080Y-1717500D01*
X-2098765Y-1721250D01*
X-2097820Y-1724584D01*
X-2096560Y-1727084D01*
X-2094670Y-1729167D01*
X-2092150Y-1730000D01*
X-2089630Y-1729167D01*
X-2087740Y-1727084D01*
X-2086480Y-1724584D01*
X-2085535Y-1721250D01*
X-2085220Y-1717500D01*
X-2085535Y-1713750D01*
X-2086480Y-1710416D01*
X-2087740Y-1707917D01*
X-2089630Y-1705833D01*
X-2092150Y-1705000D01*
G01X-2072935Y-1709167D02*
X-2071045Y-1706667D01*
X-2068840Y-1705417D01*
X-2066320Y-1705000D01*
X-2063170Y-1705833D01*
X-2060965Y-1707917D01*
X-2060335Y-1710416D01*
X-2060650Y-1712917D01*
X-2061910Y-1715000D01*
X-2068210Y-1719167D01*
X-2071045Y-1722083D01*
X-2072935Y-1726251D01*
X-2073565Y-1730000D01*
X-2060335D01*
G01X-2231929Y1277044D02*
Y1295844D01*
X-2221119Y1277044D01*
Y1295844D01*
G01X-2207724Y1277044D02*
X-2209604Y1277357D01*
X-2211249Y1278610D01*
X-2212659Y1280491D01*
X-2213599Y1282684D01*
X-2214069Y1285191D01*
Y1287697D01*
X-2213599Y1290204D01*
X-2212659Y1292397D01*
X-2211249Y1294277D01*
X-2209604Y1295531D01*
X-2207724Y1295844D01*
X-2205844Y1295531D01*
X-2204199Y1294277D01*
X-2202789Y1292397D01*
X-2201849Y1290204D01*
X-2201379Y1287697D01*
Y1285191D01*
X-2201849Y1282684D01*
X-2202789Y1280491D01*
X-2204199Y1278610D01*
X-2205844Y1277357D01*
X-2207724Y1277044D01*
G01X-2188924Y1295844D02*
Y1277044D01*
G01X-2194329Y1295844D02*
X-2183519D01*
G01X-2165424Y1277044D02*
X-2174824D01*
Y1295844D01*
X-2165424D01*
G01X-2169184Y1286758D02*
X-2174824D01*
G01X-2156259Y1279550D02*
X-2154379Y1277984D01*
X-2152264Y1277044D01*
X-2150384D01*
X-2148504Y1277984D01*
X-2147094Y1279550D01*
X-2146389Y1281744D01*
X-2146859Y1283937D01*
X-2148034Y1285817D01*
X-2150149Y1287071D01*
X-2152969Y1287697D01*
X-2154614Y1288950D01*
X-2155319Y1291144D01*
X-2154849Y1293337D01*
X-2153674Y1294904D01*
X-2152029Y1295844D01*
X-2150384D01*
X-2148739Y1295217D01*
X-2147329Y1293651D01*
G01X-2132524Y1276417D02*
X-2132994Y1276731D01*
Y1277357D01*
X-2132524Y1277671D01*
X-2132054Y1277357D01*
Y1276731D01*
X-2132524Y1276417D01*
G01Y1284877D02*
X-2132994Y1285191D01*
Y1285817D01*
X-2132524Y1286130D01*
X-2132054Y1285817D01*
Y1285191D01*
X-2132524Y1284877D01*
G01X-2100094Y1295844D02*
Y1282371D01*
X-2099154Y1279550D01*
X-2097274Y1277671D01*
X-2094924Y1277044D01*
X-2092574Y1277671D01*
X-2090694Y1279550D01*
X-2089754Y1282371D01*
Y1295844D01*
G01X-2080119Y1277044D02*
Y1289577D01*
G01Y1286444D02*
X-2079179Y1288011D01*
X-2077769Y1289264D01*
X-2075889Y1289577D01*
X-2074244Y1289264D01*
X-2072834Y1288011D01*
X-2072129Y1285817D01*
Y1277044D01*
G01X-2057324D02*
Y1295844D01*
G01X-2042049Y1285504D02*
X-2034529D01*
X-2035234Y1287697D01*
X-2036409Y1288950D01*
X-2038054Y1289577D01*
X-2039699Y1289264D01*
X-2041109Y1288324D01*
X-2042049Y1286130D01*
X-2042519Y1284250D01*
Y1282371D01*
X-2042049Y1280491D01*
X-2040874Y1278610D01*
X-2039464Y1277357D01*
X-2037819Y1277044D01*
X-2036174Y1277671D01*
X-2034529Y1279550D01*
G01X-2023249Y1279237D02*
X-2022074Y1277984D01*
X-2020429Y1277044D01*
X-2019019D01*
X-2017609Y1277671D01*
X-2016669Y1278610D01*
X-2016199Y1279863D01*
X-2016434Y1281744D01*
X-2017374Y1282684D01*
X-2021604Y1284564D01*
X-2022544Y1286758D01*
X-2022074Y1288324D01*
X-2021134Y1289264D01*
X-2019724Y1289577D01*
X-2018314Y1289264D01*
X-2016904Y1288324D01*
G01X-2004449Y1279237D02*
X-2003274Y1277984D01*
X-2001629Y1277044D01*
X-2000219D01*
X-1998809Y1277671D01*
X-1997869Y1278610D01*
X-1997399Y1279863D01*
X-1997634Y1281744D01*
X-1998574Y1282684D01*
X-2002804Y1284564D01*
X-2003744Y1286758D01*
X-2003274Y1288324D01*
X-2002334Y1289264D01*
X-2000924Y1289577D01*
X-1999514Y1289264D01*
X-1998104Y1288324D01*
G01X-1963324Y1277044D02*
X-1964734Y1277357D01*
X-1966144Y1278610D01*
X-1967084Y1280804D01*
X-1967554Y1283310D01*
X-1967084Y1285817D01*
X-1966144Y1288011D01*
X-1964734Y1289264D01*
X-1963324Y1289577D01*
X-1961914Y1289264D01*
X-1960504Y1288011D01*
X-1959564Y1285817D01*
X-1959329Y1283310D01*
X-1959564Y1280804D01*
X-1960504Y1278610D01*
X-1961914Y1277357D01*
X-1963324Y1277044D01*
G01X-1944524Y1295844D02*
Y1277044D01*
G01X-1947814Y1289577D02*
X-1941234D01*
G01X-1929719Y1277044D02*
Y1295844D01*
G01Y1286758D02*
X-1928544Y1288324D01*
X-1927369Y1289264D01*
X-1925489Y1289577D01*
X-1924079Y1289264D01*
X-1922434Y1288011D01*
X-1921729Y1286130D01*
Y1277044D01*
G01X-1910449Y1285504D02*
X-1902929D01*
X-1903634Y1287697D01*
X-1904809Y1288950D01*
X-1906454Y1289577D01*
X-1908099Y1289264D01*
X-1909509Y1288324D01*
X-1910449Y1286130D01*
X-1910919Y1284250D01*
Y1282371D01*
X-1910449Y1280491D01*
X-1909274Y1278610D01*
X-1907864Y1277357D01*
X-1906219Y1277044D01*
X-1904574Y1277671D01*
X-1902929Y1279550D01*
G01X-1891414Y1277044D02*
Y1289577D01*
G01Y1287071D02*
X-1890239Y1288324D01*
X-1889064Y1289264D01*
X-1887419Y1289577D01*
X-1886244Y1289264D01*
X-1884834Y1288324D01*
G01X-1875199Y1289577D02*
X-1872379Y1277044D01*
X-1869324Y1289577D01*
X-1866269Y1277044D01*
X-1863449Y1289577D01*
G01X-1850524D02*
Y1277044D01*
G01Y1294590D02*
X-1850994Y1294904D01*
Y1295531D01*
X-1850524Y1295844D01*
X-1850054Y1295531D01*
Y1294904D01*
X-1850524Y1294590D01*
G01X-1835249Y1279237D02*
X-1834074Y1277984D01*
X-1832429Y1277044D01*
X-1831019D01*
X-1829609Y1277671D01*
X-1828669Y1278610D01*
X-1828199Y1279863D01*
X-1828434Y1281744D01*
X-1829374Y1282684D01*
X-1833604Y1284564D01*
X-1834544Y1286758D01*
X-1834074Y1288324D01*
X-1833134Y1289264D01*
X-1831724Y1289577D01*
X-1830314Y1289264D01*
X-1828904Y1288324D01*
G01X-1816449Y1285504D02*
X-1808929D01*
X-1809634Y1287697D01*
X-1810809Y1288950D01*
X-1812454Y1289577D01*
X-1814099Y1289264D01*
X-1815509Y1288324D01*
X-1816449Y1286130D01*
X-1816919Y1284250D01*
Y1282371D01*
X-1816449Y1280491D01*
X-1815274Y1278610D01*
X-1813864Y1277357D01*
X-1812219Y1277044D01*
X-1810574Y1277671D01*
X-1808929Y1279550D01*
G01X-1778849Y1279237D02*
X-1777674Y1277984D01*
X-1776029Y1277044D01*
X-1774619D01*
X-1773209Y1277671D01*
X-1772269Y1278610D01*
X-1771799Y1279863D01*
X-1772034Y1281744D01*
X-1772974Y1282684D01*
X-1777204Y1284564D01*
X-1778144Y1286758D01*
X-1777674Y1288324D01*
X-1776734Y1289264D01*
X-1775324Y1289577D01*
X-1773914Y1289264D01*
X-1772504Y1288324D01*
G01X-1760754Y1270778D02*
Y1289577D01*
G01Y1286758D02*
X-1759579Y1288324D01*
X-1758404Y1289264D01*
X-1756524Y1289577D01*
X-1754879Y1289264D01*
X-1753234Y1287697D01*
X-1752529Y1285504D01*
X-1752294Y1283310D01*
X-1752529Y1281117D01*
X-1753234Y1278924D01*
X-1754644Y1277671D01*
X-1756524Y1277044D01*
X-1758169Y1277357D01*
X-1759814Y1278297D01*
X-1760754Y1279550D01*
G01X-1741249Y1285504D02*
X-1733729D01*
X-1734434Y1287697D01*
X-1735609Y1288950D01*
X-1737254Y1289577D01*
X-1738899Y1289264D01*
X-1740309Y1288324D01*
X-1741249Y1286130D01*
X-1741719Y1284250D01*
Y1282371D01*
X-1741249Y1280491D01*
X-1740074Y1278610D01*
X-1738664Y1277357D01*
X-1737019Y1277044D01*
X-1735374Y1277671D01*
X-1733729Y1279550D01*
G01X-1715164Y1288011D02*
X-1716809Y1289264D01*
X-1718219Y1289577D01*
X-1720099Y1288950D01*
X-1721509Y1287697D01*
X-1722449Y1285504D01*
X-1722684Y1283310D01*
X-1722449Y1281117D01*
X-1721509Y1279237D01*
X-1720099Y1277671D01*
X-1718219Y1277044D01*
X-1716574Y1277671D01*
X-1715164Y1278924D01*
G01X-1700124Y1289577D02*
Y1277044D01*
G01Y1294590D02*
X-1700594Y1294904D01*
Y1295531D01*
X-1700124Y1295844D01*
X-1699654Y1295531D01*
Y1294904D01*
X-1700124Y1294590D01*
G01X-1682734Y1277044D02*
Y1293024D01*
X-1682264Y1294590D01*
X-1681324Y1295531D01*
X-1679914Y1295844D01*
X-1678504Y1295217D01*
X-1677799Y1293651D01*
G01X-1680619Y1288324D02*
X-1685319D01*
G01X-1662524Y1289577D02*
Y1277044D01*
G01Y1294590D02*
X-1662994Y1294904D01*
Y1295531D01*
X-1662524Y1295844D01*
X-1662054Y1295531D01*
Y1294904D01*
X-1662524Y1294590D01*
G01X-1647249Y1285504D02*
X-1639729D01*
X-1640434Y1287697D01*
X-1641609Y1288950D01*
X-1643254Y1289577D01*
X-1644899Y1289264D01*
X-1646309Y1288324D01*
X-1647249Y1286130D01*
X-1647719Y1284250D01*
Y1282371D01*
X-1647249Y1280491D01*
X-1646074Y1278610D01*
X-1644664Y1277357D01*
X-1643019Y1277044D01*
X-1641374Y1277671D01*
X-1639729Y1279550D01*
G01X-1620694Y1295844D02*
Y1277044D01*
G01Y1279863D02*
X-1621634Y1278297D01*
X-1623044Y1277357D01*
X-1624689Y1277044D01*
X-1626569Y1277671D01*
X-1627979Y1279237D01*
X-1628919Y1281117D01*
X-1629154Y1283310D01*
X-1628919Y1285504D01*
X-1627979Y1287384D01*
X-1626569Y1288950D01*
X-1624689Y1289577D01*
X-1623044Y1289264D01*
X-1621869Y1288637D01*
X-1620694Y1287384D01*
G01X-2135724Y-1281456D02*
Y-1265856D01*
X-2138064Y-1268976D01*
G01Y-1281456D02*
X-2133384D01*
G01X-2115484D02*
Y-1265856D01*
X-2122699Y-1277036D01*
X-2112949D01*
G01X-2099924Y-1281976D02*
X-2100314Y-1281716D01*
Y-1281196D01*
X-2099924Y-1280936D01*
X-2099534Y-1281196D01*
Y-1281716D01*
X-2099924Y-1281976D01*
G01X-2085924Y-1281456D02*
Y-1265856D01*
X-2081244D01*
X-2079684Y-1266636D01*
X-2078514Y-1268456D01*
X-2078124Y-1270536D01*
X-2078514Y-1272616D01*
X-2079489Y-1274176D01*
X-2081244Y-1274956D01*
X-2085924D01*
G01X-2064124Y-1281456D02*
Y-1265856D01*
G01X-2049149Y-1274436D02*
X-2042909D01*
X-2043494Y-1272616D01*
X-2044469Y-1271576D01*
X-2045834Y-1271056D01*
X-2047199Y-1271316D01*
X-2048369Y-1272096D01*
X-2049149Y-1273916D01*
X-2049539Y-1275476D01*
Y-1277036D01*
X-2049149Y-1278596D01*
X-2048174Y-1280156D01*
X-2047004Y-1281196D01*
X-2045639Y-1281456D01*
X-2044274Y-1280936D01*
X-2042909Y-1279376D01*
G01X-2024814Y-1281456D02*
Y-1271056D01*
G01Y-1272876D02*
X-2025594Y-1271836D01*
X-2026764Y-1271316D01*
X-2028129Y-1271056D01*
X-2029494Y-1271576D01*
X-2030664Y-1272616D01*
X-2031444Y-1274176D01*
X-2031834Y-1276256D01*
X-2031444Y-1278336D01*
X-2030664Y-1279896D01*
X-2029494Y-1280936D01*
X-2028129Y-1281456D01*
X-2026764Y-1281196D01*
X-2025594Y-1280416D01*
X-2024814Y-1279376D01*
G01X-2013349Y-1279636D02*
X-2012374Y-1280676D01*
X-2011009Y-1281456D01*
X-2009839D01*
X-2008669Y-1280936D01*
X-2007889Y-1280156D01*
X-2007499Y-1279116D01*
X-2007694Y-1277556D01*
X-2008474Y-1276776D01*
X-2011984Y-1275216D01*
X-2012764Y-1273396D01*
X-2012374Y-1272096D01*
X-2011594Y-1271316D01*
X-2010424Y-1271056D01*
X-2009254Y-1271316D01*
X-2008084Y-1272096D01*
G01X-1995449Y-1274436D02*
X-1989209D01*
X-1989794Y-1272616D01*
X-1990769Y-1271576D01*
X-1992134Y-1271056D01*
X-1993499Y-1271316D01*
X-1994669Y-1272096D01*
X-1995449Y-1273916D01*
X-1995839Y-1275476D01*
Y-1277036D01*
X-1995449Y-1278596D01*
X-1994474Y-1280156D01*
X-1993304Y-1281196D01*
X-1991939Y-1281456D01*
X-1990574Y-1280936D01*
X-1989209Y-1279376D01*
G01X-1960234Y-1286656D02*
Y-1271056D01*
G01Y-1273396D02*
X-1959259Y-1272096D01*
X-1958284Y-1271316D01*
X-1956724Y-1271056D01*
X-1955359Y-1271316D01*
X-1953994Y-1272616D01*
X-1953409Y-1274436D01*
X-1953214Y-1276256D01*
X-1953409Y-1278076D01*
X-1953994Y-1279896D01*
X-1955164Y-1280936D01*
X-1956724Y-1281456D01*
X-1958089Y-1281196D01*
X-1959454Y-1280416D01*
X-1960234Y-1279376D01*
G01X-1941554Y-1281456D02*
Y-1271056D01*
G01Y-1273136D02*
X-1940579Y-1272096D01*
X-1939604Y-1271316D01*
X-1938239Y-1271056D01*
X-1937264Y-1271316D01*
X-1936094Y-1272096D01*
G01X-1920924Y-1281456D02*
X-1922094Y-1281196D01*
X-1923264Y-1280156D01*
X-1924044Y-1278336D01*
X-1924434Y-1276256D01*
X-1924044Y-1274176D01*
X-1923264Y-1272356D01*
X-1922094Y-1271316D01*
X-1920924Y-1271056D01*
X-1919754Y-1271316D01*
X-1918584Y-1272356D01*
X-1917804Y-1274176D01*
X-1917609Y-1276256D01*
X-1917804Y-1278336D01*
X-1918584Y-1280156D01*
X-1919754Y-1281196D01*
X-1920924Y-1281456D01*
G01X-1906534Y-1271056D02*
X-1903024Y-1281456D01*
X-1899514Y-1271056D01*
G01X-1885124D02*
Y-1281456D01*
G01Y-1266896D02*
X-1885514Y-1266636D01*
Y-1266116D01*
X-1885124Y-1265856D01*
X-1884734Y-1266116D01*
Y-1266636D01*
X-1885124Y-1266896D01*
G01X-1863714Y-1265856D02*
Y-1281456D01*
G01Y-1279116D02*
X-1864494Y-1280416D01*
X-1865664Y-1281196D01*
X-1867029Y-1281456D01*
X-1868589Y-1280936D01*
X-1869759Y-1279636D01*
X-1870539Y-1278076D01*
X-1870734Y-1276256D01*
X-1870539Y-1274436D01*
X-1869759Y-1272876D01*
X-1868589Y-1271576D01*
X-1867029Y-1271056D01*
X-1865664Y-1271316D01*
X-1864689Y-1271836D01*
X-1863714Y-1272876D01*
G01X-1852249Y-1274436D02*
X-1846009D01*
X-1846594Y-1272616D01*
X-1847569Y-1271576D01*
X-1848934Y-1271056D01*
X-1850299Y-1271316D01*
X-1851469Y-1272096D01*
X-1852249Y-1273916D01*
X-1852639Y-1275476D01*
Y-1277036D01*
X-1852249Y-1278596D01*
X-1851274Y-1280156D01*
X-1850104Y-1281196D01*
X-1848739Y-1281456D01*
X-1847374Y-1280936D01*
X-1846009Y-1279376D01*
G01X-1817424Y-1281456D02*
Y-1265856D01*
X-1812744D01*
X-1811184Y-1266636D01*
X-1810014Y-1268456D01*
X-1809624Y-1270536D01*
X-1810014Y-1272616D01*
X-1810989Y-1274176D01*
X-1812744Y-1274956D01*
X-1817424D01*
G01X-1791334Y-1267156D02*
X-1792504Y-1266376D01*
X-1793869Y-1265856D01*
X-1795429D01*
X-1797184Y-1266636D01*
X-1798549Y-1267936D01*
X-1799524Y-1269496D01*
X-1800304Y-1272096D01*
X-1800499Y-1274436D01*
X-1800109Y-1276776D01*
X-1799524Y-1278336D01*
X-1798354Y-1279896D01*
X-1796989Y-1280936D01*
X-1795624Y-1281456D01*
X-1794259D01*
X-1792894Y-1280936D01*
X-1791724Y-1280156D01*
X-1790749Y-1279116D01*
G01X-1776164Y-1273136D02*
X-1775384Y-1272356D01*
X-1774799Y-1271056D01*
X-1774409Y-1269236D01*
X-1774799Y-1267676D01*
X-1775579Y-1266636D01*
X-1776944Y-1265856D01*
X-1782209D01*
Y-1281456D01*
X-1775774D01*
X-1774409Y-1280416D01*
X-1773629Y-1278856D01*
X-1773239Y-1277036D01*
X-1773629Y-1275216D01*
X-1774799Y-1273656D01*
X-1776164Y-1273136D01*
X-1782209D01*
G01X-1728899Y-1271056D02*
X-1726559Y-1281456D01*
X-1724024Y-1271056D01*
X-1721489Y-1281456D01*
X-1719149Y-1271056D01*
G01X-1706124Y-1281456D02*
X-1707294Y-1281196D01*
X-1708464Y-1280156D01*
X-1709244Y-1278336D01*
X-1709634Y-1276256D01*
X-1709244Y-1274176D01*
X-1708464Y-1272356D01*
X-1707294Y-1271316D01*
X-1706124Y-1271056D01*
X-1704954Y-1271316D01*
X-1703784Y-1272356D01*
X-1703004Y-1274176D01*
X-1702809Y-1276256D01*
X-1703004Y-1278336D01*
X-1703784Y-1280156D01*
X-1704954Y-1281196D01*
X-1706124Y-1281456D01*
G01X-1690954D02*
Y-1271056D01*
G01Y-1273136D02*
X-1689979Y-1272096D01*
X-1689004Y-1271316D01*
X-1687639Y-1271056D01*
X-1686664Y-1271316D01*
X-1685494Y-1272096D01*
G01X-1673639Y-1281456D02*
Y-1265856D01*
G01X-1667399Y-1271056D02*
X-1673639Y-1277036D01*
G01X-1671104Y-1274696D02*
X-1667009Y-1281456D01*
G01X-1652424Y-1271056D02*
Y-1281456D01*
G01Y-1266896D02*
X-1652814Y-1266636D01*
Y-1266116D01*
X-1652424Y-1265856D01*
X-1652034Y-1266116D01*
Y-1266636D01*
X-1652424Y-1266896D01*
G01X-1637839Y-1281456D02*
Y-1271056D01*
G01Y-1273656D02*
X-1637059Y-1272356D01*
X-1635889Y-1271316D01*
X-1634329Y-1271056D01*
X-1632964Y-1271316D01*
X-1631794Y-1272356D01*
X-1631209Y-1274176D01*
Y-1281456D01*
G01X-1619354Y-1285356D02*
X-1617989Y-1286396D01*
X-1616429Y-1286656D01*
X-1615064Y-1286396D01*
X-1613894Y-1285096D01*
X-1613114Y-1283276D01*
Y-1271056D01*
G01Y-1273136D02*
X-1613894Y-1272096D01*
X-1615064Y-1271316D01*
X-1616429Y-1271056D01*
X-1617989Y-1271576D01*
X-1618964Y-1272616D01*
X-1619744Y-1274436D01*
X-1620134Y-1276256D01*
X-1619939Y-1277816D01*
X-1619159Y-1279636D01*
X-1617989Y-1280936D01*
X-1616429Y-1281456D01*
X-1615259Y-1281196D01*
X-1613894Y-1280156D01*
X-1613114Y-1279116D01*
G01X-1584334Y-1286656D02*
Y-1271056D01*
G01Y-1273396D02*
X-1583359Y-1272096D01*
X-1582384Y-1271316D01*
X-1580824Y-1271056D01*
X-1579459Y-1271316D01*
X-1578094Y-1272616D01*
X-1577509Y-1274436D01*
X-1577314Y-1276256D01*
X-1577509Y-1278076D01*
X-1578094Y-1279896D01*
X-1579264Y-1280936D01*
X-1580824Y-1281456D01*
X-1582189Y-1281196D01*
X-1583554Y-1280416D01*
X-1584334Y-1279376D01*
G01X-1559414Y-1281456D02*
Y-1271056D01*
G01Y-1272876D02*
X-1560194Y-1271836D01*
X-1561364Y-1271316D01*
X-1562729Y-1271056D01*
X-1564094Y-1271576D01*
X-1565264Y-1272616D01*
X-1566044Y-1274176D01*
X-1566434Y-1276256D01*
X-1566044Y-1278336D01*
X-1565264Y-1279896D01*
X-1564094Y-1280936D01*
X-1562729Y-1281456D01*
X-1561364Y-1281196D01*
X-1560194Y-1280416D01*
X-1559414Y-1279376D01*
G01X-1548339Y-1281456D02*
Y-1271056D01*
G01Y-1273656D02*
X-1547559Y-1272356D01*
X-1546389Y-1271316D01*
X-1544829Y-1271056D01*
X-1543464Y-1271316D01*
X-1542294Y-1272356D01*
X-1541709Y-1274176D01*
Y-1281456D01*
G01X-1530049Y-1274436D02*
X-1523809D01*
X-1524394Y-1272616D01*
X-1525369Y-1271576D01*
X-1526734Y-1271056D01*
X-1528099Y-1271316D01*
X-1529269Y-1272096D01*
X-1530049Y-1273916D01*
X-1530439Y-1275476D01*
Y-1277036D01*
X-1530049Y-1278596D01*
X-1529074Y-1280156D01*
X-1527904Y-1281196D01*
X-1526539Y-1281456D01*
X-1525174Y-1280936D01*
X-1523809Y-1279376D01*
G01X-1509224Y-1281456D02*
Y-1265856D01*
G01X-1476739Y-1271056D02*
Y-1278336D01*
X-1475959Y-1280156D01*
X-1474789Y-1281196D01*
X-1473424Y-1281456D01*
X-1472059Y-1281196D01*
X-1470889Y-1280156D01*
X-1470109Y-1278336D01*
G01Y-1281456D02*
Y-1271056D01*
G01X-1455524Y-1265856D02*
Y-1281456D01*
G01X-1458254Y-1271056D02*
X-1452794D01*
G01X-1437624D02*
Y-1281456D01*
G01Y-1266896D02*
X-1438014Y-1266636D01*
Y-1266116D01*
X-1437624Y-1265856D01*
X-1437234Y-1266116D01*
Y-1266636D01*
X-1437624Y-1266896D01*
G01X-1419724Y-1281456D02*
Y-1265856D01*
G01X-1401824Y-1271056D02*
Y-1281456D01*
G01Y-1266896D02*
X-1402214Y-1266636D01*
Y-1266116D01*
X-1401824Y-1265856D01*
X-1401434Y-1266116D01*
Y-1266636D01*
X-1401824Y-1266896D01*
G01X-1386849Y-1271056D02*
X-1380999D01*
X-1386849Y-1281456D01*
X-1380999D01*
G01X-1362514D02*
Y-1271056D01*
G01Y-1272876D02*
X-1363294Y-1271836D01*
X-1364464Y-1271316D01*
X-1365829Y-1271056D01*
X-1367194Y-1271576D01*
X-1368364Y-1272616D01*
X-1369144Y-1274176D01*
X-1369534Y-1276256D01*
X-1369144Y-1278336D01*
X-1368364Y-1279896D01*
X-1367194Y-1280936D01*
X-1365829Y-1281456D01*
X-1364464Y-1281196D01*
X-1363294Y-1280416D01*
X-1362514Y-1279376D01*
G01X-1348124Y-1265856D02*
Y-1281456D01*
G01X-1350854Y-1271056D02*
X-1345394D01*
G01X-1330224D02*
Y-1281456D01*
G01Y-1266896D02*
X-1330614Y-1266636D01*
Y-1266116D01*
X-1330224Y-1265856D01*
X-1329834Y-1266116D01*
Y-1266636D01*
X-1330224Y-1266896D01*
G01X-1312324Y-1281456D02*
X-1313494Y-1281196D01*
X-1314664Y-1280156D01*
X-1315444Y-1278336D01*
X-1315834Y-1276256D01*
X-1315444Y-1274176D01*
X-1314664Y-1272356D01*
X-1313494Y-1271316D01*
X-1312324Y-1271056D01*
X-1311154Y-1271316D01*
X-1309984Y-1272356D01*
X-1309204Y-1274176D01*
X-1309009Y-1276256D01*
X-1309204Y-1278336D01*
X-1309984Y-1280156D01*
X-1311154Y-1281196D01*
X-1312324Y-1281456D01*
G01X-1297739D02*
Y-1271056D01*
G01Y-1273656D02*
X-1296959Y-1272356D01*
X-1295789Y-1271316D01*
X-1294229Y-1271056D01*
X-1292864Y-1271316D01*
X-1291694Y-1272356D01*
X-1291109Y-1274176D01*
Y-1281456D01*
G01X-1258624Y-1271056D02*
Y-1281456D01*
G01Y-1266896D02*
X-1259014Y-1266636D01*
Y-1266116D01*
X-1258624Y-1265856D01*
X-1258234Y-1266116D01*
Y-1266636D01*
X-1258624Y-1266896D01*
G01X-1244039Y-1281456D02*
Y-1271056D01*
G01Y-1273656D02*
X-1243259Y-1272356D01*
X-1242089Y-1271316D01*
X-1240529Y-1271056D01*
X-1239164Y-1271316D01*
X-1237994Y-1272356D01*
X-1237409Y-1274176D01*
Y-1281456D01*
G01X-1204924Y-1265856D02*
Y-1281456D01*
G01X-1209409Y-1265856D02*
X-1200439D01*
G01X-1187024Y-1281456D02*
X-1188584Y-1281196D01*
X-1189949Y-1280156D01*
X-1191119Y-1278596D01*
X-1191899Y-1276776D01*
X-1192289Y-1274696D01*
Y-1272616D01*
X-1191899Y-1270536D01*
X-1191119Y-1268716D01*
X-1189949Y-1267156D01*
X-1188584Y-1266116D01*
X-1187024Y-1265856D01*
X-1185464Y-1266116D01*
X-1184099Y-1267156D01*
X-1182929Y-1268716D01*
X-1182149Y-1270536D01*
X-1181759Y-1272616D01*
Y-1274696D01*
X-1182149Y-1276776D01*
X-1182929Y-1278596D01*
X-1184099Y-1280156D01*
X-1185464Y-1281196D01*
X-1187024Y-1281456D01*
G01X-1185464Y-1277296D02*
X-1183124Y-1281456D01*
G01X-1153954D02*
Y-1271056D01*
G01Y-1273136D02*
X-1152979Y-1272096D01*
X-1152004Y-1271316D01*
X-1150639Y-1271056D01*
X-1149664Y-1271316D01*
X-1148494Y-1272096D01*
G01X-1136249Y-1274436D02*
X-1130009D01*
X-1130594Y-1272616D01*
X-1131569Y-1271576D01*
X-1132934Y-1271056D01*
X-1134299Y-1271316D01*
X-1135469Y-1272096D01*
X-1136249Y-1273916D01*
X-1136639Y-1275476D01*
Y-1277036D01*
X-1136249Y-1278596D01*
X-1135274Y-1280156D01*
X-1134104Y-1281196D01*
X-1132739Y-1281456D01*
X-1131374Y-1280936D01*
X-1130009Y-1279376D01*
G01X-1118934Y-1286656D02*
Y-1271056D01*
G01Y-1273396D02*
X-1117959Y-1272096D01*
X-1116984Y-1271316D01*
X-1115424Y-1271056D01*
X-1114059Y-1271316D01*
X-1112694Y-1272616D01*
X-1112109Y-1274436D01*
X-1111914Y-1276256D01*
X-1112109Y-1278076D01*
X-1112694Y-1279896D01*
X-1113864Y-1280936D01*
X-1115424Y-1281456D01*
X-1116789Y-1281196D01*
X-1118154Y-1280416D01*
X-1118934Y-1279376D01*
G01X-1097524Y-1281456D02*
X-1098694Y-1281196D01*
X-1099864Y-1280156D01*
X-1100644Y-1278336D01*
X-1101034Y-1276256D01*
X-1100644Y-1274176D01*
X-1099864Y-1272356D01*
X-1098694Y-1271316D01*
X-1097524Y-1271056D01*
X-1096354Y-1271316D01*
X-1095184Y-1272356D01*
X-1094404Y-1274176D01*
X-1094209Y-1276256D01*
X-1094404Y-1278336D01*
X-1095184Y-1280156D01*
X-1096354Y-1281196D01*
X-1097524Y-1281456D01*
G01X-1082354D02*
Y-1271056D01*
G01Y-1273136D02*
X-1081379Y-1272096D01*
X-1080404Y-1271316D01*
X-1079039Y-1271056D01*
X-1078064Y-1271316D01*
X-1076894Y-1272096D01*
G01X-1061724Y-1265856D02*
Y-1281456D01*
G01X-1064454Y-1271056D02*
X-1058994D01*
G01X-1043824Y-1281976D02*
X-1044214Y-1281716D01*
Y-1281196D01*
X-1043824Y-1280936D01*
X-1043434Y-1281196D01*
Y-1281716D01*
X-1043824Y-1281976D01*
G01X-2135724Y-1227456D02*
Y-1211856D01*
X-2138064Y-1214976D01*
G01Y-1227456D02*
X-2133384D01*
G01X-2122114Y-1224336D02*
X-2120944Y-1226156D01*
X-2119384Y-1227196D01*
X-2117629Y-1227456D01*
X-2116069Y-1227196D01*
X-2114509Y-1225896D01*
X-2113534Y-1224336D01*
X-2113339Y-1222776D01*
X-2113729Y-1220956D01*
X-2115094Y-1219656D01*
X-2116459Y-1219136D01*
X-2118214D01*
G01X-2116459D02*
X-2115289Y-1218356D01*
X-2114314Y-1217056D01*
X-2113924Y-1215496D01*
X-2114314Y-1213936D01*
X-2115289Y-1212636D01*
X-2117044Y-1211856D01*
X-2118799Y-1212116D01*
X-2120554Y-1213156D01*
G01X-2099924Y-1227976D02*
X-2100314Y-1227716D01*
Y-1227196D01*
X-2099924Y-1226936D01*
X-2099534Y-1227196D01*
Y-1227716D01*
X-2099924Y-1227976D01*
G01X-2085729Y-1227456D02*
Y-1211856D01*
X-2078319D01*
G01X-2081049Y-1219396D02*
X-2085729D01*
G01X-2064124Y-1227456D02*
X-2065294Y-1227196D01*
X-2066464Y-1226156D01*
X-2067244Y-1224336D01*
X-2067634Y-1222256D01*
X-2067244Y-1220176D01*
X-2066464Y-1218356D01*
X-2065294Y-1217316D01*
X-2064124Y-1217056D01*
X-2062954Y-1217316D01*
X-2061784Y-1218356D01*
X-2061004Y-1220176D01*
X-2060809Y-1222256D01*
X-2061004Y-1224336D01*
X-2061784Y-1226156D01*
X-2062954Y-1227196D01*
X-2064124Y-1227456D01*
G01X-2048954D02*
Y-1217056D01*
G01Y-1219136D02*
X-2047979Y-1218096D01*
X-2047004Y-1217316D01*
X-2045639Y-1217056D01*
X-2044664Y-1217316D01*
X-2043494Y-1218096D01*
G01X-2014519Y-1225376D02*
X-2012959Y-1226676D01*
X-2011204Y-1227456D01*
X-2009644D01*
X-2008084Y-1226676D01*
X-2006914Y-1225376D01*
X-2006329Y-1223556D01*
X-2006719Y-1221736D01*
X-2007694Y-1220176D01*
X-2009449Y-1219136D01*
X-2011789Y-1218616D01*
X-2013154Y-1217576D01*
X-2013739Y-1215756D01*
X-2013349Y-1213936D01*
X-2012374Y-1212636D01*
X-2011009Y-1211856D01*
X-2009644D01*
X-2008279Y-1212376D01*
X-2007109Y-1213676D01*
G01X-1994864Y-1211856D02*
X-1990184D01*
G01X-1992524D02*
Y-1227456D01*
G01X-1994864D02*
X-1990184D01*
G01X-1959454D02*
Y-1217056D01*
G01Y-1219136D02*
X-1958479Y-1218096D01*
X-1957504Y-1217316D01*
X-1956139Y-1217056D01*
X-1955164Y-1217316D01*
X-1953994Y-1218096D01*
G01X-1941749Y-1220436D02*
X-1935509D01*
X-1936094Y-1218616D01*
X-1937069Y-1217576D01*
X-1938434Y-1217056D01*
X-1939799Y-1217316D01*
X-1940969Y-1218096D01*
X-1941749Y-1219916D01*
X-1942139Y-1221476D01*
Y-1223036D01*
X-1941749Y-1224596D01*
X-1940774Y-1226156D01*
X-1939604Y-1227196D01*
X-1938239Y-1227456D01*
X-1936874Y-1226936D01*
X-1935509Y-1225376D01*
G01X-1917414Y-1232656D02*
Y-1217056D01*
G01Y-1219396D02*
X-1918389Y-1218096D01*
X-1919559Y-1217316D01*
X-1920924Y-1217056D01*
X-1922094Y-1217316D01*
X-1923459Y-1218616D01*
X-1924239Y-1220436D01*
X-1924434Y-1222256D01*
X-1924239Y-1224076D01*
X-1923459Y-1225896D01*
X-1922094Y-1227196D01*
X-1920924Y-1227456D01*
X-1919559Y-1227196D01*
X-1918389Y-1226416D01*
X-1917414Y-1225116D01*
G01X-1906339Y-1217056D02*
Y-1224336D01*
X-1905559Y-1226156D01*
X-1904389Y-1227196D01*
X-1903024Y-1227456D01*
X-1901659Y-1227196D01*
X-1900489Y-1226156D01*
X-1899709Y-1224336D01*
G01Y-1227456D02*
Y-1217056D01*
G01X-1885124D02*
Y-1227456D01*
G01Y-1212896D02*
X-1885514Y-1212636D01*
Y-1212116D01*
X-1885124Y-1211856D01*
X-1884734Y-1212116D01*
Y-1212636D01*
X-1885124Y-1212896D01*
G01X-1869954Y-1227456D02*
Y-1217056D01*
G01Y-1219136D02*
X-1868979Y-1218096D01*
X-1868004Y-1217316D01*
X-1866639Y-1217056D01*
X-1865664Y-1217316D01*
X-1864494Y-1218096D01*
G01X-1852249Y-1220436D02*
X-1846009D01*
X-1846594Y-1218616D01*
X-1847569Y-1217576D01*
X-1848934Y-1217056D01*
X-1850299Y-1217316D01*
X-1851469Y-1218096D01*
X-1852249Y-1219916D01*
X-1852639Y-1221476D01*
Y-1223036D01*
X-1852249Y-1224596D01*
X-1851274Y-1226156D01*
X-1850104Y-1227196D01*
X-1848739Y-1227456D01*
X-1847374Y-1226936D01*
X-1846009Y-1225376D01*
G01X-1837274Y-1227456D02*
Y-1217056D01*
G01Y-1219916D02*
X-1836689Y-1218616D01*
X-1835714Y-1217576D01*
X-1834349Y-1217056D01*
X-1832984Y-1217576D01*
X-1832009Y-1218616D01*
X-1831424Y-1219916D01*
Y-1227456D01*
G01Y-1219916D02*
X-1830839Y-1218616D01*
X-1829864Y-1217576D01*
X-1828499Y-1217056D01*
X-1827134Y-1217576D01*
X-1826159Y-1218616D01*
X-1825574Y-1220176D01*
Y-1227456D01*
G01X-1816449Y-1220436D02*
X-1810209D01*
X-1810794Y-1218616D01*
X-1811769Y-1217576D01*
X-1813134Y-1217056D01*
X-1814499Y-1217316D01*
X-1815669Y-1218096D01*
X-1816449Y-1219916D01*
X-1816839Y-1221476D01*
Y-1223036D01*
X-1816449Y-1224596D01*
X-1815474Y-1226156D01*
X-1814304Y-1227196D01*
X-1812939Y-1227456D01*
X-1811574Y-1226936D01*
X-1810209Y-1225376D01*
G01X-1798939Y-1227456D02*
Y-1217056D01*
G01Y-1219656D02*
X-1798159Y-1218356D01*
X-1796989Y-1217316D01*
X-1795429Y-1217056D01*
X-1794064Y-1217316D01*
X-1792894Y-1218356D01*
X-1792309Y-1220176D01*
Y-1227456D01*
G01X-1777724Y-1211856D02*
Y-1227456D01*
G01X-1780454Y-1217056D02*
X-1774994D01*
G01X-1762749Y-1225636D02*
X-1761774Y-1226676D01*
X-1760409Y-1227456D01*
X-1759239D01*
X-1758069Y-1226936D01*
X-1757289Y-1226156D01*
X-1756899Y-1225116D01*
X-1757094Y-1223556D01*
X-1757874Y-1222776D01*
X-1761384Y-1221216D01*
X-1762164Y-1219396D01*
X-1761774Y-1218096D01*
X-1760994Y-1217316D01*
X-1759824Y-1217056D01*
X-1758654Y-1217316D01*
X-1757484Y-1218096D01*
G01X-1742314Y-1230316D02*
X-1741534Y-1226936D01*
G01X-1727534Y-1232656D02*
Y-1217056D01*
G01Y-1219396D02*
X-1726559Y-1218096D01*
X-1725584Y-1217316D01*
X-1724024Y-1217056D01*
X-1722659Y-1217316D01*
X-1721294Y-1218616D01*
X-1720709Y-1220436D01*
X-1720514Y-1222256D01*
X-1720709Y-1224076D01*
X-1721294Y-1225896D01*
X-1722464Y-1226936D01*
X-1724024Y-1227456D01*
X-1725389Y-1227196D01*
X-1726754Y-1226416D01*
X-1727534Y-1225376D01*
G01X-1706124Y-1227456D02*
Y-1211856D01*
G01X-1691149Y-1220436D02*
X-1684909D01*
X-1685494Y-1218616D01*
X-1686469Y-1217576D01*
X-1687834Y-1217056D01*
X-1689199Y-1217316D01*
X-1690369Y-1218096D01*
X-1691149Y-1219916D01*
X-1691539Y-1221476D01*
Y-1223036D01*
X-1691149Y-1224596D01*
X-1690174Y-1226156D01*
X-1689004Y-1227196D01*
X-1687639Y-1227456D01*
X-1686274Y-1226936D01*
X-1684909Y-1225376D01*
G01X-1666814Y-1227456D02*
Y-1217056D01*
G01Y-1218876D02*
X-1667594Y-1217836D01*
X-1668764Y-1217316D01*
X-1670129Y-1217056D01*
X-1671494Y-1217576D01*
X-1672664Y-1218616D01*
X-1673444Y-1220176D01*
X-1673834Y-1222256D01*
X-1673444Y-1224336D01*
X-1672664Y-1225896D01*
X-1671494Y-1226936D01*
X-1670129Y-1227456D01*
X-1668764Y-1227196D01*
X-1667594Y-1226416D01*
X-1666814Y-1225376D01*
G01X-1655349Y-1225636D02*
X-1654374Y-1226676D01*
X-1653009Y-1227456D01*
X-1651839D01*
X-1650669Y-1226936D01*
X-1649889Y-1226156D01*
X-1649499Y-1225116D01*
X-1649694Y-1223556D01*
X-1650474Y-1222776D01*
X-1653984Y-1221216D01*
X-1654764Y-1219396D01*
X-1654374Y-1218096D01*
X-1653594Y-1217316D01*
X-1652424Y-1217056D01*
X-1651254Y-1217316D01*
X-1650084Y-1218096D01*
G01X-1637449Y-1220436D02*
X-1631209D01*
X-1631794Y-1218616D01*
X-1632769Y-1217576D01*
X-1634134Y-1217056D01*
X-1635499Y-1217316D01*
X-1636669Y-1218096D01*
X-1637449Y-1219916D01*
X-1637839Y-1221476D01*
Y-1223036D01*
X-1637449Y-1224596D01*
X-1636474Y-1226156D01*
X-1635304Y-1227196D01*
X-1633939Y-1227456D01*
X-1632574Y-1226936D01*
X-1631209Y-1225376D01*
G01X-1601454Y-1227456D02*
Y-1217056D01*
G01Y-1219136D02*
X-1600479Y-1218096D01*
X-1599504Y-1217316D01*
X-1598139Y-1217056D01*
X-1597164Y-1217316D01*
X-1595994Y-1218096D01*
G01X-1583749Y-1220436D02*
X-1577509D01*
X-1578094Y-1218616D01*
X-1579069Y-1217576D01*
X-1580434Y-1217056D01*
X-1581799Y-1217316D01*
X-1582969Y-1218096D01*
X-1583749Y-1219916D01*
X-1584139Y-1221476D01*
Y-1223036D01*
X-1583749Y-1224596D01*
X-1582774Y-1226156D01*
X-1581604Y-1227196D01*
X-1580239Y-1227456D01*
X-1578874Y-1226936D01*
X-1577509Y-1225376D01*
G01X-1564094Y-1227456D02*
Y-1214196D01*
X-1563704Y-1212896D01*
X-1562924Y-1212116D01*
X-1561754Y-1211856D01*
X-1560584Y-1212376D01*
X-1559999Y-1213676D01*
G01X-1562339Y-1218096D02*
X-1566239D01*
G01X-1547949Y-1220436D02*
X-1541709D01*
X-1542294Y-1218616D01*
X-1543269Y-1217576D01*
X-1544634Y-1217056D01*
X-1545999Y-1217316D01*
X-1547169Y-1218096D01*
X-1547949Y-1219916D01*
X-1548339Y-1221476D01*
Y-1223036D01*
X-1547949Y-1224596D01*
X-1546974Y-1226156D01*
X-1545804Y-1227196D01*
X-1544439Y-1227456D01*
X-1543074Y-1226936D01*
X-1541709Y-1225376D01*
G01X-1529854Y-1227456D02*
Y-1217056D01*
G01Y-1219136D02*
X-1528879Y-1218096D01*
X-1527904Y-1217316D01*
X-1526539Y-1217056D01*
X-1525564Y-1217316D01*
X-1524394Y-1218096D01*
G01X-1491324Y-1211856D02*
Y-1227456D01*
G01X-1494054Y-1217056D02*
X-1488594D01*
G01X-1476739Y-1227456D02*
Y-1211856D01*
G01Y-1219396D02*
X-1475764Y-1218096D01*
X-1474789Y-1217316D01*
X-1473229Y-1217056D01*
X-1472059Y-1217316D01*
X-1470694Y-1218356D01*
X-1470109Y-1219916D01*
Y-1227456D01*
G01X-1458449Y-1220436D02*
X-1452209D01*
X-1452794Y-1218616D01*
X-1453769Y-1217576D01*
X-1455134Y-1217056D01*
X-1456499Y-1217316D01*
X-1457669Y-1218096D01*
X-1458449Y-1219916D01*
X-1458839Y-1221476D01*
Y-1223036D01*
X-1458449Y-1224596D01*
X-1457474Y-1226156D01*
X-1456304Y-1227196D01*
X-1454939Y-1227456D01*
X-1453574Y-1226936D01*
X-1452209Y-1225376D01*
G01X-1420894Y-1227456D02*
Y-1214196D01*
X-1420504Y-1212896D01*
X-1419724Y-1212116D01*
X-1418554Y-1211856D01*
X-1417384Y-1212376D01*
X-1416799Y-1213676D01*
G01X-1419139Y-1218096D02*
X-1423039D01*
G01X-1401824Y-1217056D02*
Y-1227456D01*
G01Y-1212896D02*
X-1402214Y-1212636D01*
Y-1212116D01*
X-1401824Y-1211856D01*
X-1401434Y-1212116D01*
Y-1212636D01*
X-1401824Y-1212896D01*
G01X-1383924Y-1227456D02*
Y-1211856D01*
G01X-1368949Y-1220436D02*
X-1362709D01*
X-1363294Y-1218616D01*
X-1364269Y-1217576D01*
X-1365634Y-1217056D01*
X-1366999Y-1217316D01*
X-1368169Y-1218096D01*
X-1368949Y-1219916D01*
X-1369339Y-1221476D01*
Y-1223036D01*
X-1368949Y-1224596D01*
X-1367974Y-1226156D01*
X-1366804Y-1227196D01*
X-1365439Y-1227456D01*
X-1364074Y-1226936D01*
X-1362709Y-1225376D01*
G01X-1351049Y-1225636D02*
X-1350074Y-1226676D01*
X-1348709Y-1227456D01*
X-1347539D01*
X-1346369Y-1226936D01*
X-1345589Y-1226156D01*
X-1345199Y-1225116D01*
X-1345394Y-1223556D01*
X-1346174Y-1222776D01*
X-1349684Y-1221216D01*
X-1350464Y-1219396D01*
X-1350074Y-1218096D01*
X-1349294Y-1217316D01*
X-1348124Y-1217056D01*
X-1346954Y-1217316D01*
X-1345784Y-1218096D01*
G01X-1312324Y-1217056D02*
Y-1227456D01*
G01Y-1212896D02*
X-1312714Y-1212636D01*
Y-1212116D01*
X-1312324Y-1211856D01*
X-1311934Y-1212116D01*
Y-1212636D01*
X-1312324Y-1212896D01*
G01X-1297739Y-1227456D02*
Y-1217056D01*
G01Y-1219656D02*
X-1296959Y-1218356D01*
X-1295789Y-1217316D01*
X-1294229Y-1217056D01*
X-1292864Y-1217316D01*
X-1291694Y-1218356D01*
X-1291109Y-1220176D01*
Y-1227456D01*
G01X-1261354Y-1231356D02*
X-1259989Y-1232396D01*
X-1258429Y-1232656D01*
X-1257064Y-1232396D01*
X-1255894Y-1231096D01*
X-1255114Y-1229276D01*
Y-1217056D01*
G01Y-1219136D02*
X-1255894Y-1218096D01*
X-1257064Y-1217316D01*
X-1258429Y-1217056D01*
X-1259989Y-1217576D01*
X-1260964Y-1218616D01*
X-1261744Y-1220436D01*
X-1262134Y-1222256D01*
X-1261939Y-1223816D01*
X-1261159Y-1225636D01*
X-1259989Y-1226936D01*
X-1258429Y-1227456D01*
X-1257259Y-1227196D01*
X-1255894Y-1226156D01*
X-1255114Y-1225116D01*
G01X-1243649Y-1220436D02*
X-1237409D01*
X-1237994Y-1218616D01*
X-1238969Y-1217576D01*
X-1240334Y-1217056D01*
X-1241699Y-1217316D01*
X-1242869Y-1218096D01*
X-1243649Y-1219916D01*
X-1244039Y-1221476D01*
Y-1223036D01*
X-1243649Y-1224596D01*
X-1242674Y-1226156D01*
X-1241504Y-1227196D01*
X-1240139Y-1227456D01*
X-1238774Y-1226936D01*
X-1237409Y-1225376D01*
G01X-1225554Y-1227456D02*
Y-1217056D01*
G01Y-1219136D02*
X-1224579Y-1218096D01*
X-1223604Y-1217316D01*
X-1222239Y-1217056D01*
X-1221264Y-1217316D01*
X-1220094Y-1218096D01*
G01X-1208434Y-1227456D02*
Y-1211856D01*
G01Y-1219656D02*
X-1207459Y-1218096D01*
X-1206289Y-1217316D01*
X-1205119Y-1217056D01*
X-1203364Y-1217576D01*
X-1202194Y-1218616D01*
X-1201414Y-1220436D01*
Y-1222516D01*
X-1201804Y-1224596D01*
X-1202584Y-1226156D01*
X-1203949Y-1227196D01*
X-1205119Y-1227456D01*
X-1206289Y-1227196D01*
X-1207459Y-1226416D01*
X-1208434Y-1225116D01*
G01X-1189949Y-1220436D02*
X-1183709D01*
X-1184294Y-1218616D01*
X-1185269Y-1217576D01*
X-1186634Y-1217056D01*
X-1187999Y-1217316D01*
X-1189169Y-1218096D01*
X-1189949Y-1219916D01*
X-1190339Y-1221476D01*
Y-1223036D01*
X-1189949Y-1224596D01*
X-1188974Y-1226156D01*
X-1187804Y-1227196D01*
X-1186439Y-1227456D01*
X-1185074Y-1226936D01*
X-1183709Y-1225376D01*
G01X-1171854Y-1227456D02*
Y-1217056D01*
G01Y-1219136D02*
X-1170879Y-1218096D01*
X-1169904Y-1217316D01*
X-1168539Y-1217056D01*
X-1167564Y-1217316D01*
X-1166394Y-1218096D01*
G01X-1136834Y-1232656D02*
Y-1217056D01*
G01Y-1219396D02*
X-1135859Y-1218096D01*
X-1134884Y-1217316D01*
X-1133324Y-1217056D01*
X-1131959Y-1217316D01*
X-1130594Y-1218616D01*
X-1130009Y-1220436D01*
X-1129814Y-1222256D01*
X-1130009Y-1224076D01*
X-1130594Y-1225896D01*
X-1131764Y-1226936D01*
X-1133324Y-1227456D01*
X-1134689Y-1227196D01*
X-1136054Y-1226416D01*
X-1136834Y-1225376D01*
G01X-1111914Y-1227456D02*
Y-1217056D01*
G01Y-1218876D02*
X-1112694Y-1217836D01*
X-1113864Y-1217316D01*
X-1115229Y-1217056D01*
X-1116594Y-1217576D01*
X-1117764Y-1218616D01*
X-1118544Y-1220176D01*
X-1118934Y-1222256D01*
X-1118544Y-1224336D01*
X-1117764Y-1225896D01*
X-1116594Y-1226936D01*
X-1115229Y-1227456D01*
X-1113864Y-1227196D01*
X-1112694Y-1226416D01*
X-1111914Y-1225376D01*
G01X-1094404Y-1218356D02*
X-1095769Y-1217316D01*
X-1096939Y-1217056D01*
X-1098499Y-1217576D01*
X-1099669Y-1218616D01*
X-1100449Y-1220436D01*
X-1100644Y-1222256D01*
X-1100449Y-1224076D01*
X-1099669Y-1225636D01*
X-1098499Y-1226936D01*
X-1096939Y-1227456D01*
X-1095574Y-1226936D01*
X-1094404Y-1225896D01*
G01X-1082939Y-1227456D02*
Y-1211856D01*
G01X-1076699Y-1217056D02*
X-1082939Y-1223036D01*
G01X-1080404Y-1220696D02*
X-1076309Y-1227456D01*
G01X-1058214D02*
Y-1217056D01*
G01Y-1218876D02*
X-1058994Y-1217836D01*
X-1060164Y-1217316D01*
X-1061529Y-1217056D01*
X-1062894Y-1217576D01*
X-1064064Y-1218616D01*
X-1064844Y-1220176D01*
X-1065234Y-1222256D01*
X-1064844Y-1224336D01*
X-1064064Y-1225896D01*
X-1062894Y-1226936D01*
X-1061529Y-1227456D01*
X-1060164Y-1227196D01*
X-1058994Y-1226416D01*
X-1058214Y-1225376D01*
G01X-1046554Y-1231356D02*
X-1045189Y-1232396D01*
X-1043629Y-1232656D01*
X-1042264Y-1232396D01*
X-1041094Y-1231096D01*
X-1040314Y-1229276D01*
Y-1217056D01*
G01Y-1219136D02*
X-1041094Y-1218096D01*
X-1042264Y-1217316D01*
X-1043629Y-1217056D01*
X-1045189Y-1217576D01*
X-1046164Y-1218616D01*
X-1046944Y-1220436D01*
X-1047334Y-1222256D01*
X-1047139Y-1223816D01*
X-1046359Y-1225636D01*
X-1045189Y-1226936D01*
X-1043629Y-1227456D01*
X-1042459Y-1227196D01*
X-1041094Y-1226156D01*
X-1040314Y-1225116D01*
G01X-1028849Y-1220436D02*
X-1022609D01*
X-1023194Y-1218616D01*
X-1024169Y-1217576D01*
X-1025534Y-1217056D01*
X-1026899Y-1217316D01*
X-1028069Y-1218096D01*
X-1028849Y-1219916D01*
X-1029239Y-1221476D01*
Y-1223036D01*
X-1028849Y-1224596D01*
X-1027874Y-1226156D01*
X-1026704Y-1227196D01*
X-1025339Y-1227456D01*
X-1023974Y-1226936D01*
X-1022609Y-1225376D01*
G01X-1008024Y-1227976D02*
X-1008414Y-1227716D01*
Y-1227196D01*
X-1008024Y-1226936D01*
X-1007634Y-1227196D01*
Y-1227716D01*
X-1008024Y-1227976D01*
G01X-2135724Y-1173456D02*
Y-1157856D01*
X-2138064Y-1160976D01*
G01Y-1173456D02*
X-2133384D01*
G01X-2121529Y-1160456D02*
X-2120359Y-1158896D01*
X-2118994Y-1158116D01*
X-2117434Y-1157856D01*
X-2115484Y-1158376D01*
X-2114119Y-1159676D01*
X-2113729Y-1161236D01*
X-2113924Y-1162796D01*
X-2114704Y-1164096D01*
X-2118604Y-1166696D01*
X-2120359Y-1168516D01*
X-2121529Y-1171116D01*
X-2121919Y-1173456D01*
X-2113729D01*
G01X-2099924Y-1173976D02*
X-2100314Y-1173716D01*
Y-1173196D01*
X-2099924Y-1172936D01*
X-2099534Y-1173196D01*
Y-1173716D01*
X-2099924Y-1173976D01*
G01X-2085924Y-1173456D02*
Y-1157856D01*
X-2081244D01*
X-2079684Y-1158636D01*
X-2078514Y-1160456D01*
X-2078124Y-1162536D01*
X-2078514Y-1164616D01*
X-2079489Y-1166176D01*
X-2081244Y-1166956D01*
X-2085924D01*
G01X-2064124Y-1173456D02*
Y-1157856D01*
G01X-2049149Y-1166436D02*
X-2042909D01*
X-2043494Y-1164616D01*
X-2044469Y-1163576D01*
X-2045834Y-1163056D01*
X-2047199Y-1163316D01*
X-2048369Y-1164096D01*
X-2049149Y-1165916D01*
X-2049539Y-1167476D01*
Y-1169036D01*
X-2049149Y-1170596D01*
X-2048174Y-1172156D01*
X-2047004Y-1173196D01*
X-2045639Y-1173456D01*
X-2044274Y-1172936D01*
X-2042909Y-1171376D01*
G01X-2024814Y-1173456D02*
Y-1163056D01*
G01Y-1164876D02*
X-2025594Y-1163836D01*
X-2026764Y-1163316D01*
X-2028129Y-1163056D01*
X-2029494Y-1163576D01*
X-2030664Y-1164616D01*
X-2031444Y-1166176D01*
X-2031834Y-1168256D01*
X-2031444Y-1170336D01*
X-2030664Y-1171896D01*
X-2029494Y-1172936D01*
X-2028129Y-1173456D01*
X-2026764Y-1173196D01*
X-2025594Y-1172416D01*
X-2024814Y-1171376D01*
G01X-2013349Y-1171636D02*
X-2012374Y-1172676D01*
X-2011009Y-1173456D01*
X-2009839D01*
X-2008669Y-1172936D01*
X-2007889Y-1172156D01*
X-2007499Y-1171116D01*
X-2007694Y-1169556D01*
X-2008474Y-1168776D01*
X-2011984Y-1167216D01*
X-2012764Y-1165396D01*
X-2012374Y-1164096D01*
X-2011594Y-1163316D01*
X-2010424Y-1163056D01*
X-2009254Y-1163316D01*
X-2008084Y-1164096D01*
G01X-1995449Y-1166436D02*
X-1989209D01*
X-1989794Y-1164616D01*
X-1990769Y-1163576D01*
X-1992134Y-1163056D01*
X-1993499Y-1163316D01*
X-1994669Y-1164096D01*
X-1995449Y-1165916D01*
X-1995839Y-1167476D01*
Y-1169036D01*
X-1995449Y-1170596D01*
X-1994474Y-1172156D01*
X-1993304Y-1173196D01*
X-1991939Y-1173456D01*
X-1990574Y-1172936D01*
X-1989209Y-1171376D01*
G01X-1957894Y-1173456D02*
Y-1160196D01*
X-1957504Y-1158896D01*
X-1956724Y-1158116D01*
X-1955554Y-1157856D01*
X-1954384Y-1158376D01*
X-1953799Y-1159676D01*
G01X-1956139Y-1164096D02*
X-1960039D01*
G01X-1938824Y-1173456D02*
X-1939994Y-1173196D01*
X-1941164Y-1172156D01*
X-1941944Y-1170336D01*
X-1942334Y-1168256D01*
X-1941944Y-1166176D01*
X-1941164Y-1164356D01*
X-1939994Y-1163316D01*
X-1938824Y-1163056D01*
X-1937654Y-1163316D01*
X-1936484Y-1164356D01*
X-1935704Y-1166176D01*
X-1935509Y-1168256D01*
X-1935704Y-1170336D01*
X-1936484Y-1172156D01*
X-1937654Y-1173196D01*
X-1938824Y-1173456D01*
G01X-1920924D02*
Y-1157856D01*
G01X-1903024Y-1173456D02*
Y-1157856D01*
G01X-1885124Y-1173456D02*
X-1886294Y-1173196D01*
X-1887464Y-1172156D01*
X-1888244Y-1170336D01*
X-1888634Y-1168256D01*
X-1888244Y-1166176D01*
X-1887464Y-1164356D01*
X-1886294Y-1163316D01*
X-1885124Y-1163056D01*
X-1883954Y-1163316D01*
X-1882784Y-1164356D01*
X-1882004Y-1166176D01*
X-1881809Y-1168256D01*
X-1882004Y-1170336D01*
X-1882784Y-1172156D01*
X-1883954Y-1173196D01*
X-1885124Y-1173456D01*
G01X-1872099Y-1163056D02*
X-1869759Y-1173456D01*
X-1867224Y-1163056D01*
X-1864689Y-1173456D01*
X-1862349Y-1163056D01*
G01X-1831424Y-1173456D02*
X-1832594Y-1173196D01*
X-1833764Y-1172156D01*
X-1834544Y-1170336D01*
X-1834934Y-1168256D01*
X-1834544Y-1166176D01*
X-1833764Y-1164356D01*
X-1832594Y-1163316D01*
X-1831424Y-1163056D01*
X-1830254Y-1163316D01*
X-1829084Y-1164356D01*
X-1828304Y-1166176D01*
X-1828109Y-1168256D01*
X-1828304Y-1170336D01*
X-1829084Y-1172156D01*
X-1830254Y-1173196D01*
X-1831424Y-1173456D01*
G01X-1816839Y-1163056D02*
Y-1170336D01*
X-1816059Y-1172156D01*
X-1814889Y-1173196D01*
X-1813524Y-1173456D01*
X-1812159Y-1173196D01*
X-1810989Y-1172156D01*
X-1810209Y-1170336D01*
G01Y-1173456D02*
Y-1163056D01*
G01X-1798354Y-1173456D02*
Y-1163056D01*
G01Y-1165136D02*
X-1797379Y-1164096D01*
X-1796404Y-1163316D01*
X-1795039Y-1163056D01*
X-1794064Y-1163316D01*
X-1792894Y-1164096D01*
G01X-1762749Y-1171636D02*
X-1761774Y-1172676D01*
X-1760409Y-1173456D01*
X-1759239D01*
X-1758069Y-1172936D01*
X-1757289Y-1172156D01*
X-1756899Y-1171116D01*
X-1757094Y-1169556D01*
X-1757874Y-1168776D01*
X-1761384Y-1167216D01*
X-1762164Y-1165396D01*
X-1761774Y-1164096D01*
X-1760994Y-1163316D01*
X-1759824Y-1163056D01*
X-1758654Y-1163316D01*
X-1757484Y-1164096D01*
G01X-1741924Y-1157856D02*
Y-1173456D01*
G01X-1744654Y-1163056D02*
X-1739194D01*
G01X-1720514Y-1173456D02*
Y-1163056D01*
G01Y-1164876D02*
X-1721294Y-1163836D01*
X-1722464Y-1163316D01*
X-1723829Y-1163056D01*
X-1725194Y-1163576D01*
X-1726364Y-1164616D01*
X-1727144Y-1166176D01*
X-1727534Y-1168256D01*
X-1727144Y-1170336D01*
X-1726364Y-1171896D01*
X-1725194Y-1172936D01*
X-1723829Y-1173456D01*
X-1722464Y-1173196D01*
X-1721294Y-1172416D01*
X-1720514Y-1171376D01*
G01X-1703004Y-1164356D02*
X-1704369Y-1163316D01*
X-1705539Y-1163056D01*
X-1707099Y-1163576D01*
X-1708269Y-1164616D01*
X-1709049Y-1166436D01*
X-1709244Y-1168256D01*
X-1709049Y-1170076D01*
X-1708269Y-1171636D01*
X-1707099Y-1172936D01*
X-1705539Y-1173456D01*
X-1704174Y-1172936D01*
X-1703004Y-1171896D01*
G01X-1691539Y-1173456D02*
Y-1157856D01*
G01X-1685299Y-1163056D02*
X-1691539Y-1169036D01*
G01X-1689004Y-1166696D02*
X-1684909Y-1173456D01*
G01X-1672859Y-1168256D02*
X-1667789D01*
G01X-1655739Y-1163056D02*
Y-1170336D01*
X-1654959Y-1172156D01*
X-1653789Y-1173196D01*
X-1652424Y-1173456D01*
X-1651059Y-1173196D01*
X-1649889Y-1172156D01*
X-1649109Y-1170336D01*
G01Y-1173456D02*
Y-1163056D01*
G01X-1638034Y-1178656D02*
Y-1163056D01*
G01Y-1165396D02*
X-1637059Y-1164096D01*
X-1636084Y-1163316D01*
X-1634524Y-1163056D01*
X-1633159Y-1163316D01*
X-1631794Y-1164616D01*
X-1631209Y-1166436D01*
X-1631014Y-1168256D01*
X-1631209Y-1170076D01*
X-1631794Y-1171896D01*
X-1632964Y-1172936D01*
X-1634524Y-1173456D01*
X-1635889Y-1173196D01*
X-1637254Y-1172416D01*
X-1638034Y-1171376D01*
G01X-1598724Y-1163056D02*
Y-1173456D01*
G01Y-1158896D02*
X-1599114Y-1158636D01*
Y-1158116D01*
X-1598724Y-1157856D01*
X-1598334Y-1158116D01*
Y-1158636D01*
X-1598724Y-1158896D01*
G01X-1584139Y-1173456D02*
Y-1163056D01*
G01Y-1165656D02*
X-1583359Y-1164356D01*
X-1582189Y-1163316D01*
X-1580629Y-1163056D01*
X-1579264Y-1163316D01*
X-1578094Y-1164356D01*
X-1577509Y-1166176D01*
Y-1173456D01*
G01X-1545024Y-1157856D02*
Y-1173456D01*
G01X-1547754Y-1163056D02*
X-1542294D01*
G01X-1530439Y-1173456D02*
Y-1157856D01*
G01Y-1165396D02*
X-1529464Y-1164096D01*
X-1528489Y-1163316D01*
X-1526929Y-1163056D01*
X-1525759Y-1163316D01*
X-1524394Y-1164356D01*
X-1523809Y-1165916D01*
Y-1173456D01*
G01X-1512149Y-1166436D02*
X-1505909D01*
X-1506494Y-1164616D01*
X-1507469Y-1163576D01*
X-1508834Y-1163056D01*
X-1510199Y-1163316D01*
X-1511369Y-1164096D01*
X-1512149Y-1165916D01*
X-1512539Y-1167476D01*
Y-1169036D01*
X-1512149Y-1170596D01*
X-1511174Y-1172156D01*
X-1510004Y-1173196D01*
X-1508639Y-1173456D01*
X-1507274Y-1172936D01*
X-1505909Y-1171376D01*
G01X-1476154Y-1177356D02*
X-1474789Y-1178396D01*
X-1473229Y-1178656D01*
X-1471864Y-1178396D01*
X-1470694Y-1177096D01*
X-1469914Y-1175276D01*
Y-1163056D01*
G01Y-1165136D02*
X-1470694Y-1164096D01*
X-1471864Y-1163316D01*
X-1473229Y-1163056D01*
X-1474789Y-1163576D01*
X-1475764Y-1164616D01*
X-1476544Y-1166436D01*
X-1476934Y-1168256D01*
X-1476739Y-1169816D01*
X-1475959Y-1171636D01*
X-1474789Y-1172936D01*
X-1473229Y-1173456D01*
X-1472059Y-1173196D01*
X-1470694Y-1172156D01*
X-1469914Y-1171116D01*
G01X-1458449Y-1166436D02*
X-1452209D01*
X-1452794Y-1164616D01*
X-1453769Y-1163576D01*
X-1455134Y-1163056D01*
X-1456499Y-1163316D01*
X-1457669Y-1164096D01*
X-1458449Y-1165916D01*
X-1458839Y-1167476D01*
Y-1169036D01*
X-1458449Y-1170596D01*
X-1457474Y-1172156D01*
X-1456304Y-1173196D01*
X-1454939Y-1173456D01*
X-1453574Y-1172936D01*
X-1452209Y-1171376D01*
G01X-1440354Y-1173456D02*
Y-1163056D01*
G01Y-1165136D02*
X-1439379Y-1164096D01*
X-1438404Y-1163316D01*
X-1437039Y-1163056D01*
X-1436064Y-1163316D01*
X-1434894Y-1164096D01*
G01X-1423234Y-1173456D02*
Y-1157856D01*
G01Y-1165656D02*
X-1422259Y-1164096D01*
X-1421089Y-1163316D01*
X-1419919Y-1163056D01*
X-1418164Y-1163576D01*
X-1416994Y-1164616D01*
X-1416214Y-1166436D01*
Y-1168516D01*
X-1416604Y-1170596D01*
X-1417384Y-1172156D01*
X-1418749Y-1173196D01*
X-1419919Y-1173456D01*
X-1421089Y-1173196D01*
X-1422259Y-1172416D01*
X-1423234Y-1171116D01*
G01X-1404749Y-1166436D02*
X-1398509D01*
X-1399094Y-1164616D01*
X-1400069Y-1163576D01*
X-1401434Y-1163056D01*
X-1402799Y-1163316D01*
X-1403969Y-1164096D01*
X-1404749Y-1165916D01*
X-1405139Y-1167476D01*
Y-1169036D01*
X-1404749Y-1170596D01*
X-1403774Y-1172156D01*
X-1402604Y-1173196D01*
X-1401239Y-1173456D01*
X-1399874Y-1172936D01*
X-1398509Y-1171376D01*
G01X-1386654Y-1173456D02*
Y-1163056D01*
G01Y-1165136D02*
X-1385679Y-1164096D01*
X-1384704Y-1163316D01*
X-1383339Y-1163056D01*
X-1382364Y-1163316D01*
X-1381194Y-1164096D01*
G01X-1351634Y-1178656D02*
Y-1163056D01*
G01Y-1165396D02*
X-1350659Y-1164096D01*
X-1349684Y-1163316D01*
X-1348124Y-1163056D01*
X-1346759Y-1163316D01*
X-1345394Y-1164616D01*
X-1344809Y-1166436D01*
X-1344614Y-1168256D01*
X-1344809Y-1170076D01*
X-1345394Y-1171896D01*
X-1346564Y-1172936D01*
X-1348124Y-1173456D01*
X-1349489Y-1173196D01*
X-1350854Y-1172416D01*
X-1351634Y-1171376D01*
G01X-1326714Y-1173456D02*
Y-1163056D01*
G01Y-1164876D02*
X-1327494Y-1163836D01*
X-1328664Y-1163316D01*
X-1330029Y-1163056D01*
X-1331394Y-1163576D01*
X-1332564Y-1164616D01*
X-1333344Y-1166176D01*
X-1333734Y-1168256D01*
X-1333344Y-1170336D01*
X-1332564Y-1171896D01*
X-1331394Y-1172936D01*
X-1330029Y-1173456D01*
X-1328664Y-1173196D01*
X-1327494Y-1172416D01*
X-1326714Y-1171376D01*
G01X-1309204Y-1164356D02*
X-1310569Y-1163316D01*
X-1311739Y-1163056D01*
X-1313299Y-1163576D01*
X-1314469Y-1164616D01*
X-1315249Y-1166436D01*
X-1315444Y-1168256D01*
X-1315249Y-1170076D01*
X-1314469Y-1171636D01*
X-1313299Y-1172936D01*
X-1311739Y-1173456D01*
X-1310374Y-1172936D01*
X-1309204Y-1171896D01*
G01X-1297739Y-1173456D02*
Y-1157856D01*
G01X-1291499Y-1163056D02*
X-1297739Y-1169036D01*
G01X-1295204Y-1166696D02*
X-1291109Y-1173456D01*
G01X-1273014D02*
Y-1163056D01*
G01Y-1164876D02*
X-1273794Y-1163836D01*
X-1274964Y-1163316D01*
X-1276329Y-1163056D01*
X-1277694Y-1163576D01*
X-1278864Y-1164616D01*
X-1279644Y-1166176D01*
X-1280034Y-1168256D01*
X-1279644Y-1170336D01*
X-1278864Y-1171896D01*
X-1277694Y-1172936D01*
X-1276329Y-1173456D01*
X-1274964Y-1173196D01*
X-1273794Y-1172416D01*
X-1273014Y-1171376D01*
G01X-1261354Y-1177356D02*
X-1259989Y-1178396D01*
X-1258429Y-1178656D01*
X-1257064Y-1178396D01*
X-1255894Y-1177096D01*
X-1255114Y-1175276D01*
Y-1163056D01*
G01Y-1165136D02*
X-1255894Y-1164096D01*
X-1257064Y-1163316D01*
X-1258429Y-1163056D01*
X-1259989Y-1163576D01*
X-1260964Y-1164616D01*
X-1261744Y-1166436D01*
X-1262134Y-1168256D01*
X-1261939Y-1169816D01*
X-1261159Y-1171636D01*
X-1259989Y-1172936D01*
X-1258429Y-1173456D01*
X-1257259Y-1173196D01*
X-1255894Y-1172156D01*
X-1255114Y-1171116D01*
G01X-1243649Y-1166436D02*
X-1237409D01*
X-1237994Y-1164616D01*
X-1238969Y-1163576D01*
X-1240334Y-1163056D01*
X-1241699Y-1163316D01*
X-1242869Y-1164096D01*
X-1243649Y-1165916D01*
X-1244039Y-1167476D01*
Y-1169036D01*
X-1243649Y-1170596D01*
X-1242674Y-1172156D01*
X-1241504Y-1173196D01*
X-1240139Y-1173456D01*
X-1238774Y-1172936D01*
X-1237409Y-1171376D01*
G01X-1222824Y-1173976D02*
X-1223214Y-1173716D01*
Y-1173196D01*
X-1222824Y-1172936D01*
X-1222434Y-1173196D01*
Y-1173716D01*
X-1222824Y-1173976D01*
G01X-2135724Y-1085456D02*
Y-1069856D01*
X-2138064Y-1072976D01*
G01Y-1085456D02*
X-2133384D01*
G01X-2117824D02*
Y-1069856D01*
X-2120164Y-1072976D01*
G01Y-1085456D02*
X-2115484D01*
G01X-2099924Y-1085976D02*
X-2100314Y-1085716D01*
Y-1085196D01*
X-2099924Y-1084936D01*
X-2099534Y-1085196D01*
Y-1085716D01*
X-2099924Y-1085976D01*
G01X-2085924Y-1085456D02*
Y-1069856D01*
X-2081244D01*
X-2079684Y-1070636D01*
X-2078514Y-1072456D01*
X-2078124Y-1074536D01*
X-2078514Y-1076616D01*
X-2079489Y-1078176D01*
X-2081244Y-1078956D01*
X-2085924D01*
G01X-2064124Y-1085456D02*
Y-1069856D01*
G01X-2049149Y-1078436D02*
X-2042909D01*
X-2043494Y-1076616D01*
X-2044469Y-1075576D01*
X-2045834Y-1075056D01*
X-2047199Y-1075316D01*
X-2048369Y-1076096D01*
X-2049149Y-1077916D01*
X-2049539Y-1079476D01*
Y-1081036D01*
X-2049149Y-1082596D01*
X-2048174Y-1084156D01*
X-2047004Y-1085196D01*
X-2045639Y-1085456D01*
X-2044274Y-1084936D01*
X-2042909Y-1083376D01*
G01X-2024814Y-1085456D02*
Y-1075056D01*
G01Y-1076876D02*
X-2025594Y-1075836D01*
X-2026764Y-1075316D01*
X-2028129Y-1075056D01*
X-2029494Y-1075576D01*
X-2030664Y-1076616D01*
X-2031444Y-1078176D01*
X-2031834Y-1080256D01*
X-2031444Y-1082336D01*
X-2030664Y-1083896D01*
X-2029494Y-1084936D01*
X-2028129Y-1085456D01*
X-2026764Y-1085196D01*
X-2025594Y-1084416D01*
X-2024814Y-1083376D01*
G01X-2013349Y-1083636D02*
X-2012374Y-1084676D01*
X-2011009Y-1085456D01*
X-2009839D01*
X-2008669Y-1084936D01*
X-2007889Y-1084156D01*
X-2007499Y-1083116D01*
X-2007694Y-1081556D01*
X-2008474Y-1080776D01*
X-2011984Y-1079216D01*
X-2012764Y-1077396D01*
X-2012374Y-1076096D01*
X-2011594Y-1075316D01*
X-2010424Y-1075056D01*
X-2009254Y-1075316D01*
X-2008084Y-1076096D01*
G01X-1995449Y-1078436D02*
X-1989209D01*
X-1989794Y-1076616D01*
X-1990769Y-1075576D01*
X-1992134Y-1075056D01*
X-1993499Y-1075316D01*
X-1994669Y-1076096D01*
X-1995449Y-1077916D01*
X-1995839Y-1079476D01*
Y-1081036D01*
X-1995449Y-1082596D01*
X-1994474Y-1084156D01*
X-1993304Y-1085196D01*
X-1991939Y-1085456D01*
X-1990574Y-1084936D01*
X-1989209Y-1083376D01*
G01X-1960234Y-1090656D02*
Y-1075056D01*
G01Y-1077396D02*
X-1959259Y-1076096D01*
X-1958284Y-1075316D01*
X-1956724Y-1075056D01*
X-1955359Y-1075316D01*
X-1953994Y-1076616D01*
X-1953409Y-1078436D01*
X-1953214Y-1080256D01*
X-1953409Y-1082076D01*
X-1953994Y-1083896D01*
X-1955164Y-1084936D01*
X-1956724Y-1085456D01*
X-1958089Y-1085196D01*
X-1959454Y-1084416D01*
X-1960234Y-1083376D01*
G01X-1941554Y-1085456D02*
Y-1075056D01*
G01Y-1077136D02*
X-1940579Y-1076096D01*
X-1939604Y-1075316D01*
X-1938239Y-1075056D01*
X-1937264Y-1075316D01*
X-1936094Y-1076096D01*
G01X-1920924Y-1085456D02*
X-1922094Y-1085196D01*
X-1923264Y-1084156D01*
X-1924044Y-1082336D01*
X-1924434Y-1080256D01*
X-1924044Y-1078176D01*
X-1923264Y-1076356D01*
X-1922094Y-1075316D01*
X-1920924Y-1075056D01*
X-1919754Y-1075316D01*
X-1918584Y-1076356D01*
X-1917804Y-1078176D01*
X-1917609Y-1080256D01*
X-1917804Y-1082336D01*
X-1918584Y-1084156D01*
X-1919754Y-1085196D01*
X-1920924Y-1085456D01*
G01X-1906534Y-1075056D02*
X-1903024Y-1085456D01*
X-1899514Y-1075056D01*
G01X-1885124D02*
Y-1085456D01*
G01Y-1070896D02*
X-1885514Y-1070636D01*
Y-1070116D01*
X-1885124Y-1069856D01*
X-1884734Y-1070116D01*
Y-1070636D01*
X-1885124Y-1070896D01*
G01X-1863714Y-1069856D02*
Y-1085456D01*
G01Y-1083116D02*
X-1864494Y-1084416D01*
X-1865664Y-1085196D01*
X-1867029Y-1085456D01*
X-1868589Y-1084936D01*
X-1869759Y-1083636D01*
X-1870539Y-1082076D01*
X-1870734Y-1080256D01*
X-1870539Y-1078436D01*
X-1869759Y-1076876D01*
X-1868589Y-1075576D01*
X-1867029Y-1075056D01*
X-1865664Y-1075316D01*
X-1864689Y-1075836D01*
X-1863714Y-1076876D01*
G01X-1852249Y-1078436D02*
X-1846009D01*
X-1846594Y-1076616D01*
X-1847569Y-1075576D01*
X-1848934Y-1075056D01*
X-1850299Y-1075316D01*
X-1851469Y-1076096D01*
X-1852249Y-1077916D01*
X-1852639Y-1079476D01*
Y-1081036D01*
X-1852249Y-1082596D01*
X-1851274Y-1084156D01*
X-1850104Y-1085196D01*
X-1848739Y-1085456D01*
X-1847374Y-1084936D01*
X-1846009Y-1083376D01*
G01X-1810014Y-1085456D02*
Y-1075056D01*
G01Y-1076876D02*
X-1810794Y-1075836D01*
X-1811964Y-1075316D01*
X-1813329Y-1075056D01*
X-1814694Y-1075576D01*
X-1815864Y-1076616D01*
X-1816644Y-1078176D01*
X-1817034Y-1080256D01*
X-1816644Y-1082336D01*
X-1815864Y-1083896D01*
X-1814694Y-1084936D01*
X-1813329Y-1085456D01*
X-1811964Y-1085196D01*
X-1810794Y-1084416D01*
X-1810014Y-1083376D01*
G01X-1792504Y-1076356D02*
X-1793869Y-1075316D01*
X-1795039Y-1075056D01*
X-1796599Y-1075576D01*
X-1797769Y-1076616D01*
X-1798549Y-1078436D01*
X-1798744Y-1080256D01*
X-1798549Y-1082076D01*
X-1797769Y-1083636D01*
X-1796599Y-1084936D01*
X-1795039Y-1085456D01*
X-1793674Y-1084936D01*
X-1792504Y-1083896D01*
G01X-1777724Y-1069856D02*
Y-1085456D01*
G01X-1780454Y-1075056D02*
X-1774994D01*
G01X-1763139D02*
Y-1082336D01*
X-1762359Y-1084156D01*
X-1761189Y-1085196D01*
X-1759824Y-1085456D01*
X-1758459Y-1085196D01*
X-1757289Y-1084156D01*
X-1756509Y-1082336D01*
G01Y-1085456D02*
Y-1075056D01*
G01X-1738414Y-1085456D02*
Y-1075056D01*
G01Y-1076876D02*
X-1739194Y-1075836D01*
X-1740364Y-1075316D01*
X-1741729Y-1075056D01*
X-1743094Y-1075576D01*
X-1744264Y-1076616D01*
X-1745044Y-1078176D01*
X-1745434Y-1080256D01*
X-1745044Y-1082336D01*
X-1744264Y-1083896D01*
X-1743094Y-1084936D01*
X-1741729Y-1085456D01*
X-1740364Y-1085196D01*
X-1739194Y-1084416D01*
X-1738414Y-1083376D01*
G01X-1724024Y-1085456D02*
Y-1069856D01*
G01X-1691539Y-1085456D02*
Y-1069856D01*
G01Y-1077396D02*
X-1690564Y-1076096D01*
X-1689589Y-1075316D01*
X-1688029Y-1075056D01*
X-1686859Y-1075316D01*
X-1685494Y-1076356D01*
X-1684909Y-1077916D01*
Y-1085456D01*
G01X-1670324D02*
X-1671494Y-1085196D01*
X-1672664Y-1084156D01*
X-1673444Y-1082336D01*
X-1673834Y-1080256D01*
X-1673444Y-1078176D01*
X-1672664Y-1076356D01*
X-1671494Y-1075316D01*
X-1670324Y-1075056D01*
X-1669154Y-1075316D01*
X-1667984Y-1076356D01*
X-1667204Y-1078176D01*
X-1667009Y-1080256D01*
X-1667204Y-1082336D01*
X-1667984Y-1084156D01*
X-1669154Y-1085196D01*
X-1670324Y-1085456D01*
G01X-1652424D02*
Y-1069856D01*
G01X-1637449Y-1078436D02*
X-1631209D01*
X-1631794Y-1076616D01*
X-1632769Y-1075576D01*
X-1634134Y-1075056D01*
X-1635499Y-1075316D01*
X-1636669Y-1076096D01*
X-1637449Y-1077916D01*
X-1637839Y-1079476D01*
Y-1081036D01*
X-1637449Y-1082596D01*
X-1636474Y-1084156D01*
X-1635304Y-1085196D01*
X-1633939Y-1085456D01*
X-1632574Y-1084936D01*
X-1631209Y-1083376D01*
G01X-1604574Y-1085456D02*
Y-1075056D01*
G01Y-1077916D02*
X-1603989Y-1076616D01*
X-1603014Y-1075576D01*
X-1601649Y-1075056D01*
X-1600284Y-1075576D01*
X-1599309Y-1076616D01*
X-1598724Y-1077916D01*
Y-1085456D01*
G01Y-1077916D02*
X-1598139Y-1076616D01*
X-1597164Y-1075576D01*
X-1595799Y-1075056D01*
X-1594434Y-1075576D01*
X-1593459Y-1076616D01*
X-1592874Y-1078176D01*
Y-1085456D01*
G01X-1583749Y-1078436D02*
X-1577509D01*
X-1578094Y-1076616D01*
X-1579069Y-1075576D01*
X-1580434Y-1075056D01*
X-1581799Y-1075316D01*
X-1582969Y-1076096D01*
X-1583749Y-1077916D01*
X-1584139Y-1079476D01*
Y-1081036D01*
X-1583749Y-1082596D01*
X-1582774Y-1084156D01*
X-1581604Y-1085196D01*
X-1580239Y-1085456D01*
X-1578874Y-1084936D01*
X-1577509Y-1083376D01*
G01X-1559414Y-1085456D02*
Y-1075056D01*
G01Y-1076876D02*
X-1560194Y-1075836D01*
X-1561364Y-1075316D01*
X-1562729Y-1075056D01*
X-1564094Y-1075576D01*
X-1565264Y-1076616D01*
X-1566044Y-1078176D01*
X-1566434Y-1080256D01*
X-1566044Y-1082336D01*
X-1565264Y-1083896D01*
X-1564094Y-1084936D01*
X-1562729Y-1085456D01*
X-1561364Y-1085196D01*
X-1560194Y-1084416D01*
X-1559414Y-1083376D01*
G01X-1547949Y-1083636D02*
X-1546974Y-1084676D01*
X-1545609Y-1085456D01*
X-1544439D01*
X-1543269Y-1084936D01*
X-1542489Y-1084156D01*
X-1542099Y-1083116D01*
X-1542294Y-1081556D01*
X-1543074Y-1080776D01*
X-1546584Y-1079216D01*
X-1547364Y-1077396D01*
X-1546974Y-1076096D01*
X-1546194Y-1075316D01*
X-1545024Y-1075056D01*
X-1543854Y-1075316D01*
X-1542684Y-1076096D01*
G01X-1530439Y-1075056D02*
Y-1082336D01*
X-1529659Y-1084156D01*
X-1528489Y-1085196D01*
X-1527124Y-1085456D01*
X-1525759Y-1085196D01*
X-1524589Y-1084156D01*
X-1523809Y-1082336D01*
G01Y-1085456D02*
Y-1075056D01*
G01X-1511954Y-1085456D02*
Y-1075056D01*
G01Y-1077136D02*
X-1510979Y-1076096D01*
X-1510004Y-1075316D01*
X-1508639Y-1075056D01*
X-1507664Y-1075316D01*
X-1506494Y-1076096D01*
G01X-1494249Y-1078436D02*
X-1488009D01*
X-1488594Y-1076616D01*
X-1489569Y-1075576D01*
X-1490934Y-1075056D01*
X-1492299Y-1075316D01*
X-1493469Y-1076096D01*
X-1494249Y-1077916D01*
X-1494639Y-1079476D01*
Y-1081036D01*
X-1494249Y-1082596D01*
X-1493274Y-1084156D01*
X-1492104Y-1085196D01*
X-1490739Y-1085456D01*
X-1489374Y-1084936D01*
X-1488009Y-1083376D01*
G01X-1479274Y-1085456D02*
Y-1075056D01*
G01Y-1077916D02*
X-1478689Y-1076616D01*
X-1477714Y-1075576D01*
X-1476349Y-1075056D01*
X-1474984Y-1075576D01*
X-1474009Y-1076616D01*
X-1473424Y-1077916D01*
Y-1085456D01*
G01Y-1077916D02*
X-1472839Y-1076616D01*
X-1471864Y-1075576D01*
X-1470499Y-1075056D01*
X-1469134Y-1075576D01*
X-1468159Y-1076616D01*
X-1467574Y-1078176D01*
Y-1085456D01*
G01X-1458449Y-1078436D02*
X-1452209D01*
X-1452794Y-1076616D01*
X-1453769Y-1075576D01*
X-1455134Y-1075056D01*
X-1456499Y-1075316D01*
X-1457669Y-1076096D01*
X-1458449Y-1077916D01*
X-1458839Y-1079476D01*
Y-1081036D01*
X-1458449Y-1082596D01*
X-1457474Y-1084156D01*
X-1456304Y-1085196D01*
X-1454939Y-1085456D01*
X-1453574Y-1084936D01*
X-1452209Y-1083376D01*
G01X-1440939Y-1085456D02*
Y-1075056D01*
G01Y-1077656D02*
X-1440159Y-1076356D01*
X-1438989Y-1075316D01*
X-1437429Y-1075056D01*
X-1436064Y-1075316D01*
X-1434894Y-1076356D01*
X-1434309Y-1078176D01*
Y-1085456D01*
G01X-1419724Y-1069856D02*
Y-1085456D01*
G01X-1422454Y-1075056D02*
X-1416994D01*
G01X-1386654Y-1085456D02*
Y-1075056D01*
G01Y-1077136D02*
X-1385679Y-1076096D01*
X-1384704Y-1075316D01*
X-1383339Y-1075056D01*
X-1382364Y-1075316D01*
X-1381194Y-1076096D01*
G01X-1368949Y-1078436D02*
X-1362709D01*
X-1363294Y-1076616D01*
X-1364269Y-1075576D01*
X-1365634Y-1075056D01*
X-1366999Y-1075316D01*
X-1368169Y-1076096D01*
X-1368949Y-1077916D01*
X-1369339Y-1079476D01*
Y-1081036D01*
X-1368949Y-1082596D01*
X-1367974Y-1084156D01*
X-1366804Y-1085196D01*
X-1365439Y-1085456D01*
X-1364074Y-1084936D01*
X-1362709Y-1083376D01*
G01X-1351634Y-1090656D02*
Y-1075056D01*
G01Y-1077396D02*
X-1350659Y-1076096D01*
X-1349684Y-1075316D01*
X-1348124Y-1075056D01*
X-1346759Y-1075316D01*
X-1345394Y-1076616D01*
X-1344809Y-1078436D01*
X-1344614Y-1080256D01*
X-1344809Y-1082076D01*
X-1345394Y-1083896D01*
X-1346564Y-1084936D01*
X-1348124Y-1085456D01*
X-1349489Y-1085196D01*
X-1350854Y-1084416D01*
X-1351634Y-1083376D01*
G01X-1330224Y-1085456D02*
X-1331394Y-1085196D01*
X-1332564Y-1084156D01*
X-1333344Y-1082336D01*
X-1333734Y-1080256D01*
X-1333344Y-1078176D01*
X-1332564Y-1076356D01*
X-1331394Y-1075316D01*
X-1330224Y-1075056D01*
X-1329054Y-1075316D01*
X-1327884Y-1076356D01*
X-1327104Y-1078176D01*
X-1326909Y-1080256D01*
X-1327104Y-1082336D01*
X-1327884Y-1084156D01*
X-1329054Y-1085196D01*
X-1330224Y-1085456D01*
G01X-1315054D02*
Y-1075056D01*
G01Y-1077136D02*
X-1314079Y-1076096D01*
X-1313104Y-1075316D01*
X-1311739Y-1075056D01*
X-1310764Y-1075316D01*
X-1309594Y-1076096D01*
G01X-1294424Y-1069856D02*
Y-1085456D01*
G01X-1297154Y-1075056D02*
X-1291694D01*
G01X-1259794Y-1085456D02*
Y-1072196D01*
X-1259404Y-1070896D01*
X-1258624Y-1070116D01*
X-1257454Y-1069856D01*
X-1256284Y-1070376D01*
X-1255699Y-1071676D01*
G01X-1258039Y-1076096D02*
X-1261939D01*
G01X-1240724Y-1085456D02*
X-1241894Y-1085196D01*
X-1243064Y-1084156D01*
X-1243844Y-1082336D01*
X-1244234Y-1080256D01*
X-1243844Y-1078176D01*
X-1243064Y-1076356D01*
X-1241894Y-1075316D01*
X-1240724Y-1075056D01*
X-1239554Y-1075316D01*
X-1238384Y-1076356D01*
X-1237604Y-1078176D01*
X-1237409Y-1080256D01*
X-1237604Y-1082336D01*
X-1238384Y-1084156D01*
X-1239554Y-1085196D01*
X-1240724Y-1085456D01*
G01X-1225554D02*
Y-1075056D01*
G01Y-1077136D02*
X-1224579Y-1076096D01*
X-1223604Y-1075316D01*
X-1222239Y-1075056D01*
X-1221264Y-1075316D01*
X-1220094Y-1076096D01*
G01X-1190534Y-1090656D02*
Y-1075056D01*
G01Y-1077396D02*
X-1189559Y-1076096D01*
X-1188584Y-1075316D01*
X-1187024Y-1075056D01*
X-1185659Y-1075316D01*
X-1184294Y-1076616D01*
X-1183709Y-1078436D01*
X-1183514Y-1080256D01*
X-1183709Y-1082076D01*
X-1184294Y-1083896D01*
X-1185464Y-1084936D01*
X-1187024Y-1085456D01*
X-1188389Y-1085196D01*
X-1189754Y-1084416D01*
X-1190534Y-1083376D01*
G01X-1171854Y-1085456D02*
Y-1075056D01*
G01Y-1077136D02*
X-1170879Y-1076096D01*
X-1169904Y-1075316D01*
X-1168539Y-1075056D01*
X-1167564Y-1075316D01*
X-1166394Y-1076096D01*
G01X-1154149Y-1078436D02*
X-1147909D01*
X-1148494Y-1076616D01*
X-1149469Y-1075576D01*
X-1150834Y-1075056D01*
X-1152199Y-1075316D01*
X-1153369Y-1076096D01*
X-1154149Y-1077916D01*
X-1154539Y-1079476D01*
Y-1081036D01*
X-1154149Y-1082596D01*
X-1153174Y-1084156D01*
X-1152004Y-1085196D01*
X-1150639Y-1085456D01*
X-1149274Y-1084936D01*
X-1147909Y-1083376D01*
G01X-1136249Y-1083636D02*
X-1135274Y-1084676D01*
X-1133909Y-1085456D01*
X-1132739D01*
X-1131569Y-1084936D01*
X-1130789Y-1084156D01*
X-1130399Y-1083116D01*
X-1130594Y-1081556D01*
X-1131374Y-1080776D01*
X-1134884Y-1079216D01*
X-1135664Y-1077396D01*
X-1135274Y-1076096D01*
X-1134494Y-1075316D01*
X-1133324Y-1075056D01*
X-1132154Y-1075316D01*
X-1130984Y-1076096D01*
G01X-1118349Y-1083636D02*
X-1117374Y-1084676D01*
X-1116009Y-1085456D01*
X-1114839D01*
X-1113669Y-1084936D01*
X-1112889Y-1084156D01*
X-1112499Y-1083116D01*
X-1112694Y-1081556D01*
X-1113474Y-1080776D01*
X-1116984Y-1079216D01*
X-1117764Y-1077396D01*
X-1117374Y-1076096D01*
X-1116594Y-1075316D01*
X-1115424Y-1075056D01*
X-1114254Y-1075316D01*
X-1113084Y-1076096D01*
G01X-1100059Y-1080256D02*
X-1094989D01*
G01X-1080794Y-1085456D02*
Y-1072196D01*
X-1080404Y-1070896D01*
X-1079624Y-1070116D01*
X-1078454Y-1069856D01*
X-1077284Y-1070376D01*
X-1076699Y-1071676D01*
G01X-1079039Y-1076096D02*
X-1082939D01*
G01X-1061724Y-1075056D02*
Y-1085456D01*
G01Y-1070896D02*
X-1062114Y-1070636D01*
Y-1070116D01*
X-1061724Y-1069856D01*
X-1061334Y-1070116D01*
Y-1070636D01*
X-1061724Y-1070896D01*
G01X-1043824Y-1069856D02*
Y-1085456D01*
G01X-1046554Y-1075056D02*
X-1041094D01*
G01X-1011339Y-1085456D02*
Y-1069856D01*
G01Y-1077396D02*
X-1010364Y-1076096D01*
X-1009389Y-1075316D01*
X-1007829Y-1075056D01*
X-1006659Y-1075316D01*
X-1005294Y-1076356D01*
X-1004709Y-1077916D01*
Y-1085456D01*
G01X-990124D02*
X-991294Y-1085196D01*
X-992464Y-1084156D01*
X-993244Y-1082336D01*
X-993634Y-1080256D01*
X-993244Y-1078176D01*
X-992464Y-1076356D01*
X-991294Y-1075316D01*
X-990124Y-1075056D01*
X-988954Y-1075316D01*
X-987784Y-1076356D01*
X-987004Y-1078176D01*
X-986809Y-1080256D01*
X-987004Y-1082336D01*
X-987784Y-1084156D01*
X-988954Y-1085196D01*
X-990124Y-1085456D01*
G01X-972224D02*
Y-1069856D01*
G01X-957249Y-1078436D02*
X-951009D01*
X-951594Y-1076616D01*
X-952569Y-1075576D01*
X-953934Y-1075056D01*
X-955299Y-1075316D01*
X-956469Y-1076096D01*
X-957249Y-1077916D01*
X-957639Y-1079476D01*
Y-1081036D01*
X-957249Y-1082596D01*
X-956274Y-1084156D01*
X-955104Y-1085196D01*
X-953739Y-1085456D01*
X-952374Y-1084936D01*
X-951009Y-1083376D01*
G01X-939349Y-1083636D02*
X-938374Y-1084676D01*
X-937009Y-1085456D01*
X-935839D01*
X-934669Y-1084936D01*
X-933889Y-1084156D01*
X-933499Y-1083116D01*
X-933694Y-1081556D01*
X-934474Y-1080776D01*
X-937984Y-1079216D01*
X-938764Y-1077396D01*
X-938374Y-1076096D01*
X-937594Y-1075316D01*
X-936424Y-1075056D01*
X-935254Y-1075316D01*
X-934084Y-1076096D01*
G01X-897114Y-1085456D02*
Y-1075056D01*
G01Y-1076876D02*
X-897894Y-1075836D01*
X-899064Y-1075316D01*
X-900429Y-1075056D01*
X-901794Y-1075576D01*
X-902964Y-1076616D01*
X-903744Y-1078176D01*
X-904134Y-1080256D01*
X-903744Y-1082336D01*
X-902964Y-1083896D01*
X-901794Y-1084936D01*
X-900429Y-1085456D01*
X-899064Y-1085196D01*
X-897894Y-1084416D01*
X-897114Y-1083376D01*
G01X-886039Y-1085456D02*
Y-1075056D01*
G01Y-1077656D02*
X-885259Y-1076356D01*
X-884089Y-1075316D01*
X-882529Y-1075056D01*
X-881164Y-1075316D01*
X-879994Y-1076356D01*
X-879409Y-1078176D01*
Y-1085456D01*
G01X-861314Y-1069856D02*
Y-1085456D01*
G01Y-1083116D02*
X-862094Y-1084416D01*
X-863264Y-1085196D01*
X-864629Y-1085456D01*
X-866189Y-1084936D01*
X-867359Y-1083636D01*
X-868139Y-1082076D01*
X-868334Y-1080256D01*
X-868139Y-1078436D01*
X-867359Y-1076876D01*
X-866189Y-1075576D01*
X-864629Y-1075056D01*
X-863264Y-1075316D01*
X-862289Y-1075836D01*
X-861314Y-1076876D01*
G01X-832339Y-1085456D02*
Y-1075056D01*
G01Y-1077656D02*
X-831559Y-1076356D01*
X-830389Y-1075316D01*
X-828829Y-1075056D01*
X-827464Y-1075316D01*
X-826294Y-1076356D01*
X-825709Y-1078176D01*
Y-1085456D01*
G01X-811124D02*
X-812294Y-1085196D01*
X-813464Y-1084156D01*
X-814244Y-1082336D01*
X-814634Y-1080256D01*
X-814244Y-1078176D01*
X-813464Y-1076356D01*
X-812294Y-1075316D01*
X-811124Y-1075056D01*
X-809954Y-1075316D01*
X-808784Y-1076356D01*
X-808004Y-1078176D01*
X-807809Y-1080256D01*
X-808004Y-1082336D01*
X-808784Y-1084156D01*
X-809954Y-1085196D01*
X-811124Y-1085456D01*
G01X-796539D02*
Y-1075056D01*
G01Y-1077656D02*
X-795759Y-1076356D01*
X-794589Y-1075316D01*
X-793029Y-1075056D01*
X-791664Y-1075316D01*
X-790494Y-1076356D01*
X-789909Y-1078176D01*
Y-1085456D01*
G01X-777859Y-1080256D02*
X-772789D01*
G01X-761324Y-1085456D02*
Y-1069856D01*
X-756644D01*
X-755084Y-1070636D01*
X-753914Y-1072456D01*
X-753524Y-1074536D01*
X-753914Y-1076616D01*
X-754889Y-1078176D01*
X-756644Y-1078956D01*
X-761324D01*
G01X-739524Y-1069856D02*
Y-1085456D01*
G01X-744009Y-1069856D02*
X-735039D01*
G01X-725719Y-1085456D02*
Y-1069856D01*
G01X-717529D02*
Y-1085456D01*
G01Y-1077656D02*
X-725719D01*
G01X-689139Y-1085456D02*
Y-1069856D01*
G01Y-1077396D02*
X-688164Y-1076096D01*
X-687189Y-1075316D01*
X-685629Y-1075056D01*
X-684459Y-1075316D01*
X-683094Y-1076356D01*
X-682509Y-1077916D01*
Y-1085456D01*
G01X-667924D02*
X-669094Y-1085196D01*
X-670264Y-1084156D01*
X-671044Y-1082336D01*
X-671434Y-1080256D01*
X-671044Y-1078176D01*
X-670264Y-1076356D01*
X-669094Y-1075316D01*
X-667924Y-1075056D01*
X-666754Y-1075316D01*
X-665584Y-1076356D01*
X-664804Y-1078176D01*
X-664609Y-1080256D01*
X-664804Y-1082336D01*
X-665584Y-1084156D01*
X-666754Y-1085196D01*
X-667924Y-1085456D01*
G01X-650024D02*
Y-1069856D01*
G01X-635049Y-1078436D02*
X-628809D01*
X-629394Y-1076616D01*
X-630369Y-1075576D01*
X-631734Y-1075056D01*
X-633099Y-1075316D01*
X-634269Y-1076096D01*
X-635049Y-1077916D01*
X-635439Y-1079476D01*
Y-1081036D01*
X-635049Y-1082596D01*
X-634074Y-1084156D01*
X-632904Y-1085196D01*
X-631539Y-1085456D01*
X-630174Y-1084936D01*
X-628809Y-1083376D01*
G01X-617149Y-1083636D02*
X-616174Y-1084676D01*
X-614809Y-1085456D01*
X-613639D01*
X-612469Y-1084936D01*
X-611689Y-1084156D01*
X-611299Y-1083116D01*
X-611494Y-1081556D01*
X-612274Y-1080776D01*
X-615784Y-1079216D01*
X-616564Y-1077396D01*
X-616174Y-1076096D01*
X-615394Y-1075316D01*
X-614224Y-1075056D01*
X-613054Y-1075316D01*
X-611884Y-1076096D01*
G01X-578424Y-1075056D02*
Y-1085456D01*
G01Y-1070896D02*
X-578814Y-1070636D01*
Y-1070116D01*
X-578424Y-1069856D01*
X-578034Y-1070116D01*
Y-1070636D01*
X-578424Y-1070896D01*
G01X-563839Y-1085456D02*
Y-1075056D01*
G01Y-1077656D02*
X-563059Y-1076356D01*
X-561889Y-1075316D01*
X-560329Y-1075056D01*
X-558964Y-1075316D01*
X-557794Y-1076356D01*
X-557209Y-1078176D01*
Y-1085456D01*
G01X-521214D02*
Y-1075056D01*
G01Y-1076876D02*
X-521994Y-1075836D01*
X-523164Y-1075316D01*
X-524529Y-1075056D01*
X-525894Y-1075576D01*
X-527064Y-1076616D01*
X-527844Y-1078176D01*
X-528234Y-1080256D01*
X-527844Y-1082336D01*
X-527064Y-1083896D01*
X-525894Y-1084936D01*
X-524529Y-1085456D01*
X-523164Y-1085196D01*
X-521994Y-1084416D01*
X-521214Y-1083376D01*
G01X-492434Y-1085456D02*
Y-1069856D01*
G01Y-1077656D02*
X-491459Y-1076096D01*
X-490289Y-1075316D01*
X-489119Y-1075056D01*
X-487364Y-1075576D01*
X-486194Y-1076616D01*
X-485414Y-1078436D01*
Y-1080516D01*
X-485804Y-1082596D01*
X-486584Y-1084156D01*
X-487949Y-1085196D01*
X-489119Y-1085456D01*
X-490289Y-1085196D01*
X-491459Y-1084416D01*
X-492434Y-1083116D01*
G01X-471024Y-1085456D02*
X-472194Y-1085196D01*
X-473364Y-1084156D01*
X-474144Y-1082336D01*
X-474534Y-1080256D01*
X-474144Y-1078176D01*
X-473364Y-1076356D01*
X-472194Y-1075316D01*
X-471024Y-1075056D01*
X-469854Y-1075316D01*
X-468684Y-1076356D01*
X-467904Y-1078176D01*
X-467709Y-1080256D01*
X-467904Y-1082336D01*
X-468684Y-1084156D01*
X-469854Y-1085196D01*
X-471024Y-1085456D01*
G01X-449614D02*
Y-1075056D01*
G01Y-1076876D02*
X-450394Y-1075836D01*
X-451564Y-1075316D01*
X-452929Y-1075056D01*
X-454294Y-1075576D01*
X-455464Y-1076616D01*
X-456244Y-1078176D01*
X-456634Y-1080256D01*
X-456244Y-1082336D01*
X-455464Y-1083896D01*
X-454294Y-1084936D01*
X-452929Y-1085456D01*
X-451564Y-1085196D01*
X-450394Y-1084416D01*
X-449614Y-1083376D01*
G01X-437954Y-1085456D02*
Y-1075056D01*
G01Y-1077136D02*
X-436979Y-1076096D01*
X-436004Y-1075316D01*
X-434639Y-1075056D01*
X-433664Y-1075316D01*
X-432494Y-1076096D01*
G01X-413814Y-1069856D02*
Y-1085456D01*
G01Y-1083116D02*
X-414594Y-1084416D01*
X-415764Y-1085196D01*
X-417129Y-1085456D01*
X-418689Y-1084936D01*
X-419859Y-1083636D01*
X-420639Y-1082076D01*
X-420834Y-1080256D01*
X-420639Y-1078436D01*
X-419859Y-1076876D01*
X-418689Y-1075576D01*
X-417129Y-1075056D01*
X-415764Y-1075316D01*
X-414789Y-1075836D01*
X-413814Y-1076876D01*
G01X-399424Y-1085976D02*
X-399814Y-1085716D01*
Y-1085196D01*
X-399424Y-1084936D01*
X-399034Y-1085196D01*
Y-1085716D01*
X-399424Y-1085976D01*
G01X-2135724Y-963456D02*
Y-947856D01*
X-2138064Y-950976D01*
G01Y-963456D02*
X-2133384D01*
G01X-2117824Y-947856D02*
X-2119384Y-948376D01*
X-2120554Y-949676D01*
X-2121334Y-951236D01*
X-2121919Y-953316D01*
X-2122114Y-955656D01*
X-2121919Y-957996D01*
X-2121334Y-960076D01*
X-2120554Y-961636D01*
X-2119384Y-962936D01*
X-2117824Y-963456D01*
X-2116264Y-962936D01*
X-2115094Y-961636D01*
X-2114314Y-960076D01*
X-2113729Y-957996D01*
X-2113534Y-955656D01*
X-2113729Y-953316D01*
X-2114314Y-951236D01*
X-2115094Y-949676D01*
X-2116264Y-948376D01*
X-2117824Y-947856D01*
G01X-2099924Y-963976D02*
X-2100314Y-963716D01*
Y-963196D01*
X-2099924Y-962936D01*
X-2099534Y-963196D01*
Y-963716D01*
X-2099924Y-963976D01*
G01X-2068999Y-963456D02*
X-2064124Y-947856D01*
X-2059249Y-963456D01*
G01X-2061004Y-957996D02*
X-2067244D01*
G01X-2046224Y-963456D02*
Y-947856D01*
G01X-2028324Y-963456D02*
Y-947856D01*
G01X-1990964Y-955136D02*
X-1990184Y-954356D01*
X-1989599Y-953056D01*
X-1989209Y-951236D01*
X-1989599Y-949676D01*
X-1990379Y-948636D01*
X-1991744Y-947856D01*
X-1997009D01*
Y-963456D01*
X-1990574D01*
X-1989209Y-962416D01*
X-1988429Y-960856D01*
X-1988039Y-959036D01*
X-1988429Y-957216D01*
X-1989599Y-955656D01*
X-1990964Y-955136D01*
X-1997009D01*
G01X-1973454Y-955656D02*
X-1969554D01*
Y-960336D01*
X-1970724Y-961896D01*
X-1972089Y-962936D01*
X-1974039Y-963456D01*
X-1975989Y-962936D01*
X-1977354Y-961896D01*
X-1978524Y-960336D01*
X-1979304Y-958516D01*
X-1979694Y-956436D01*
Y-954616D01*
X-1979304Y-953056D01*
X-1978524Y-951236D01*
X-1977354Y-949676D01*
X-1976184Y-948636D01*
X-1974624Y-947856D01*
X-1973259D01*
X-1971699Y-948376D01*
X-1970529Y-949416D01*
G01X-1961599Y-963456D02*
X-1956724Y-947856D01*
X-1951849Y-963456D01*
G01X-1953604Y-957996D02*
X-1959844D01*
G01X-1924434Y-968656D02*
Y-953056D01*
G01Y-955396D02*
X-1923459Y-954096D01*
X-1922484Y-953316D01*
X-1920924Y-953056D01*
X-1919559Y-953316D01*
X-1918194Y-954616D01*
X-1917609Y-956436D01*
X-1917414Y-958256D01*
X-1917609Y-960076D01*
X-1918194Y-961896D01*
X-1919364Y-962936D01*
X-1920924Y-963456D01*
X-1922289Y-963196D01*
X-1923654Y-962416D01*
X-1924434Y-961376D01*
G01X-1899514Y-963456D02*
Y-953056D01*
G01Y-954876D02*
X-1900294Y-953836D01*
X-1901464Y-953316D01*
X-1902829Y-953056D01*
X-1904194Y-953576D01*
X-1905364Y-954616D01*
X-1906144Y-956176D01*
X-1906534Y-958256D01*
X-1906144Y-960336D01*
X-1905364Y-961896D01*
X-1904194Y-962936D01*
X-1902829Y-963456D01*
X-1901464Y-963196D01*
X-1900294Y-962416D01*
X-1899514Y-961376D01*
G01X-1882004Y-954356D02*
X-1883369Y-953316D01*
X-1884539Y-953056D01*
X-1886099Y-953576D01*
X-1887269Y-954616D01*
X-1888049Y-956436D01*
X-1888244Y-958256D01*
X-1888049Y-960076D01*
X-1887269Y-961636D01*
X-1886099Y-962936D01*
X-1884539Y-963456D01*
X-1883174Y-962936D01*
X-1882004Y-961896D01*
G01X-1870539Y-963456D02*
Y-947856D01*
G01X-1864299Y-953056D02*
X-1870539Y-959036D01*
G01X-1868004Y-956696D02*
X-1863909Y-963456D01*
G01X-1845814D02*
Y-953056D01*
G01Y-954876D02*
X-1846594Y-953836D01*
X-1847764Y-953316D01*
X-1849129Y-953056D01*
X-1850494Y-953576D01*
X-1851664Y-954616D01*
X-1852444Y-956176D01*
X-1852834Y-958256D01*
X-1852444Y-960336D01*
X-1851664Y-961896D01*
X-1850494Y-962936D01*
X-1849129Y-963456D01*
X-1847764Y-963196D01*
X-1846594Y-962416D01*
X-1845814Y-961376D01*
G01X-1834154Y-967356D02*
X-1832789Y-968396D01*
X-1831229Y-968656D01*
X-1829864Y-968396D01*
X-1828694Y-967096D01*
X-1827914Y-965276D01*
Y-953056D01*
G01Y-955136D02*
X-1828694Y-954096D01*
X-1829864Y-953316D01*
X-1831229Y-953056D01*
X-1832789Y-953576D01*
X-1833764Y-954616D01*
X-1834544Y-956436D01*
X-1834934Y-958256D01*
X-1834739Y-959816D01*
X-1833959Y-961636D01*
X-1832789Y-962936D01*
X-1831229Y-963456D01*
X-1830059Y-963196D01*
X-1828694Y-962156D01*
X-1827914Y-961116D01*
G01X-1816449Y-956436D02*
X-1810209D01*
X-1810794Y-954616D01*
X-1811769Y-953576D01*
X-1813134Y-953056D01*
X-1814499Y-953316D01*
X-1815669Y-954096D01*
X-1816449Y-955916D01*
X-1816839Y-957476D01*
Y-959036D01*
X-1816449Y-960596D01*
X-1815474Y-962156D01*
X-1814304Y-963196D01*
X-1812939Y-963456D01*
X-1811574Y-962936D01*
X-1810209Y-961376D01*
G01X-1780649Y-961636D02*
X-1779674Y-962676D01*
X-1778309Y-963456D01*
X-1777139D01*
X-1775969Y-962936D01*
X-1775189Y-962156D01*
X-1774799Y-961116D01*
X-1774994Y-959556D01*
X-1775774Y-958776D01*
X-1779284Y-957216D01*
X-1780064Y-955396D01*
X-1779674Y-954096D01*
X-1778894Y-953316D01*
X-1777724Y-953056D01*
X-1776554Y-953316D01*
X-1775384Y-954096D01*
G01X-1759824Y-953056D02*
Y-963456D01*
G01Y-948896D02*
X-1760214Y-948636D01*
Y-948116D01*
X-1759824Y-947856D01*
X-1759434Y-948116D01*
Y-948636D01*
X-1759824Y-948896D01*
G01X-1741924Y-947856D02*
Y-963456D01*
G01X-1744654Y-953056D02*
X-1739194D01*
G01X-1726949Y-956436D02*
X-1720709D01*
X-1721294Y-954616D01*
X-1722269Y-953576D01*
X-1723634Y-953056D01*
X-1724999Y-953316D01*
X-1726169Y-954096D01*
X-1726949Y-955916D01*
X-1727339Y-957476D01*
Y-959036D01*
X-1726949Y-960596D01*
X-1725974Y-962156D01*
X-1724804Y-963196D01*
X-1723439Y-963456D01*
X-1722074Y-962936D01*
X-1720709Y-961376D01*
G01X-1709049Y-961636D02*
X-1708074Y-962676D01*
X-1706709Y-963456D01*
X-1705539D01*
X-1704369Y-962936D01*
X-1703589Y-962156D01*
X-1703199Y-961116D01*
X-1703394Y-959556D01*
X-1704174Y-958776D01*
X-1707684Y-957216D01*
X-1708464Y-955396D01*
X-1708074Y-954096D01*
X-1707294Y-953316D01*
X-1706124Y-953056D01*
X-1704954Y-953316D01*
X-1703784Y-954096D01*
G01X-1670324Y-963456D02*
X-1671494Y-963196D01*
X-1672664Y-962156D01*
X-1673444Y-960336D01*
X-1673834Y-958256D01*
X-1673444Y-956176D01*
X-1672664Y-954356D01*
X-1671494Y-953316D01*
X-1670324Y-953056D01*
X-1669154Y-953316D01*
X-1667984Y-954356D01*
X-1667204Y-956176D01*
X-1667009Y-958256D01*
X-1667204Y-960336D01*
X-1667984Y-962156D01*
X-1669154Y-963196D01*
X-1670324Y-963456D01*
G01X-1653594D02*
Y-950196D01*
X-1653204Y-948896D01*
X-1652424Y-948116D01*
X-1651254Y-947856D01*
X-1650084Y-948376D01*
X-1649499Y-949676D01*
G01X-1651839Y-954096D02*
X-1655739D01*
G01X-1614284Y-963456D02*
Y-947856D01*
X-1621499Y-959036D01*
X-1611749D01*
G01X-1599114Y-963456D02*
X-1598724Y-960076D01*
X-1598139Y-957216D01*
X-1597359Y-954616D01*
X-1596384Y-951756D01*
X-1594824Y-947856D01*
X-1602624D01*
G01X-1580824Y-963976D02*
X-1581214Y-963716D01*
Y-963196D01*
X-1580824Y-962936D01*
X-1580434Y-963196D01*
Y-963716D01*
X-1580824Y-963976D01*
G01X-1567214Y-961116D02*
X-1566044Y-962416D01*
X-1564679Y-963196D01*
X-1562924Y-963456D01*
X-1561169Y-962936D01*
X-1559804Y-961896D01*
X-1558829Y-960076D01*
X-1558634Y-957996D01*
X-1559024Y-955916D01*
X-1559999Y-954616D01*
X-1561364Y-953576D01*
X-1562729Y-953316D01*
X-1564094Y-953576D01*
X-1565849Y-954616D01*
X-1565264Y-947856D01*
X-1559999D01*
G01X-1532194Y-963456D02*
Y-947856D01*
X-1527124Y-960856D01*
X-1522054Y-947856D01*
Y-963456D01*
G01X-1514294D02*
Y-947856D01*
X-1509224Y-960856D01*
X-1504154Y-947856D01*
Y-963456D01*
G01X-1492299Y-968656D02*
X-1494249Y-966056D01*
X-1495224Y-963456D01*
Y-953056D01*
X-1494249Y-950456D01*
X-1492299Y-947856D01*
G01X-1473424Y-963456D02*
Y-947856D01*
X-1475764Y-950976D01*
G01Y-963456D02*
X-1471084D01*
G01X-1455524Y-963976D02*
X-1455914Y-963716D01*
Y-963196D01*
X-1455524Y-962936D01*
X-1455134Y-963196D01*
Y-963716D01*
X-1455524Y-963976D01*
G01X-1437624Y-963456D02*
X-1436259Y-963196D01*
X-1434699Y-962416D01*
X-1433724Y-961116D01*
X-1433334Y-959296D01*
X-1433724Y-957476D01*
X-1434894Y-955916D01*
X-1436649Y-955136D01*
X-1438599D01*
X-1439769Y-954616D01*
X-1440744Y-953316D01*
X-1441134Y-951496D01*
X-1440549Y-949676D01*
X-1439184Y-948376D01*
X-1437624Y-947856D01*
X-1436064Y-948376D01*
X-1434699Y-949676D01*
X-1434114Y-951496D01*
X-1434504Y-953316D01*
X-1435479Y-954616D01*
X-1436649Y-955136D01*
X-1438599D01*
X-1440354Y-955916D01*
X-1441524Y-957476D01*
X-1441914Y-959296D01*
X-1441524Y-961116D01*
X-1440549Y-962416D01*
X-1438989Y-963196D01*
X-1437624Y-963456D01*
G01X-1420114D02*
X-1419724Y-960076D01*
X-1419139Y-957216D01*
X-1418359Y-954616D01*
X-1417384Y-951756D01*
X-1415824Y-947856D01*
X-1423624D01*
G01X-1383924Y-953056D02*
Y-963456D01*
G01Y-948896D02*
X-1384314Y-948636D01*
Y-948116D01*
X-1383924Y-947856D01*
X-1383534Y-948116D01*
Y-948636D01*
X-1383924Y-948896D01*
G01X-1369339Y-963456D02*
Y-953056D01*
G01Y-955656D02*
X-1368559Y-954356D01*
X-1367389Y-953316D01*
X-1365829Y-953056D01*
X-1364464Y-953316D01*
X-1363294Y-954356D01*
X-1362709Y-956176D01*
Y-963456D01*
G01X-1345004Y-954356D02*
X-1346369Y-953316D01*
X-1347539Y-953056D01*
X-1349099Y-953576D01*
X-1350269Y-954616D01*
X-1351049Y-956436D01*
X-1351244Y-958256D01*
X-1351049Y-960076D01*
X-1350269Y-961636D01*
X-1349099Y-962936D01*
X-1347539Y-963456D01*
X-1346174Y-962936D01*
X-1345004Y-961896D01*
G01X-1333539Y-963456D02*
Y-947856D01*
G01Y-955396D02*
X-1332564Y-954096D01*
X-1331589Y-953316D01*
X-1330029Y-953056D01*
X-1328859Y-953316D01*
X-1327494Y-954356D01*
X-1326909Y-955916D01*
Y-963456D01*
G01X-1315249Y-956436D02*
X-1309009D01*
X-1309594Y-954616D01*
X-1310569Y-953576D01*
X-1311934Y-953056D01*
X-1313299Y-953316D01*
X-1314469Y-954096D01*
X-1315249Y-955916D01*
X-1315639Y-957476D01*
Y-959036D01*
X-1315249Y-960596D01*
X-1314274Y-962156D01*
X-1313104Y-963196D01*
X-1311739Y-963456D01*
X-1310374Y-962936D01*
X-1309009Y-961376D01*
G01X-1297349Y-961636D02*
X-1296374Y-962676D01*
X-1295009Y-963456D01*
X-1293839D01*
X-1292669Y-962936D01*
X-1291889Y-962156D01*
X-1291499Y-961116D01*
X-1291694Y-959556D01*
X-1292474Y-958776D01*
X-1295984Y-957216D01*
X-1296764Y-955396D01*
X-1296374Y-954096D01*
X-1295594Y-953316D01*
X-1294424Y-953056D01*
X-1293254Y-953316D01*
X-1292084Y-954096D01*
G01X-1275549Y-968656D02*
X-1273599Y-966056D01*
X-1272624Y-963456D01*
Y-953056D01*
X-1273599Y-950456D01*
X-1275549Y-947856D01*
G01X-1237214Y-963456D02*
Y-953056D01*
G01Y-954876D02*
X-1237994Y-953836D01*
X-1239164Y-953316D01*
X-1240529Y-953056D01*
X-1241894Y-953576D01*
X-1243064Y-954616D01*
X-1243844Y-956176D01*
X-1244234Y-958256D01*
X-1243844Y-960336D01*
X-1243064Y-961896D01*
X-1241894Y-962936D01*
X-1240529Y-963456D01*
X-1239164Y-963196D01*
X-1237994Y-962416D01*
X-1237214Y-961376D01*
G01X-1226139Y-963456D02*
Y-953056D01*
G01Y-955656D02*
X-1225359Y-954356D01*
X-1224189Y-953316D01*
X-1222629Y-953056D01*
X-1221264Y-953316D01*
X-1220094Y-954356D01*
X-1219509Y-956176D01*
Y-963456D01*
G01X-1201414Y-947856D02*
Y-963456D01*
G01Y-961116D02*
X-1202194Y-962416D01*
X-1203364Y-963196D01*
X-1204729Y-963456D01*
X-1206289Y-962936D01*
X-1207459Y-961636D01*
X-1208239Y-960076D01*
X-1208434Y-958256D01*
X-1208239Y-956436D01*
X-1207459Y-954876D01*
X-1206289Y-953576D01*
X-1204729Y-953056D01*
X-1203364Y-953316D01*
X-1202389Y-953836D01*
X-1201414Y-954876D01*
G01X-1165614Y-963456D02*
Y-953056D01*
G01Y-954876D02*
X-1166394Y-953836D01*
X-1167564Y-953316D01*
X-1168929Y-953056D01*
X-1170294Y-953576D01*
X-1171464Y-954616D01*
X-1172244Y-956176D01*
X-1172634Y-958256D01*
X-1172244Y-960336D01*
X-1171464Y-961896D01*
X-1170294Y-962936D01*
X-1168929Y-963456D01*
X-1167564Y-963196D01*
X-1166394Y-962416D01*
X-1165614Y-961376D01*
G01X-1154734Y-963456D02*
Y-947856D01*
G01Y-955656D02*
X-1153759Y-954096D01*
X-1152589Y-953316D01*
X-1151419Y-953056D01*
X-1149664Y-953576D01*
X-1148494Y-954616D01*
X-1147714Y-956436D01*
Y-958516D01*
X-1148104Y-960596D01*
X-1148884Y-962156D01*
X-1150249Y-963196D01*
X-1151419Y-963456D01*
X-1152589Y-963196D01*
X-1153759Y-962416D01*
X-1154734Y-961116D01*
G01X-1133324Y-963456D02*
X-1134494Y-963196D01*
X-1135664Y-962156D01*
X-1136444Y-960336D01*
X-1136834Y-958256D01*
X-1136444Y-956176D01*
X-1135664Y-954356D01*
X-1134494Y-953316D01*
X-1133324Y-953056D01*
X-1132154Y-953316D01*
X-1130984Y-954356D01*
X-1130204Y-956176D01*
X-1130009Y-958256D01*
X-1130204Y-960336D01*
X-1130984Y-962156D01*
X-1132154Y-963196D01*
X-1133324Y-963456D01*
G01X-1118934Y-953056D02*
X-1115424Y-963456D01*
X-1111914Y-953056D01*
G01X-1100449Y-956436D02*
X-1094209D01*
X-1094794Y-954616D01*
X-1095769Y-953576D01*
X-1097134Y-953056D01*
X-1098499Y-953316D01*
X-1099669Y-954096D01*
X-1100449Y-955916D01*
X-1100839Y-957476D01*
Y-959036D01*
X-1100449Y-960596D01*
X-1099474Y-962156D01*
X-1098304Y-963196D01*
X-1096939Y-963456D01*
X-1095574Y-962936D01*
X-1094209Y-961376D01*
G01X-1058214Y-963456D02*
Y-953056D01*
G01Y-954876D02*
X-1058994Y-953836D01*
X-1060164Y-953316D01*
X-1061529Y-953056D01*
X-1062894Y-953576D01*
X-1064064Y-954616D01*
X-1064844Y-956176D01*
X-1065234Y-958256D01*
X-1064844Y-960336D01*
X-1064064Y-961896D01*
X-1062894Y-962936D01*
X-1061529Y-963456D01*
X-1060164Y-963196D01*
X-1058994Y-962416D01*
X-1058214Y-961376D01*
G01X-1046554Y-963456D02*
Y-953056D01*
G01Y-955136D02*
X-1045579Y-954096D01*
X-1044604Y-953316D01*
X-1043239Y-953056D01*
X-1042264Y-953316D01*
X-1041094Y-954096D01*
G01X-1028849Y-956436D02*
X-1022609D01*
X-1023194Y-954616D01*
X-1024169Y-953576D01*
X-1025534Y-953056D01*
X-1026899Y-953316D01*
X-1028069Y-954096D01*
X-1028849Y-955916D01*
X-1029239Y-957476D01*
Y-959036D01*
X-1028849Y-960596D01*
X-1027874Y-962156D01*
X-1026704Y-963196D01*
X-1025339Y-963456D01*
X-1023974Y-962936D01*
X-1022609Y-961376D01*
G01X-992854Y-963456D02*
Y-953056D01*
G01Y-955136D02*
X-991879Y-954096D01*
X-990904Y-953316D01*
X-989539Y-953056D01*
X-988564Y-953316D01*
X-987394Y-954096D01*
G01X-975149Y-956436D02*
X-968909D01*
X-969494Y-954616D01*
X-970469Y-953576D01*
X-971834Y-953056D01*
X-973199Y-953316D01*
X-974369Y-954096D01*
X-975149Y-955916D01*
X-975539Y-957476D01*
Y-959036D01*
X-975149Y-960596D01*
X-974174Y-962156D01*
X-973004Y-963196D01*
X-971639Y-963456D01*
X-970274Y-962936D01*
X-968909Y-961376D01*
G01X-950814Y-968656D02*
Y-953056D01*
G01Y-955396D02*
X-951789Y-954096D01*
X-952959Y-953316D01*
X-954324Y-953056D01*
X-955494Y-953316D01*
X-956859Y-954616D01*
X-957639Y-956436D01*
X-957834Y-958256D01*
X-957639Y-960076D01*
X-956859Y-961896D01*
X-955494Y-963196D01*
X-954324Y-963456D01*
X-952959Y-963196D01*
X-951789Y-962416D01*
X-950814Y-961116D01*
G01X-939739Y-953056D02*
Y-960336D01*
X-938959Y-962156D01*
X-937789Y-963196D01*
X-936424Y-963456D01*
X-935059Y-963196D01*
X-933889Y-962156D01*
X-933109Y-960336D01*
G01Y-963456D02*
Y-953056D01*
G01X-918524D02*
Y-963456D01*
G01Y-948896D02*
X-918914Y-948636D01*
Y-948116D01*
X-918524Y-947856D01*
X-918134Y-948116D01*
Y-948636D01*
X-918524Y-948896D01*
G01X-903354Y-963456D02*
Y-953056D01*
G01Y-955136D02*
X-902379Y-954096D01*
X-901404Y-953316D01*
X-900039Y-953056D01*
X-899064Y-953316D01*
X-897894Y-954096D01*
G01X-885649Y-956436D02*
X-879409D01*
X-879994Y-954616D01*
X-880969Y-953576D01*
X-882334Y-953056D01*
X-883699Y-953316D01*
X-884869Y-954096D01*
X-885649Y-955916D01*
X-886039Y-957476D01*
Y-959036D01*
X-885649Y-960596D01*
X-884674Y-962156D01*
X-883504Y-963196D01*
X-882139Y-963456D01*
X-880774Y-962936D01*
X-879409Y-961376D01*
G01X-861314Y-947856D02*
Y-963456D01*
G01Y-961116D02*
X-862094Y-962416D01*
X-863264Y-963196D01*
X-864629Y-963456D01*
X-866189Y-962936D01*
X-867359Y-961636D01*
X-868139Y-960076D01*
X-868334Y-958256D01*
X-868139Y-956436D01*
X-867359Y-954876D01*
X-866189Y-953576D01*
X-864629Y-953056D01*
X-863264Y-953316D01*
X-862289Y-953836D01*
X-861314Y-954876D01*
G01X-829024Y-947856D02*
Y-963456D01*
G01X-831754Y-953056D02*
X-826294D01*
G01X-811124Y-963456D02*
X-812294Y-963196D01*
X-813464Y-962156D01*
X-814244Y-960336D01*
X-814634Y-958256D01*
X-814244Y-956176D01*
X-813464Y-954356D01*
X-812294Y-953316D01*
X-811124Y-953056D01*
X-809954Y-953316D01*
X-808784Y-954356D01*
X-808004Y-956176D01*
X-807809Y-958256D01*
X-808004Y-960336D01*
X-808784Y-962156D01*
X-809954Y-963196D01*
X-811124Y-963456D01*
G01X-778639D02*
Y-947856D01*
G01Y-955396D02*
X-777664Y-954096D01*
X-776689Y-953316D01*
X-775129Y-953056D01*
X-773959Y-953316D01*
X-772594Y-954356D01*
X-772009Y-955916D01*
Y-963456D01*
G01X-753914D02*
Y-953056D01*
G01Y-954876D02*
X-754694Y-953836D01*
X-755864Y-953316D01*
X-757229Y-953056D01*
X-758594Y-953576D01*
X-759764Y-954616D01*
X-760544Y-956176D01*
X-760934Y-958256D01*
X-760544Y-960336D01*
X-759764Y-961896D01*
X-758594Y-962936D01*
X-757229Y-963456D01*
X-755864Y-963196D01*
X-754694Y-962416D01*
X-753914Y-961376D01*
G01X-743034Y-953056D02*
X-739524Y-963456D01*
X-736014Y-953056D01*
G01X-724549Y-956436D02*
X-718309D01*
X-718894Y-954616D01*
X-719869Y-953576D01*
X-721234Y-953056D01*
X-722599Y-953316D01*
X-723769Y-954096D01*
X-724549Y-955916D01*
X-724939Y-957476D01*
Y-959036D01*
X-724549Y-960596D01*
X-723574Y-962156D01*
X-722404Y-963196D01*
X-721039Y-963456D01*
X-719674Y-962936D01*
X-718309Y-961376D01*
G01X-689139Y-963456D02*
Y-953056D01*
G01Y-955656D02*
X-688359Y-954356D01*
X-687189Y-953316D01*
X-685629Y-953056D01*
X-684264Y-953316D01*
X-683094Y-954356D01*
X-682509Y-956176D01*
Y-963456D01*
G01X-667924D02*
X-669094Y-963196D01*
X-670264Y-962156D01*
X-671044Y-960336D01*
X-671434Y-958256D01*
X-671044Y-956176D01*
X-670264Y-954356D01*
X-669094Y-953316D01*
X-667924Y-953056D01*
X-666754Y-953316D01*
X-665584Y-954356D01*
X-664804Y-956176D01*
X-664609Y-958256D01*
X-664804Y-960336D01*
X-665584Y-962156D01*
X-666754Y-963196D01*
X-667924Y-963456D01*
G01X-650024Y-947856D02*
Y-963456D01*
G01X-652754Y-953056D02*
X-647294D01*
G01X-620074Y-963456D02*
Y-953056D01*
G01Y-955916D02*
X-619489Y-954616D01*
X-618514Y-953576D01*
X-617149Y-953056D01*
X-615784Y-953576D01*
X-614809Y-954616D01*
X-614224Y-955916D01*
Y-963456D01*
G01Y-955916D02*
X-613639Y-954616D01*
X-612664Y-953576D01*
X-611299Y-953056D01*
X-609934Y-953576D01*
X-608959Y-954616D01*
X-608374Y-956176D01*
Y-963456D01*
G01X-596324D02*
X-597494Y-963196D01*
X-598664Y-962156D01*
X-599444Y-960336D01*
X-599834Y-958256D01*
X-599444Y-956176D01*
X-598664Y-954356D01*
X-597494Y-953316D01*
X-596324Y-953056D01*
X-595154Y-953316D01*
X-593984Y-954356D01*
X-593204Y-956176D01*
X-593009Y-958256D01*
X-593204Y-960336D01*
X-593984Y-962156D01*
X-595154Y-963196D01*
X-596324Y-963456D01*
G01X-581154D02*
Y-953056D01*
G01Y-955136D02*
X-580179Y-954096D01*
X-579204Y-953316D01*
X-577839Y-953056D01*
X-576864Y-953316D01*
X-575694Y-954096D01*
G01X-563449Y-956436D02*
X-557209D01*
X-557794Y-954616D01*
X-558769Y-953576D01*
X-560134Y-953056D01*
X-561499Y-953316D01*
X-562669Y-954096D01*
X-563449Y-955916D01*
X-563839Y-957476D01*
Y-959036D01*
X-563449Y-960596D01*
X-562474Y-962156D01*
X-561304Y-963196D01*
X-559939Y-963456D01*
X-558574Y-962936D01*
X-557209Y-961376D01*
G01X-524724Y-947856D02*
Y-963456D01*
G01X-527454Y-953056D02*
X-521994D01*
G01X-510139Y-963456D02*
Y-947856D01*
G01Y-955396D02*
X-509164Y-954096D01*
X-508189Y-953316D01*
X-506629Y-953056D01*
X-505459Y-953316D01*
X-504094Y-954356D01*
X-503509Y-955916D01*
Y-963456D01*
G01X-485414D02*
Y-953056D01*
G01Y-954876D02*
X-486194Y-953836D01*
X-487364Y-953316D01*
X-488729Y-953056D01*
X-490094Y-953576D01*
X-491264Y-954616D01*
X-492044Y-956176D01*
X-492434Y-958256D01*
X-492044Y-960336D01*
X-491264Y-961896D01*
X-490094Y-962936D01*
X-488729Y-963456D01*
X-487364Y-963196D01*
X-486194Y-962416D01*
X-485414Y-961376D01*
G01X-474339Y-963456D02*
Y-953056D01*
G01Y-955656D02*
X-473559Y-954356D01*
X-472389Y-953316D01*
X-470829Y-953056D01*
X-469464Y-953316D01*
X-468294Y-954356D01*
X-467709Y-956176D01*
Y-963456D01*
G01X-2139039Y-907636D02*
X-2137674Y-908936D01*
X-2136114Y-909456D01*
X-2134554Y-908936D01*
X-2133189Y-907376D01*
X-2132214Y-905036D01*
X-2131824Y-902696D01*
Y-899836D01*
X-2132214Y-897496D01*
X-2133189Y-895416D01*
X-2134359Y-894376D01*
X-2135724Y-893856D01*
X-2137284Y-894376D01*
X-2138454Y-895416D01*
X-2139234Y-896976D01*
X-2139624Y-899056D01*
X-2139234Y-900876D01*
X-2138259Y-902696D01*
X-2137089Y-903736D01*
X-2135724Y-903996D01*
X-2134164Y-903476D01*
X-2132994Y-902176D01*
X-2131824Y-899836D01*
G01X-2117824Y-909976D02*
X-2118214Y-909716D01*
Y-909196D01*
X-2117824Y-908936D01*
X-2117434Y-909196D01*
Y-909716D01*
X-2117824Y-909976D01*
G01X-2085924Y-909456D02*
Y-893856D01*
X-2081244D01*
X-2079684Y-894636D01*
X-2078514Y-896456D01*
X-2078124Y-898536D01*
X-2078514Y-900616D01*
X-2079489Y-902176D01*
X-2081244Y-902956D01*
X-2085924D01*
G01X-2064124Y-909456D02*
Y-893856D01*
G01X-2049149Y-902436D02*
X-2042909D01*
X-2043494Y-900616D01*
X-2044469Y-899576D01*
X-2045834Y-899056D01*
X-2047199Y-899316D01*
X-2048369Y-900096D01*
X-2049149Y-901916D01*
X-2049539Y-903476D01*
Y-905036D01*
X-2049149Y-906596D01*
X-2048174Y-908156D01*
X-2047004Y-909196D01*
X-2045639Y-909456D01*
X-2044274Y-908936D01*
X-2042909Y-907376D01*
G01X-2024814Y-909456D02*
Y-899056D01*
G01Y-900876D02*
X-2025594Y-899836D01*
X-2026764Y-899316D01*
X-2028129Y-899056D01*
X-2029494Y-899576D01*
X-2030664Y-900616D01*
X-2031444Y-902176D01*
X-2031834Y-904256D01*
X-2031444Y-906336D01*
X-2030664Y-907896D01*
X-2029494Y-908936D01*
X-2028129Y-909456D01*
X-2026764Y-909196D01*
X-2025594Y-908416D01*
X-2024814Y-907376D01*
G01X-2013349Y-907636D02*
X-2012374Y-908676D01*
X-2011009Y-909456D01*
X-2009839D01*
X-2008669Y-908936D01*
X-2007889Y-908156D01*
X-2007499Y-907116D01*
X-2007694Y-905556D01*
X-2008474Y-904776D01*
X-2011984Y-903216D01*
X-2012764Y-901396D01*
X-2012374Y-900096D01*
X-2011594Y-899316D01*
X-2010424Y-899056D01*
X-2009254Y-899316D01*
X-2008084Y-900096D01*
G01X-1995449Y-902436D02*
X-1989209D01*
X-1989794Y-900616D01*
X-1990769Y-899576D01*
X-1992134Y-899056D01*
X-1993499Y-899316D01*
X-1994669Y-900096D01*
X-1995449Y-901916D01*
X-1995839Y-903476D01*
Y-905036D01*
X-1995449Y-906596D01*
X-1994474Y-908156D01*
X-1993304Y-909196D01*
X-1991939Y-909456D01*
X-1990574Y-908936D01*
X-1989209Y-907376D01*
G01X-1960234Y-914656D02*
Y-899056D01*
G01Y-901396D02*
X-1959259Y-900096D01*
X-1958284Y-899316D01*
X-1956724Y-899056D01*
X-1955359Y-899316D01*
X-1953994Y-900616D01*
X-1953409Y-902436D01*
X-1953214Y-904256D01*
X-1953409Y-906076D01*
X-1953994Y-907896D01*
X-1955164Y-908936D01*
X-1956724Y-909456D01*
X-1958089Y-909196D01*
X-1959454Y-908416D01*
X-1960234Y-907376D01*
G01X-1941554Y-909456D02*
Y-899056D01*
G01Y-901136D02*
X-1940579Y-900096D01*
X-1939604Y-899316D01*
X-1938239Y-899056D01*
X-1937264Y-899316D01*
X-1936094Y-900096D01*
G01X-1920924Y-909456D02*
X-1922094Y-909196D01*
X-1923264Y-908156D01*
X-1924044Y-906336D01*
X-1924434Y-904256D01*
X-1924044Y-902176D01*
X-1923264Y-900356D01*
X-1922094Y-899316D01*
X-1920924Y-899056D01*
X-1919754Y-899316D01*
X-1918584Y-900356D01*
X-1917804Y-902176D01*
X-1917609Y-904256D01*
X-1917804Y-906336D01*
X-1918584Y-908156D01*
X-1919754Y-909196D01*
X-1920924Y-909456D01*
G01X-1906534Y-899056D02*
X-1903024Y-909456D01*
X-1899514Y-899056D01*
G01X-1885124D02*
Y-909456D01*
G01Y-894896D02*
X-1885514Y-894636D01*
Y-894116D01*
X-1885124Y-893856D01*
X-1884734Y-894116D01*
Y-894636D01*
X-1885124Y-894896D01*
G01X-1863714Y-893856D02*
Y-909456D01*
G01Y-907116D02*
X-1864494Y-908416D01*
X-1865664Y-909196D01*
X-1867029Y-909456D01*
X-1868589Y-908936D01*
X-1869759Y-907636D01*
X-1870539Y-906076D01*
X-1870734Y-904256D01*
X-1870539Y-902436D01*
X-1869759Y-900876D01*
X-1868589Y-899576D01*
X-1867029Y-899056D01*
X-1865664Y-899316D01*
X-1864689Y-899836D01*
X-1863714Y-900876D01*
G01X-1852249Y-902436D02*
X-1846009D01*
X-1846594Y-900616D01*
X-1847569Y-899576D01*
X-1848934Y-899056D01*
X-1850299Y-899316D01*
X-1851469Y-900096D01*
X-1852249Y-901916D01*
X-1852639Y-903476D01*
Y-905036D01*
X-1852249Y-906596D01*
X-1851274Y-908156D01*
X-1850104Y-909196D01*
X-1848739Y-909456D01*
X-1847374Y-908936D01*
X-1846009Y-907376D01*
G01X-1810014Y-909456D02*
Y-899056D01*
G01Y-900876D02*
X-1810794Y-899836D01*
X-1811964Y-899316D01*
X-1813329Y-899056D01*
X-1814694Y-899576D01*
X-1815864Y-900616D01*
X-1816644Y-902176D01*
X-1817034Y-904256D01*
X-1816644Y-906336D01*
X-1815864Y-907896D01*
X-1814694Y-908936D01*
X-1813329Y-909456D01*
X-1811964Y-909196D01*
X-1810794Y-908416D01*
X-1810014Y-907376D01*
G01X-1792504Y-900356D02*
X-1793869Y-899316D01*
X-1795039Y-899056D01*
X-1796599Y-899576D01*
X-1797769Y-900616D01*
X-1798549Y-902436D01*
X-1798744Y-904256D01*
X-1798549Y-906076D01*
X-1797769Y-907636D01*
X-1796599Y-908936D01*
X-1795039Y-909456D01*
X-1793674Y-908936D01*
X-1792504Y-907896D01*
G01X-1777724Y-893856D02*
Y-909456D01*
G01X-1780454Y-899056D02*
X-1774994D01*
G01X-1763139D02*
Y-906336D01*
X-1762359Y-908156D01*
X-1761189Y-909196D01*
X-1759824Y-909456D01*
X-1758459Y-909196D01*
X-1757289Y-908156D01*
X-1756509Y-906336D01*
G01Y-909456D02*
Y-899056D01*
G01X-1738414Y-909456D02*
Y-899056D01*
G01Y-900876D02*
X-1739194Y-899836D01*
X-1740364Y-899316D01*
X-1741729Y-899056D01*
X-1743094Y-899576D01*
X-1744264Y-900616D01*
X-1745044Y-902176D01*
X-1745434Y-904256D01*
X-1745044Y-906336D01*
X-1744264Y-907896D01*
X-1743094Y-908936D01*
X-1741729Y-909456D01*
X-1740364Y-909196D01*
X-1739194Y-908416D01*
X-1738414Y-907376D01*
G01X-1724024Y-909456D02*
Y-893856D01*
G01X-1690954Y-909456D02*
Y-899056D01*
G01Y-901136D02*
X-1689979Y-900096D01*
X-1689004Y-899316D01*
X-1687639Y-899056D01*
X-1686664Y-899316D01*
X-1685494Y-900096D01*
G01X-1673249Y-902436D02*
X-1667009D01*
X-1667594Y-900616D01*
X-1668569Y-899576D01*
X-1669934Y-899056D01*
X-1671299Y-899316D01*
X-1672469Y-900096D01*
X-1673249Y-901916D01*
X-1673639Y-903476D01*
Y-905036D01*
X-1673249Y-906596D01*
X-1672274Y-908156D01*
X-1671104Y-909196D01*
X-1669739Y-909456D01*
X-1668374Y-908936D01*
X-1667009Y-907376D01*
G01X-1655349Y-907636D02*
X-1654374Y-908676D01*
X-1653009Y-909456D01*
X-1651839D01*
X-1650669Y-908936D01*
X-1649889Y-908156D01*
X-1649499Y-907116D01*
X-1649694Y-905556D01*
X-1650474Y-904776D01*
X-1653984Y-903216D01*
X-1654764Y-901396D01*
X-1654374Y-900096D01*
X-1653594Y-899316D01*
X-1652424Y-899056D01*
X-1651254Y-899316D01*
X-1650084Y-900096D01*
G01X-1634524Y-899056D02*
Y-909456D01*
G01Y-894896D02*
X-1634914Y-894636D01*
Y-894116D01*
X-1634524Y-893856D01*
X-1634134Y-894116D01*
Y-894636D01*
X-1634524Y-894896D01*
G01X-1613114Y-893856D02*
Y-909456D01*
G01Y-907116D02*
X-1613894Y-908416D01*
X-1615064Y-909196D01*
X-1616429Y-909456D01*
X-1617989Y-908936D01*
X-1619159Y-907636D01*
X-1619939Y-906076D01*
X-1620134Y-904256D01*
X-1619939Y-902436D01*
X-1619159Y-900876D01*
X-1617989Y-899576D01*
X-1616429Y-899056D01*
X-1615064Y-899316D01*
X-1614089Y-899836D01*
X-1613114Y-900876D01*
G01X-1602039Y-899056D02*
Y-906336D01*
X-1601259Y-908156D01*
X-1600089Y-909196D01*
X-1598724Y-909456D01*
X-1597359Y-909196D01*
X-1596189Y-908156D01*
X-1595409Y-906336D01*
G01Y-909456D02*
Y-899056D01*
G01X-1577314Y-909456D02*
Y-899056D01*
G01Y-900876D02*
X-1578094Y-899836D01*
X-1579264Y-899316D01*
X-1580629Y-899056D01*
X-1581994Y-899576D01*
X-1583164Y-900616D01*
X-1583944Y-902176D01*
X-1584334Y-904256D01*
X-1583944Y-906336D01*
X-1583164Y-907896D01*
X-1581994Y-908936D01*
X-1580629Y-909456D01*
X-1579264Y-909196D01*
X-1578094Y-908416D01*
X-1577314Y-907376D01*
G01X-1562924Y-909456D02*
Y-893856D01*
G01X-1524004Y-900356D02*
X-1525369Y-899316D01*
X-1526539Y-899056D01*
X-1528099Y-899576D01*
X-1529269Y-900616D01*
X-1530049Y-902436D01*
X-1530244Y-904256D01*
X-1530049Y-906076D01*
X-1529269Y-907636D01*
X-1528099Y-908936D01*
X-1526539Y-909456D01*
X-1525174Y-908936D01*
X-1524004Y-907896D01*
G01X-1509224Y-909456D02*
X-1510394Y-909196D01*
X-1511564Y-908156D01*
X-1512344Y-906336D01*
X-1512734Y-904256D01*
X-1512344Y-902176D01*
X-1511564Y-900356D01*
X-1510394Y-899316D01*
X-1509224Y-899056D01*
X-1508054Y-899316D01*
X-1506884Y-900356D01*
X-1506104Y-902176D01*
X-1505909Y-904256D01*
X-1506104Y-906336D01*
X-1506884Y-908156D01*
X-1508054Y-909196D01*
X-1509224Y-909456D01*
G01X-1494834Y-914656D02*
Y-899056D01*
G01Y-901396D02*
X-1493859Y-900096D01*
X-1492884Y-899316D01*
X-1491324Y-899056D01*
X-1489959Y-899316D01*
X-1488594Y-900616D01*
X-1488009Y-902436D01*
X-1487814Y-904256D01*
X-1488009Y-906076D01*
X-1488594Y-907896D01*
X-1489764Y-908936D01*
X-1491324Y-909456D01*
X-1492689Y-909196D01*
X-1494054Y-908416D01*
X-1494834Y-907376D01*
G01X-1476934Y-914656D02*
Y-899056D01*
G01Y-901396D02*
X-1475959Y-900096D01*
X-1474984Y-899316D01*
X-1473424Y-899056D01*
X-1472059Y-899316D01*
X-1470694Y-900616D01*
X-1470109Y-902436D01*
X-1469914Y-904256D01*
X-1470109Y-906076D01*
X-1470694Y-907896D01*
X-1471864Y-908936D01*
X-1473424Y-909456D01*
X-1474789Y-909196D01*
X-1476154Y-908416D01*
X-1476934Y-907376D01*
G01X-1458449Y-902436D02*
X-1452209D01*
X-1452794Y-900616D01*
X-1453769Y-899576D01*
X-1455134Y-899056D01*
X-1456499Y-899316D01*
X-1457669Y-900096D01*
X-1458449Y-901916D01*
X-1458839Y-903476D01*
Y-905036D01*
X-1458449Y-906596D01*
X-1457474Y-908156D01*
X-1456304Y-909196D01*
X-1454939Y-909456D01*
X-1453574Y-908936D01*
X-1452209Y-907376D01*
G01X-1440354Y-909456D02*
Y-899056D01*
G01Y-901136D02*
X-1439379Y-900096D01*
X-1438404Y-899316D01*
X-1437039Y-899056D01*
X-1436064Y-899316D01*
X-1434894Y-900096D01*
G01X-1404554Y-909456D02*
Y-899056D01*
G01Y-901136D02*
X-1403579Y-900096D01*
X-1402604Y-899316D01*
X-1401239Y-899056D01*
X-1400264Y-899316D01*
X-1399094Y-900096D01*
G01X-1380414Y-909456D02*
Y-899056D01*
G01Y-900876D02*
X-1381194Y-899836D01*
X-1382364Y-899316D01*
X-1383729Y-899056D01*
X-1385094Y-899576D01*
X-1386264Y-900616D01*
X-1387044Y-902176D01*
X-1387434Y-904256D01*
X-1387044Y-906336D01*
X-1386264Y-907896D01*
X-1385094Y-908936D01*
X-1383729Y-909456D01*
X-1382364Y-909196D01*
X-1381194Y-908416D01*
X-1380414Y-907376D01*
G01X-1366024Y-893856D02*
Y-909456D01*
G01X-1368754Y-899056D02*
X-1363294D01*
G01X-1351049Y-902436D02*
X-1344809D01*
X-1345394Y-900616D01*
X-1346369Y-899576D01*
X-1347734Y-899056D01*
X-1349099Y-899316D01*
X-1350269Y-900096D01*
X-1351049Y-901916D01*
X-1351439Y-903476D01*
Y-905036D01*
X-1351049Y-906596D01*
X-1350074Y-908156D01*
X-1348904Y-909196D01*
X-1347539Y-909456D01*
X-1346174Y-908936D01*
X-1344809Y-907376D01*
G01X-1313494Y-909456D02*
Y-896196D01*
X-1313104Y-894896D01*
X-1312324Y-894116D01*
X-1311154Y-893856D01*
X-1309984Y-894376D01*
X-1309399Y-895676D01*
G01X-1311739Y-900096D02*
X-1315639D01*
G01X-1294424Y-909456D02*
X-1295594Y-909196D01*
X-1296764Y-908156D01*
X-1297544Y-906336D01*
X-1297934Y-904256D01*
X-1297544Y-902176D01*
X-1296764Y-900356D01*
X-1295594Y-899316D01*
X-1294424Y-899056D01*
X-1293254Y-899316D01*
X-1292084Y-900356D01*
X-1291304Y-902176D01*
X-1291109Y-904256D01*
X-1291304Y-906336D01*
X-1292084Y-908156D01*
X-1293254Y-909196D01*
X-1294424Y-909456D01*
G01X-1279254D02*
Y-899056D01*
G01Y-901136D02*
X-1278279Y-900096D01*
X-1277304Y-899316D01*
X-1275939Y-899056D01*
X-1274964Y-899316D01*
X-1273794Y-900096D01*
G01X-1243649Y-902436D02*
X-1237409D01*
X-1237994Y-900616D01*
X-1238969Y-899576D01*
X-1240334Y-899056D01*
X-1241699Y-899316D01*
X-1242869Y-900096D01*
X-1243649Y-901916D01*
X-1244039Y-903476D01*
Y-905036D01*
X-1243649Y-906596D01*
X-1242674Y-908156D01*
X-1241504Y-909196D01*
X-1240139Y-909456D01*
X-1238774Y-908936D01*
X-1237409Y-907376D01*
G01X-1219314Y-909456D02*
Y-899056D01*
G01Y-900876D02*
X-1220094Y-899836D01*
X-1221264Y-899316D01*
X-1222629Y-899056D01*
X-1223994Y-899576D01*
X-1225164Y-900616D01*
X-1225944Y-902176D01*
X-1226334Y-904256D01*
X-1225944Y-906336D01*
X-1225164Y-907896D01*
X-1223994Y-908936D01*
X-1222629Y-909456D01*
X-1221264Y-909196D01*
X-1220094Y-908416D01*
X-1219314Y-907376D01*
G01X-1201804Y-900356D02*
X-1203169Y-899316D01*
X-1204339Y-899056D01*
X-1205899Y-899576D01*
X-1207069Y-900616D01*
X-1207849Y-902436D01*
X-1208044Y-904256D01*
X-1207849Y-906076D01*
X-1207069Y-907636D01*
X-1205899Y-908936D01*
X-1204339Y-909456D01*
X-1202974Y-908936D01*
X-1201804Y-907896D01*
G01X-1190339Y-909456D02*
Y-893856D01*
G01Y-901396D02*
X-1189364Y-900096D01*
X-1188389Y-899316D01*
X-1186829Y-899056D01*
X-1185659Y-899316D01*
X-1184294Y-900356D01*
X-1183709Y-901916D01*
Y-909456D01*
G01X-1151224D02*
Y-893856D01*
G01X-1129814Y-909456D02*
Y-899056D01*
G01Y-900876D02*
X-1130594Y-899836D01*
X-1131764Y-899316D01*
X-1133129Y-899056D01*
X-1134494Y-899576D01*
X-1135664Y-900616D01*
X-1136444Y-902176D01*
X-1136834Y-904256D01*
X-1136444Y-906336D01*
X-1135664Y-907896D01*
X-1134494Y-908936D01*
X-1133129Y-909456D01*
X-1131764Y-909196D01*
X-1130594Y-908416D01*
X-1129814Y-907376D01*
G01X-1119519Y-914136D02*
X-1118349Y-914656D01*
X-1116789Y-914136D01*
X-1115814Y-913096D01*
X-1115034Y-911796D01*
X-1113864Y-907636D01*
X-1111329Y-899056D01*
G01X-1117569D02*
X-1113864Y-907636D01*
G01X-1100449Y-902436D02*
X-1094209D01*
X-1094794Y-900616D01*
X-1095769Y-899576D01*
X-1097134Y-899056D01*
X-1098499Y-899316D01*
X-1099669Y-900096D01*
X-1100449Y-901916D01*
X-1100839Y-903476D01*
Y-905036D01*
X-1100449Y-906596D01*
X-1099474Y-908156D01*
X-1098304Y-909196D01*
X-1096939Y-909456D01*
X-1095574Y-908936D01*
X-1094209Y-907376D01*
G01X-1082354Y-909456D02*
Y-899056D01*
G01Y-901136D02*
X-1081379Y-900096D01*
X-1080404Y-899316D01*
X-1079039Y-899056D01*
X-1078064Y-899316D01*
X-1076894Y-900096D01*
G01X-1043824Y-899056D02*
Y-909456D01*
G01Y-894896D02*
X-1044214Y-894636D01*
Y-894116D01*
X-1043824Y-893856D01*
X-1043434Y-894116D01*
Y-894636D01*
X-1043824Y-894896D01*
G01X-1029239Y-909456D02*
Y-899056D01*
G01Y-901656D02*
X-1028459Y-900356D01*
X-1027289Y-899316D01*
X-1025729Y-899056D01*
X-1024364Y-899316D01*
X-1023194Y-900356D01*
X-1022609Y-902176D01*
Y-909456D01*
G01X-994414D02*
Y-893856D01*
X-990514D01*
X-988954Y-894636D01*
X-987784Y-895676D01*
X-986809Y-897236D01*
X-986029Y-899056D01*
X-985834Y-901656D01*
X-986029Y-904256D01*
X-986809Y-906076D01*
X-987784Y-907636D01*
X-988954Y-908676D01*
X-990514Y-909456D01*
X-994414D01*
G01X-975929D02*
Y-893856D01*
X-968519D01*
G01X-971249Y-901396D02*
X-975929D01*
G01X-959394Y-909456D02*
Y-893856D01*
X-954324Y-906856D01*
X-949254Y-893856D01*
Y-909456D01*
G01X-921254D02*
Y-899056D01*
G01Y-901136D02*
X-920279Y-900096D01*
X-919304Y-899316D01*
X-917939Y-899056D01*
X-916964Y-899316D01*
X-915794Y-900096D01*
G01X-903549Y-902436D02*
X-897309D01*
X-897894Y-900616D01*
X-898869Y-899576D01*
X-900234Y-899056D01*
X-901599Y-899316D01*
X-902769Y-900096D01*
X-903549Y-901916D01*
X-903939Y-903476D01*
Y-905036D01*
X-903549Y-906596D01*
X-902574Y-908156D01*
X-901404Y-909196D01*
X-900039Y-909456D01*
X-898674Y-908936D01*
X-897309Y-907376D01*
G01X-886234Y-914656D02*
Y-899056D01*
G01Y-901396D02*
X-885259Y-900096D01*
X-884284Y-899316D01*
X-882724Y-899056D01*
X-881359Y-899316D01*
X-879994Y-900616D01*
X-879409Y-902436D01*
X-879214Y-904256D01*
X-879409Y-906076D01*
X-879994Y-907896D01*
X-881164Y-908936D01*
X-882724Y-909456D01*
X-884089Y-909196D01*
X-885454Y-908416D01*
X-886234Y-907376D01*
G01X-864824Y-909456D02*
X-865994Y-909196D01*
X-867164Y-908156D01*
X-867944Y-906336D01*
X-868334Y-904256D01*
X-867944Y-902176D01*
X-867164Y-900356D01*
X-865994Y-899316D01*
X-864824Y-899056D01*
X-863654Y-899316D01*
X-862484Y-900356D01*
X-861704Y-902176D01*
X-861509Y-904256D01*
X-861704Y-906336D01*
X-862484Y-908156D01*
X-863654Y-909196D01*
X-864824Y-909456D01*
G01X-849654D02*
Y-899056D01*
G01Y-901136D02*
X-848679Y-900096D01*
X-847704Y-899316D01*
X-846339Y-899056D01*
X-845364Y-899316D01*
X-844194Y-900096D01*
G01X-829024Y-893856D02*
Y-909456D01*
G01X-831754Y-899056D02*
X-826294D01*
G01X-811124Y-909976D02*
X-811514Y-909716D01*
Y-909196D01*
X-811124Y-908936D01*
X-810734Y-909196D01*
Y-909716D01*
X-811124Y-909976D01*
G01X-2135724Y-787456D02*
X-2134359Y-787196D01*
X-2132799Y-786416D01*
X-2131824Y-785116D01*
X-2131434Y-783296D01*
X-2131824Y-781476D01*
X-2132994Y-779916D01*
X-2134749Y-779136D01*
X-2136699D01*
X-2137869Y-778616D01*
X-2138844Y-777316D01*
X-2139234Y-775496D01*
X-2138649Y-773676D01*
X-2137284Y-772376D01*
X-2135724Y-771856D01*
X-2134164Y-772376D01*
X-2132799Y-773676D01*
X-2132214Y-775496D01*
X-2132604Y-777316D01*
X-2133579Y-778616D01*
X-2134749Y-779136D01*
X-2136699D01*
X-2138454Y-779916D01*
X-2139624Y-781476D01*
X-2140014Y-783296D01*
X-2139624Y-785116D01*
X-2138649Y-786416D01*
X-2137089Y-787196D01*
X-2135724Y-787456D01*
G01X-2117824Y-787976D02*
X-2118214Y-787716D01*
Y-787196D01*
X-2117824Y-786936D01*
X-2117434Y-787196D01*
Y-787716D01*
X-2117824Y-787976D01*
G01X-2086899Y-787456D02*
X-2082024Y-771856D01*
X-2077149Y-787456D01*
G01X-2078904Y-781996D02*
X-2085144D01*
G01X-2064124Y-787456D02*
Y-771856D01*
G01X-2046224Y-787456D02*
Y-771856D01*
G01X-2010424D02*
Y-787456D01*
G01X-2013154Y-777056D02*
X-2007694D01*
G01X-1995839Y-787456D02*
Y-771856D01*
G01Y-779396D02*
X-1994864Y-778096D01*
X-1993889Y-777316D01*
X-1992329Y-777056D01*
X-1991159Y-777316D01*
X-1989794Y-778356D01*
X-1989209Y-779916D01*
Y-787456D01*
G01X-1977549Y-780436D02*
X-1971309D01*
X-1971894Y-778616D01*
X-1972869Y-777576D01*
X-1974234Y-777056D01*
X-1975599Y-777316D01*
X-1976769Y-778096D01*
X-1977549Y-779916D01*
X-1977939Y-781476D01*
Y-783036D01*
X-1977549Y-784596D01*
X-1976574Y-786156D01*
X-1975404Y-787196D01*
X-1974039Y-787456D01*
X-1972674Y-786936D01*
X-1971309Y-785376D01*
G01X-1935314Y-771856D02*
Y-787456D01*
G01Y-785116D02*
X-1936094Y-786416D01*
X-1937264Y-787196D01*
X-1938629Y-787456D01*
X-1940189Y-786936D01*
X-1941359Y-785636D01*
X-1942139Y-784076D01*
X-1942334Y-782256D01*
X-1942139Y-780436D01*
X-1941359Y-778876D01*
X-1940189Y-777576D01*
X-1938629Y-777056D01*
X-1937264Y-777316D01*
X-1936289Y-777836D01*
X-1935314Y-778876D01*
G01X-1920924Y-777056D02*
Y-787456D01*
G01Y-772896D02*
X-1921314Y-772636D01*
Y-772116D01*
X-1920924Y-771856D01*
X-1920534Y-772116D01*
Y-772636D01*
X-1920924Y-772896D01*
G01X-1908874Y-787456D02*
Y-777056D01*
G01Y-779916D02*
X-1908289Y-778616D01*
X-1907314Y-777576D01*
X-1905949Y-777056D01*
X-1904584Y-777576D01*
X-1903609Y-778616D01*
X-1903024Y-779916D01*
Y-787456D01*
G01Y-779916D02*
X-1902439Y-778616D01*
X-1901464Y-777576D01*
X-1900099Y-777056D01*
X-1898734Y-777576D01*
X-1897759Y-778616D01*
X-1897174Y-780176D01*
Y-787456D01*
G01X-1888049Y-780436D02*
X-1881809D01*
X-1882394Y-778616D01*
X-1883369Y-777576D01*
X-1884734Y-777056D01*
X-1886099Y-777316D01*
X-1887269Y-778096D01*
X-1888049Y-779916D01*
X-1888439Y-781476D01*
Y-783036D01*
X-1888049Y-784596D01*
X-1887074Y-786156D01*
X-1885904Y-787196D01*
X-1884539Y-787456D01*
X-1883174Y-786936D01*
X-1881809Y-785376D01*
G01X-1870539Y-787456D02*
Y-777056D01*
G01Y-779656D02*
X-1869759Y-778356D01*
X-1868589Y-777316D01*
X-1867029Y-777056D01*
X-1865664Y-777316D01*
X-1864494Y-778356D01*
X-1863909Y-780176D01*
Y-787456D01*
G01X-1852249Y-785636D02*
X-1851274Y-786676D01*
X-1849909Y-787456D01*
X-1848739D01*
X-1847569Y-786936D01*
X-1846789Y-786156D01*
X-1846399Y-785116D01*
X-1846594Y-783556D01*
X-1847374Y-782776D01*
X-1850884Y-781216D01*
X-1851664Y-779396D01*
X-1851274Y-778096D01*
X-1850494Y-777316D01*
X-1849324Y-777056D01*
X-1848154Y-777316D01*
X-1846984Y-778096D01*
G01X-1831424Y-777056D02*
Y-787456D01*
G01Y-772896D02*
X-1831814Y-772636D01*
Y-772116D01*
X-1831424Y-771856D01*
X-1831034Y-772116D01*
Y-772636D01*
X-1831424Y-772896D01*
G01X-1813524Y-787456D02*
X-1814694Y-787196D01*
X-1815864Y-786156D01*
X-1816644Y-784336D01*
X-1817034Y-782256D01*
X-1816644Y-780176D01*
X-1815864Y-778356D01*
X-1814694Y-777316D01*
X-1813524Y-777056D01*
X-1812354Y-777316D01*
X-1811184Y-778356D01*
X-1810404Y-780176D01*
X-1810209Y-782256D01*
X-1810404Y-784336D01*
X-1811184Y-786156D01*
X-1812354Y-787196D01*
X-1813524Y-787456D01*
G01X-1798939D02*
Y-777056D01*
G01Y-779656D02*
X-1798159Y-778356D01*
X-1796989Y-777316D01*
X-1795429Y-777056D01*
X-1794064Y-777316D01*
X-1792894Y-778356D01*
X-1792309Y-780176D01*
Y-787456D01*
G01X-1780649Y-785636D02*
X-1779674Y-786676D01*
X-1778309Y-787456D01*
X-1777139D01*
X-1775969Y-786936D01*
X-1775189Y-786156D01*
X-1774799Y-785116D01*
X-1774994Y-783556D01*
X-1775774Y-782776D01*
X-1779284Y-781216D01*
X-1780064Y-779396D01*
X-1779674Y-778096D01*
X-1778894Y-777316D01*
X-1777724Y-777056D01*
X-1776554Y-777316D01*
X-1775384Y-778096D01*
G01X-1741924Y-777056D02*
Y-787456D01*
G01Y-772896D02*
X-1742314Y-772636D01*
Y-772116D01*
X-1741924Y-771856D01*
X-1741534Y-772116D01*
Y-772636D01*
X-1741924Y-772896D01*
G01X-1727339Y-787456D02*
Y-777056D01*
G01Y-779656D02*
X-1726559Y-778356D01*
X-1725389Y-777316D01*
X-1723829Y-777056D01*
X-1722464Y-777316D01*
X-1721294Y-778356D01*
X-1720709Y-780176D01*
Y-787456D01*
G01X-1688224Y-771856D02*
Y-787456D01*
G01X-1690954Y-777056D02*
X-1685494D01*
G01X-1673639Y-787456D02*
Y-771856D01*
G01Y-779396D02*
X-1672664Y-778096D01*
X-1671689Y-777316D01*
X-1670129Y-777056D01*
X-1668959Y-777316D01*
X-1667594Y-778356D01*
X-1667009Y-779916D01*
Y-787456D01*
G01X-1655349Y-780436D02*
X-1649109D01*
X-1649694Y-778616D01*
X-1650669Y-777576D01*
X-1652034Y-777056D01*
X-1653399Y-777316D01*
X-1654569Y-778096D01*
X-1655349Y-779916D01*
X-1655739Y-781476D01*
Y-783036D01*
X-1655349Y-784596D01*
X-1654374Y-786156D01*
X-1653204Y-787196D01*
X-1651839Y-787456D01*
X-1650474Y-786936D01*
X-1649109Y-785376D01*
G01X-1613114Y-771856D02*
Y-787456D01*
G01Y-785116D02*
X-1613894Y-786416D01*
X-1615064Y-787196D01*
X-1616429Y-787456D01*
X-1617989Y-786936D01*
X-1619159Y-785636D01*
X-1619939Y-784076D01*
X-1620134Y-782256D01*
X-1619939Y-780436D01*
X-1619159Y-778876D01*
X-1617989Y-777576D01*
X-1616429Y-777056D01*
X-1615064Y-777316D01*
X-1614089Y-777836D01*
X-1613114Y-778876D01*
G01X-1601454Y-787456D02*
Y-777056D01*
G01Y-779136D02*
X-1600479Y-778096D01*
X-1599504Y-777316D01*
X-1598139Y-777056D01*
X-1597164Y-777316D01*
X-1595994Y-778096D01*
G01X-1577314Y-787456D02*
Y-777056D01*
G01Y-778876D02*
X-1578094Y-777836D01*
X-1579264Y-777316D01*
X-1580629Y-777056D01*
X-1581994Y-777576D01*
X-1583164Y-778616D01*
X-1583944Y-780176D01*
X-1584334Y-782256D01*
X-1583944Y-784336D01*
X-1583164Y-785896D01*
X-1581994Y-786936D01*
X-1580629Y-787456D01*
X-1579264Y-787196D01*
X-1578094Y-786416D01*
X-1577314Y-785376D01*
G01X-1567799Y-777056D02*
X-1565459Y-787456D01*
X-1562924Y-777056D01*
X-1560389Y-787456D01*
X-1558049Y-777056D01*
G01X-1545024D02*
Y-787456D01*
G01Y-772896D02*
X-1545414Y-772636D01*
Y-772116D01*
X-1545024Y-771856D01*
X-1544634Y-772116D01*
Y-772636D01*
X-1545024Y-772896D01*
G01X-1530439Y-787456D02*
Y-777056D01*
G01Y-779656D02*
X-1529659Y-778356D01*
X-1528489Y-777316D01*
X-1526929Y-777056D01*
X-1525564Y-777316D01*
X-1524394Y-778356D01*
X-1523809Y-780176D01*
Y-787456D01*
G01X-1511954Y-791356D02*
X-1510589Y-792396D01*
X-1509029Y-792656D01*
X-1507664Y-792396D01*
X-1506494Y-791096D01*
X-1505714Y-789276D01*
Y-777056D01*
G01Y-779136D02*
X-1506494Y-778096D01*
X-1507664Y-777316D01*
X-1509029Y-777056D01*
X-1510589Y-777576D01*
X-1511564Y-778616D01*
X-1512344Y-780436D01*
X-1512734Y-782256D01*
X-1512539Y-783816D01*
X-1511759Y-785636D01*
X-1510589Y-786936D01*
X-1509029Y-787456D01*
X-1507859Y-787196D01*
X-1506494Y-786156D01*
X-1505714Y-785116D01*
G01X-1478299Y-777056D02*
X-1475959Y-787456D01*
X-1473424Y-777056D01*
X-1470889Y-787456D01*
X-1468549Y-777056D01*
G01X-1455524D02*
Y-787456D01*
G01Y-772896D02*
X-1455914Y-772636D01*
Y-772116D01*
X-1455524Y-771856D01*
X-1455134Y-772116D01*
Y-772636D01*
X-1455524Y-772896D01*
G01X-1437624Y-787456D02*
Y-771856D01*
G01X-1419724Y-787456D02*
Y-771856D01*
G01X-1386849Y-785636D02*
X-1385874Y-786676D01*
X-1384509Y-787456D01*
X-1383339D01*
X-1382169Y-786936D01*
X-1381389Y-786156D01*
X-1380999Y-785116D01*
X-1381194Y-783556D01*
X-1381974Y-782776D01*
X-1385484Y-781216D01*
X-1386264Y-779396D01*
X-1385874Y-778096D01*
X-1385094Y-777316D01*
X-1383924Y-777056D01*
X-1382754Y-777316D01*
X-1381584Y-778096D01*
G01X-1366024Y-771856D02*
Y-787456D01*
G01X-1368754Y-777056D02*
X-1363294D01*
G01X-1344614Y-787456D02*
Y-777056D01*
G01Y-778876D02*
X-1345394Y-777836D01*
X-1346564Y-777316D01*
X-1347929Y-777056D01*
X-1349294Y-777576D01*
X-1350464Y-778616D01*
X-1351244Y-780176D01*
X-1351634Y-782256D01*
X-1351244Y-784336D01*
X-1350464Y-785896D01*
X-1349294Y-786936D01*
X-1347929Y-787456D01*
X-1346564Y-787196D01*
X-1345394Y-786416D01*
X-1344614Y-785376D01*
G01X-1330224Y-771856D02*
Y-787456D01*
G01X-1332954Y-777056D02*
X-1327494D01*
G01X-1312324D02*
Y-787456D01*
G01Y-772896D02*
X-1312714Y-772636D01*
Y-772116D01*
X-1312324Y-771856D01*
X-1311934Y-772116D01*
Y-772636D01*
X-1312324Y-772896D01*
G01X-1297349Y-785636D02*
X-1296374Y-786676D01*
X-1295009Y-787456D01*
X-1293839D01*
X-1292669Y-786936D01*
X-1291889Y-786156D01*
X-1291499Y-785116D01*
X-1291694Y-783556D01*
X-1292474Y-782776D01*
X-1295984Y-781216D01*
X-1296764Y-779396D01*
X-1296374Y-778096D01*
X-1295594Y-777316D01*
X-1294424Y-777056D01*
X-1293254Y-777316D01*
X-1292084Y-778096D01*
G01X-1276524Y-771856D02*
Y-787456D01*
G01X-1279254Y-777056D02*
X-1273794D01*
G01X-1258624D02*
Y-787456D01*
G01Y-772896D02*
X-1259014Y-772636D01*
Y-772116D01*
X-1258624Y-771856D01*
X-1258234Y-772116D01*
Y-772636D01*
X-1258624Y-772896D01*
G01X-1237604Y-778356D02*
X-1238969Y-777316D01*
X-1240139Y-777056D01*
X-1241699Y-777576D01*
X-1242869Y-778616D01*
X-1243649Y-780436D01*
X-1243844Y-782256D01*
X-1243649Y-784076D01*
X-1242869Y-785636D01*
X-1241699Y-786936D01*
X-1240139Y-787456D01*
X-1238774Y-786936D01*
X-1237604Y-785896D01*
G01X-1219314Y-787456D02*
Y-777056D01*
G01Y-778876D02*
X-1220094Y-777836D01*
X-1221264Y-777316D01*
X-1222629Y-777056D01*
X-1223994Y-777576D01*
X-1225164Y-778616D01*
X-1225944Y-780176D01*
X-1226334Y-782256D01*
X-1225944Y-784336D01*
X-1225164Y-785896D01*
X-1223994Y-786936D01*
X-1222629Y-787456D01*
X-1221264Y-787196D01*
X-1220094Y-786416D01*
X-1219314Y-785376D01*
G01X-1204924Y-787456D02*
Y-771856D01*
G01X-1187024Y-787456D02*
Y-771856D01*
G01X-1173219Y-792136D02*
X-1172049Y-792656D01*
X-1170489Y-792136D01*
X-1169514Y-791096D01*
X-1168734Y-789796D01*
X-1167564Y-785636D01*
X-1165029Y-777056D01*
G01X-1171269D02*
X-1167564Y-785636D01*
G01X-1139174Y-787456D02*
Y-777056D01*
G01Y-779916D02*
X-1138589Y-778616D01*
X-1137614Y-777576D01*
X-1136249Y-777056D01*
X-1134884Y-777576D01*
X-1133909Y-778616D01*
X-1133324Y-779916D01*
Y-787456D01*
G01Y-779916D02*
X-1132739Y-778616D01*
X-1131764Y-777576D01*
X-1130399Y-777056D01*
X-1129034Y-777576D01*
X-1128059Y-778616D01*
X-1127474Y-780176D01*
Y-787456D01*
G01X-1115424D02*
X-1116594Y-787196D01*
X-1117764Y-786156D01*
X-1118544Y-784336D01*
X-1118934Y-782256D01*
X-1118544Y-780176D01*
X-1117764Y-778356D01*
X-1116594Y-777316D01*
X-1115424Y-777056D01*
X-1114254Y-777316D01*
X-1113084Y-778356D01*
X-1112304Y-780176D01*
X-1112109Y-782256D01*
X-1112304Y-784336D01*
X-1113084Y-786156D01*
X-1114254Y-787196D01*
X-1115424Y-787456D01*
G01X-1100839D02*
Y-777056D01*
G01Y-779656D02*
X-1100059Y-778356D01*
X-1098889Y-777316D01*
X-1097329Y-777056D01*
X-1095964Y-777316D01*
X-1094794Y-778356D01*
X-1094209Y-780176D01*
Y-787456D01*
G01X-1079624Y-777056D02*
Y-787456D01*
G01Y-772896D02*
X-1080014Y-772636D01*
Y-772116D01*
X-1079624Y-771856D01*
X-1079234Y-772116D01*
Y-772636D01*
X-1079624Y-772896D01*
G01X-1061724Y-771856D02*
Y-787456D01*
G01X-1064454Y-777056D02*
X-1058994D01*
G01X-1043824Y-787456D02*
X-1044994Y-787196D01*
X-1046164Y-786156D01*
X-1046944Y-784336D01*
X-1047334Y-782256D01*
X-1046944Y-780176D01*
X-1046164Y-778356D01*
X-1044994Y-777316D01*
X-1043824Y-777056D01*
X-1042654Y-777316D01*
X-1041484Y-778356D01*
X-1040704Y-780176D01*
X-1040509Y-782256D01*
X-1040704Y-784336D01*
X-1041484Y-786156D01*
X-1042654Y-787196D01*
X-1043824Y-787456D01*
G01X-1028654D02*
Y-777056D01*
G01Y-779136D02*
X-1027679Y-778096D01*
X-1026704Y-777316D01*
X-1025339Y-777056D01*
X-1024364Y-777316D01*
X-1023194Y-778096D01*
G01X-990124Y-771856D02*
Y-787456D01*
G01X-992854Y-777056D02*
X-987394D01*
G01X-975539Y-787456D02*
Y-771856D01*
G01Y-779396D02*
X-974564Y-778096D01*
X-973589Y-777316D01*
X-972029Y-777056D01*
X-970859Y-777316D01*
X-969494Y-778356D01*
X-968909Y-779916D01*
Y-787456D01*
G01X-957249Y-780436D02*
X-951009D01*
X-951594Y-778616D01*
X-952569Y-777576D01*
X-953934Y-777056D01*
X-955299Y-777316D01*
X-956469Y-778096D01*
X-957249Y-779916D01*
X-957639Y-781476D01*
Y-783036D01*
X-957249Y-784596D01*
X-956274Y-786156D01*
X-955104Y-787196D01*
X-953739Y-787456D01*
X-952374Y-786936D01*
X-951009Y-785376D01*
G01X-918524Y-787456D02*
X-919694Y-787196D01*
X-920864Y-786156D01*
X-921644Y-784336D01*
X-922034Y-782256D01*
X-921644Y-780176D01*
X-920864Y-778356D01*
X-919694Y-777316D01*
X-918524Y-777056D01*
X-917354Y-777316D01*
X-916184Y-778356D01*
X-915404Y-780176D01*
X-915209Y-782256D01*
X-915404Y-784336D01*
X-916184Y-786156D01*
X-917354Y-787196D01*
X-918524Y-787456D01*
G01X-903939D02*
Y-777056D01*
G01Y-779656D02*
X-903159Y-778356D01*
X-901989Y-777316D01*
X-900429Y-777056D01*
X-899064Y-777316D01*
X-897894Y-778356D01*
X-897309Y-780176D01*
Y-787456D01*
G01X-885454Y-791356D02*
X-884089Y-792396D01*
X-882529Y-792656D01*
X-881164Y-792396D01*
X-879994Y-791096D01*
X-879214Y-789276D01*
Y-777056D01*
G01Y-779136D02*
X-879994Y-778096D01*
X-881164Y-777316D01*
X-882529Y-777056D01*
X-884089Y-777576D01*
X-885064Y-778616D01*
X-885844Y-780436D01*
X-886234Y-782256D01*
X-886039Y-783816D01*
X-885259Y-785636D01*
X-884089Y-786936D01*
X-882529Y-787456D01*
X-881359Y-787196D01*
X-879994Y-786156D01*
X-879214Y-785116D01*
G01X-864824Y-787456D02*
X-865994Y-787196D01*
X-867164Y-786156D01*
X-867944Y-784336D01*
X-868334Y-782256D01*
X-867944Y-780176D01*
X-867164Y-778356D01*
X-865994Y-777316D01*
X-864824Y-777056D01*
X-863654Y-777316D01*
X-862484Y-778356D01*
X-861704Y-780176D01*
X-861509Y-782256D01*
X-861704Y-784336D01*
X-862484Y-786156D01*
X-863654Y-787196D01*
X-864824Y-787456D01*
G01X-846924Y-777056D02*
Y-787456D01*
G01Y-772896D02*
X-847314Y-772636D01*
Y-772116D01*
X-846924Y-771856D01*
X-846534Y-772116D01*
Y-772636D01*
X-846924Y-772896D01*
G01X-832339Y-787456D02*
Y-777056D01*
G01Y-779656D02*
X-831559Y-778356D01*
X-830389Y-777316D01*
X-828829Y-777056D01*
X-827464Y-777316D01*
X-826294Y-778356D01*
X-825709Y-780176D01*
Y-787456D01*
G01X-813854Y-791356D02*
X-812489Y-792396D01*
X-810929Y-792656D01*
X-809564Y-792396D01*
X-808394Y-791096D01*
X-807614Y-789276D01*
Y-777056D01*
G01Y-779136D02*
X-808394Y-778096D01*
X-809564Y-777316D01*
X-810929Y-777056D01*
X-812489Y-777576D01*
X-813464Y-778616D01*
X-814244Y-780436D01*
X-814634Y-782256D01*
X-814439Y-783816D01*
X-813659Y-785636D01*
X-812489Y-786936D01*
X-810929Y-787456D01*
X-809759Y-787196D01*
X-808394Y-786156D01*
X-807614Y-785116D01*
G01X-778834Y-792656D02*
Y-777056D01*
G01Y-779396D02*
X-777859Y-778096D01*
X-776884Y-777316D01*
X-775324Y-777056D01*
X-773959Y-777316D01*
X-772594Y-778616D01*
X-772009Y-780436D01*
X-771814Y-782256D01*
X-772009Y-784076D01*
X-772594Y-785896D01*
X-773764Y-786936D01*
X-775324Y-787456D01*
X-776689Y-787196D01*
X-778054Y-786416D01*
X-778834Y-785376D01*
G01X-760154Y-787456D02*
Y-777056D01*
G01Y-779136D02*
X-759179Y-778096D01*
X-758204Y-777316D01*
X-756839Y-777056D01*
X-755864Y-777316D01*
X-754694Y-778096D01*
G01X-739524Y-787456D02*
X-740694Y-787196D01*
X-741864Y-786156D01*
X-742644Y-784336D01*
X-743034Y-782256D01*
X-742644Y-780176D01*
X-741864Y-778356D01*
X-740694Y-777316D01*
X-739524Y-777056D01*
X-738354Y-777316D01*
X-737184Y-778356D01*
X-736404Y-780176D01*
X-736209Y-782256D01*
X-736404Y-784336D01*
X-737184Y-786156D01*
X-738354Y-787196D01*
X-739524Y-787456D01*
G01X-718504Y-778356D02*
X-719869Y-777316D01*
X-721039Y-777056D01*
X-722599Y-777576D01*
X-723769Y-778616D01*
X-724549Y-780436D01*
X-724744Y-782256D01*
X-724549Y-784076D01*
X-723769Y-785636D01*
X-722599Y-786936D01*
X-721039Y-787456D01*
X-719674Y-786936D01*
X-718504Y-785896D01*
G01X-706649Y-780436D02*
X-700409D01*
X-700994Y-778616D01*
X-701969Y-777576D01*
X-703334Y-777056D01*
X-704699Y-777316D01*
X-705869Y-778096D01*
X-706649Y-779916D01*
X-707039Y-781476D01*
Y-783036D01*
X-706649Y-784596D01*
X-705674Y-786156D01*
X-704504Y-787196D01*
X-703139Y-787456D01*
X-701774Y-786936D01*
X-700409Y-785376D01*
G01X-688749Y-785636D02*
X-687774Y-786676D01*
X-686409Y-787456D01*
X-685239D01*
X-684069Y-786936D01*
X-683289Y-786156D01*
X-682899Y-785116D01*
X-683094Y-783556D01*
X-683874Y-782776D01*
X-687384Y-781216D01*
X-688164Y-779396D01*
X-687774Y-778096D01*
X-686994Y-777316D01*
X-685824Y-777056D01*
X-684654Y-777316D01*
X-683484Y-778096D01*
G01X-670849Y-785636D02*
X-669874Y-786676D01*
X-668509Y-787456D01*
X-667339D01*
X-666169Y-786936D01*
X-665389Y-786156D01*
X-664999Y-785116D01*
X-665194Y-783556D01*
X-665974Y-782776D01*
X-669484Y-781216D01*
X-670264Y-779396D01*
X-669874Y-778096D01*
X-669094Y-777316D01*
X-667924Y-777056D01*
X-666754Y-777316D01*
X-665584Y-778096D01*
G01X-628614Y-792656D02*
Y-777056D01*
G01Y-779396D02*
X-629589Y-778096D01*
X-630759Y-777316D01*
X-632124Y-777056D01*
X-633294Y-777316D01*
X-634659Y-778616D01*
X-635439Y-780436D01*
X-635634Y-782256D01*
X-635439Y-784076D01*
X-634659Y-785896D01*
X-633294Y-787196D01*
X-632124Y-787456D01*
X-630759Y-787196D01*
X-629589Y-786416D01*
X-628614Y-785116D01*
G01X-617539Y-777056D02*
Y-784336D01*
X-616759Y-786156D01*
X-615589Y-787196D01*
X-614224Y-787456D01*
X-612859Y-787196D01*
X-611689Y-786156D01*
X-610909Y-784336D01*
G01Y-787456D02*
Y-777056D01*
G01X-592814Y-787456D02*
Y-777056D01*
G01Y-778876D02*
X-593594Y-777836D01*
X-594764Y-777316D01*
X-596129Y-777056D01*
X-597494Y-777576D01*
X-598664Y-778616D01*
X-599444Y-780176D01*
X-599834Y-782256D01*
X-599444Y-784336D01*
X-598664Y-785896D01*
X-597494Y-786936D01*
X-596129Y-787456D01*
X-594764Y-787196D01*
X-593594Y-786416D01*
X-592814Y-785376D01*
G01X-578424Y-787456D02*
Y-771856D01*
G01X-560524Y-777056D02*
Y-787456D01*
G01Y-772896D02*
X-560914Y-772636D01*
Y-772116D01*
X-560524Y-771856D01*
X-560134Y-772116D01*
Y-772636D01*
X-560524Y-772896D01*
G01X-542624Y-771856D02*
Y-787456D01*
G01X-545354Y-777056D02*
X-539894D01*
G01X-528819Y-792136D02*
X-527649Y-792656D01*
X-526089Y-792136D01*
X-525114Y-791096D01*
X-524334Y-789796D01*
X-523164Y-785636D01*
X-520629Y-777056D01*
G01X-526869D02*
X-523164Y-785636D01*
G01X-485804Y-778356D02*
X-487169Y-777316D01*
X-488339Y-777056D01*
X-489899Y-777576D01*
X-491069Y-778616D01*
X-491849Y-780436D01*
X-492044Y-782256D01*
X-491849Y-784076D01*
X-491069Y-785636D01*
X-489899Y-786936D01*
X-488339Y-787456D01*
X-486974Y-786936D01*
X-485804Y-785896D01*
G01X-471024Y-787456D02*
X-472194Y-787196D01*
X-473364Y-786156D01*
X-474144Y-784336D01*
X-474534Y-782256D01*
X-474144Y-780176D01*
X-473364Y-778356D01*
X-472194Y-777316D01*
X-471024Y-777056D01*
X-469854Y-777316D01*
X-468684Y-778356D01*
X-467904Y-780176D01*
X-467709Y-782256D01*
X-467904Y-784336D01*
X-468684Y-786156D01*
X-469854Y-787196D01*
X-471024Y-787456D01*
G01X-456439D02*
Y-777056D01*
G01Y-779656D02*
X-455659Y-778356D01*
X-454489Y-777316D01*
X-452929Y-777056D01*
X-451564Y-777316D01*
X-450394Y-778356D01*
X-449809Y-780176D01*
Y-787456D01*
G01X-435224Y-771856D02*
Y-787456D01*
G01X-437954Y-777056D02*
X-432494D01*
G01X-420054Y-787456D02*
Y-777056D01*
G01Y-779136D02*
X-419079Y-778096D01*
X-418104Y-777316D01*
X-416739Y-777056D01*
X-415764Y-777316D01*
X-414594Y-778096D01*
G01X-399424Y-787456D02*
X-400594Y-787196D01*
X-401764Y-786156D01*
X-402544Y-784336D01*
X-402934Y-782256D01*
X-402544Y-780176D01*
X-401764Y-778356D01*
X-400594Y-777316D01*
X-399424Y-777056D01*
X-398254Y-777316D01*
X-397084Y-778356D01*
X-396304Y-780176D01*
X-396109Y-782256D01*
X-396304Y-784336D01*
X-397084Y-786156D01*
X-398254Y-787196D01*
X-399424Y-787456D01*
G01X-381524D02*
Y-771856D01*
G01X-2136114Y-699456D02*
X-2135724Y-696076D01*
X-2135139Y-693216D01*
X-2134359Y-690616D01*
X-2133384Y-687756D01*
X-2131824Y-683856D01*
X-2139624D01*
G01X-2117824Y-699976D02*
X-2118214Y-699716D01*
Y-699196D01*
X-2117824Y-698936D01*
X-2117434Y-699196D01*
Y-699716D01*
X-2117824Y-699976D01*
G01X-2085924Y-699456D02*
Y-683856D01*
X-2081244D01*
X-2079684Y-684636D01*
X-2078514Y-686456D01*
X-2078124Y-688536D01*
X-2078514Y-690616D01*
X-2079489Y-692176D01*
X-2081244Y-692956D01*
X-2085924D01*
G01X-2064124Y-699456D02*
Y-683856D01*
G01X-2049149Y-692436D02*
X-2042909D01*
X-2043494Y-690616D01*
X-2044469Y-689576D01*
X-2045834Y-689056D01*
X-2047199Y-689316D01*
X-2048369Y-690096D01*
X-2049149Y-691916D01*
X-2049539Y-693476D01*
Y-695036D01*
X-2049149Y-696596D01*
X-2048174Y-698156D01*
X-2047004Y-699196D01*
X-2045639Y-699456D01*
X-2044274Y-698936D01*
X-2042909Y-697376D01*
G01X-2024814Y-699456D02*
Y-689056D01*
G01Y-690876D02*
X-2025594Y-689836D01*
X-2026764Y-689316D01*
X-2028129Y-689056D01*
X-2029494Y-689576D01*
X-2030664Y-690616D01*
X-2031444Y-692176D01*
X-2031834Y-694256D01*
X-2031444Y-696336D01*
X-2030664Y-697896D01*
X-2029494Y-698936D01*
X-2028129Y-699456D01*
X-2026764Y-699196D01*
X-2025594Y-698416D01*
X-2024814Y-697376D01*
G01X-2013349Y-697636D02*
X-2012374Y-698676D01*
X-2011009Y-699456D01*
X-2009839D01*
X-2008669Y-698936D01*
X-2007889Y-698156D01*
X-2007499Y-697116D01*
X-2007694Y-695556D01*
X-2008474Y-694776D01*
X-2011984Y-693216D01*
X-2012764Y-691396D01*
X-2012374Y-690096D01*
X-2011594Y-689316D01*
X-2010424Y-689056D01*
X-2009254Y-689316D01*
X-2008084Y-690096D01*
G01X-1995449Y-692436D02*
X-1989209D01*
X-1989794Y-690616D01*
X-1990769Y-689576D01*
X-1992134Y-689056D01*
X-1993499Y-689316D01*
X-1994669Y-690096D01*
X-1995449Y-691916D01*
X-1995839Y-693476D01*
Y-695036D01*
X-1995449Y-696596D01*
X-1994474Y-698156D01*
X-1993304Y-699196D01*
X-1991939Y-699456D01*
X-1990574Y-698936D01*
X-1989209Y-697376D01*
G01X-1960234Y-704656D02*
Y-689056D01*
G01Y-691396D02*
X-1959259Y-690096D01*
X-1958284Y-689316D01*
X-1956724Y-689056D01*
X-1955359Y-689316D01*
X-1953994Y-690616D01*
X-1953409Y-692436D01*
X-1953214Y-694256D01*
X-1953409Y-696076D01*
X-1953994Y-697896D01*
X-1955164Y-698936D01*
X-1956724Y-699456D01*
X-1958089Y-699196D01*
X-1959454Y-698416D01*
X-1960234Y-697376D01*
G01X-1941554Y-699456D02*
Y-689056D01*
G01Y-691136D02*
X-1940579Y-690096D01*
X-1939604Y-689316D01*
X-1938239Y-689056D01*
X-1937264Y-689316D01*
X-1936094Y-690096D01*
G01X-1920924Y-699456D02*
X-1922094Y-699196D01*
X-1923264Y-698156D01*
X-1924044Y-696336D01*
X-1924434Y-694256D01*
X-1924044Y-692176D01*
X-1923264Y-690356D01*
X-1922094Y-689316D01*
X-1920924Y-689056D01*
X-1919754Y-689316D01*
X-1918584Y-690356D01*
X-1917804Y-692176D01*
X-1917609Y-694256D01*
X-1917804Y-696336D01*
X-1918584Y-698156D01*
X-1919754Y-699196D01*
X-1920924Y-699456D01*
G01X-1906534Y-689056D02*
X-1903024Y-699456D01*
X-1899514Y-689056D01*
G01X-1885124D02*
Y-699456D01*
G01Y-684896D02*
X-1885514Y-684636D01*
Y-684116D01*
X-1885124Y-683856D01*
X-1884734Y-684116D01*
Y-684636D01*
X-1885124Y-684896D01*
G01X-1863714Y-683856D02*
Y-699456D01*
G01Y-697116D02*
X-1864494Y-698416D01*
X-1865664Y-699196D01*
X-1867029Y-699456D01*
X-1868589Y-698936D01*
X-1869759Y-697636D01*
X-1870539Y-696076D01*
X-1870734Y-694256D01*
X-1870539Y-692436D01*
X-1869759Y-690876D01*
X-1868589Y-689576D01*
X-1867029Y-689056D01*
X-1865664Y-689316D01*
X-1864689Y-689836D01*
X-1863714Y-690876D01*
G01X-1852249Y-692436D02*
X-1846009D01*
X-1846594Y-690616D01*
X-1847569Y-689576D01*
X-1848934Y-689056D01*
X-1850299Y-689316D01*
X-1851469Y-690096D01*
X-1852249Y-691916D01*
X-1852639Y-693476D01*
Y-695036D01*
X-1852249Y-696596D01*
X-1851274Y-698156D01*
X-1850104Y-699196D01*
X-1848739Y-699456D01*
X-1847374Y-698936D01*
X-1846009Y-697376D01*
G01X-1810014Y-683856D02*
Y-699456D01*
G01Y-697116D02*
X-1810794Y-698416D01*
X-1811964Y-699196D01*
X-1813329Y-699456D01*
X-1814889Y-698936D01*
X-1816059Y-697636D01*
X-1816839Y-696076D01*
X-1817034Y-694256D01*
X-1816839Y-692436D01*
X-1816059Y-690876D01*
X-1814889Y-689576D01*
X-1813329Y-689056D01*
X-1811964Y-689316D01*
X-1810989Y-689836D01*
X-1810014Y-690876D01*
G01X-1798354Y-699456D02*
Y-689056D01*
G01Y-691136D02*
X-1797379Y-690096D01*
X-1796404Y-689316D01*
X-1795039Y-689056D01*
X-1794064Y-689316D01*
X-1792894Y-690096D01*
G01X-1777724Y-689056D02*
Y-699456D01*
G01Y-684896D02*
X-1778114Y-684636D01*
Y-684116D01*
X-1777724Y-683856D01*
X-1777334Y-684116D01*
Y-684636D01*
X-1777724Y-684896D01*
G01X-1759824Y-699456D02*
Y-683856D01*
G01X-1741924Y-699456D02*
Y-683856D01*
G01X-1709634Y-699456D02*
Y-683856D01*
G01Y-691656D02*
X-1708659Y-690096D01*
X-1707489Y-689316D01*
X-1706319Y-689056D01*
X-1704564Y-689576D01*
X-1703394Y-690616D01*
X-1702614Y-692436D01*
Y-694516D01*
X-1703004Y-696596D01*
X-1703784Y-698156D01*
X-1705149Y-699196D01*
X-1706319Y-699456D01*
X-1707489Y-699196D01*
X-1708659Y-698416D01*
X-1709634Y-697116D01*
G01X-1688224Y-689056D02*
Y-699456D01*
G01Y-684896D02*
X-1688614Y-684636D01*
Y-684116D01*
X-1688224Y-683856D01*
X-1687834Y-684116D01*
Y-684636D01*
X-1688224Y-684896D01*
G01X-1670324Y-683856D02*
Y-699456D01*
G01X-1673054Y-689056D02*
X-1667594D01*
G01X-1637449Y-697636D02*
X-1636474Y-698676D01*
X-1635109Y-699456D01*
X-1633939D01*
X-1632769Y-698936D01*
X-1631989Y-698156D01*
X-1631599Y-697116D01*
X-1631794Y-695556D01*
X-1632574Y-694776D01*
X-1636084Y-693216D01*
X-1636864Y-691396D01*
X-1636474Y-690096D01*
X-1635694Y-689316D01*
X-1634524Y-689056D01*
X-1633354Y-689316D01*
X-1632184Y-690096D01*
G01X-1616624Y-689056D02*
Y-699456D01*
G01Y-684896D02*
X-1617014Y-684636D01*
Y-684116D01*
X-1616624Y-683856D01*
X-1616234Y-684116D01*
Y-684636D01*
X-1616624Y-684896D01*
G01X-1601649Y-689056D02*
X-1595799D01*
X-1601649Y-699456D01*
X-1595799D01*
G01X-1583749Y-692436D02*
X-1577509D01*
X-1578094Y-690616D01*
X-1579069Y-689576D01*
X-1580434Y-689056D01*
X-1581799Y-689316D01*
X-1582969Y-690096D01*
X-1583749Y-691916D01*
X-1584139Y-693476D01*
Y-695036D01*
X-1583749Y-696596D01*
X-1582774Y-698156D01*
X-1581604Y-699196D01*
X-1580239Y-699456D01*
X-1578874Y-698936D01*
X-1577509Y-697376D01*
G01X-1547949Y-697636D02*
X-1546974Y-698676D01*
X-1545609Y-699456D01*
X-1544439D01*
X-1543269Y-698936D01*
X-1542489Y-698156D01*
X-1542099Y-697116D01*
X-1542294Y-695556D01*
X-1543074Y-694776D01*
X-1546584Y-693216D01*
X-1547364Y-691396D01*
X-1546974Y-690096D01*
X-1546194Y-689316D01*
X-1545024Y-689056D01*
X-1543854Y-689316D01*
X-1542684Y-690096D01*
G01X-1530049Y-692436D02*
X-1523809D01*
X-1524394Y-690616D01*
X-1525369Y-689576D01*
X-1526734Y-689056D01*
X-1528099Y-689316D01*
X-1529269Y-690096D01*
X-1530049Y-691916D01*
X-1530439Y-693476D01*
Y-695036D01*
X-1530049Y-696596D01*
X-1529074Y-698156D01*
X-1527904Y-699196D01*
X-1526539Y-699456D01*
X-1525174Y-698936D01*
X-1523809Y-697376D01*
G01X-1509224Y-699456D02*
Y-683856D01*
G01X-1494249Y-692436D02*
X-1488009D01*
X-1488594Y-690616D01*
X-1489569Y-689576D01*
X-1490934Y-689056D01*
X-1492299Y-689316D01*
X-1493469Y-690096D01*
X-1494249Y-691916D01*
X-1494639Y-693476D01*
Y-695036D01*
X-1494249Y-696596D01*
X-1493274Y-698156D01*
X-1492104Y-699196D01*
X-1490739Y-699456D01*
X-1489374Y-698936D01*
X-1488009Y-697376D01*
G01X-1470304Y-690356D02*
X-1471669Y-689316D01*
X-1472839Y-689056D01*
X-1474399Y-689576D01*
X-1475569Y-690616D01*
X-1476349Y-692436D01*
X-1476544Y-694256D01*
X-1476349Y-696076D01*
X-1475569Y-697636D01*
X-1474399Y-698936D01*
X-1472839Y-699456D01*
X-1471474Y-698936D01*
X-1470304Y-697896D01*
G01X-1455524Y-683856D02*
Y-699456D01*
G01X-1458254Y-689056D02*
X-1452794D01*
G01X-1440549Y-692436D02*
X-1434309D01*
X-1434894Y-690616D01*
X-1435869Y-689576D01*
X-1437234Y-689056D01*
X-1438599Y-689316D01*
X-1439769Y-690096D01*
X-1440549Y-691916D01*
X-1440939Y-693476D01*
Y-695036D01*
X-1440549Y-696596D01*
X-1439574Y-698156D01*
X-1438404Y-699196D01*
X-1437039Y-699456D01*
X-1435674Y-698936D01*
X-1434309Y-697376D01*
G01X-1416214Y-683856D02*
Y-699456D01*
G01Y-697116D02*
X-1416994Y-698416D01*
X-1418164Y-699196D01*
X-1419529Y-699456D01*
X-1421089Y-698936D01*
X-1422259Y-697636D01*
X-1423039Y-696076D01*
X-1423234Y-694256D01*
X-1423039Y-692436D01*
X-1422259Y-690876D01*
X-1421089Y-689576D01*
X-1419529Y-689056D01*
X-1418164Y-689316D01*
X-1417189Y-689836D01*
X-1416214Y-690876D01*
G01X-1385094Y-699456D02*
Y-686196D01*
X-1384704Y-684896D01*
X-1383924Y-684116D01*
X-1382754Y-683856D01*
X-1381584Y-684376D01*
X-1380999Y-685676D01*
G01X-1383339Y-690096D02*
X-1387239D01*
G01X-1366024Y-699456D02*
X-1367194Y-699196D01*
X-1368364Y-698156D01*
X-1369144Y-696336D01*
X-1369534Y-694256D01*
X-1369144Y-692176D01*
X-1368364Y-690356D01*
X-1367194Y-689316D01*
X-1366024Y-689056D01*
X-1364854Y-689316D01*
X-1363684Y-690356D01*
X-1362904Y-692176D01*
X-1362709Y-694256D01*
X-1362904Y-696336D01*
X-1363684Y-698156D01*
X-1364854Y-699196D01*
X-1366024Y-699456D01*
G01X-1350854D02*
Y-689056D01*
G01Y-691136D02*
X-1349879Y-690096D01*
X-1348904Y-689316D01*
X-1347539Y-689056D01*
X-1346564Y-689316D01*
X-1345394Y-690096D01*
G01X-1308814Y-699456D02*
Y-689056D01*
G01Y-690876D02*
X-1309594Y-689836D01*
X-1310764Y-689316D01*
X-1312129Y-689056D01*
X-1313494Y-689576D01*
X-1314664Y-690616D01*
X-1315444Y-692176D01*
X-1315834Y-694256D01*
X-1315444Y-696336D01*
X-1314664Y-697896D01*
X-1313494Y-698936D01*
X-1312129Y-699456D01*
X-1310764Y-699196D01*
X-1309594Y-698416D01*
X-1308814Y-697376D01*
G01X-1294424Y-699456D02*
Y-683856D01*
G01X-1276524Y-699456D02*
Y-683856D01*
G01X-1244234Y-704656D02*
Y-689056D01*
G01Y-691396D02*
X-1243259Y-690096D01*
X-1242284Y-689316D01*
X-1240724Y-689056D01*
X-1239359Y-689316D01*
X-1237994Y-690616D01*
X-1237409Y-692436D01*
X-1237214Y-694256D01*
X-1237409Y-696076D01*
X-1237994Y-697896D01*
X-1239164Y-698936D01*
X-1240724Y-699456D01*
X-1242089Y-699196D01*
X-1243454Y-698416D01*
X-1244234Y-697376D01*
G01X-1225554Y-699456D02*
Y-689056D01*
G01Y-691136D02*
X-1224579Y-690096D01*
X-1223604Y-689316D01*
X-1222239Y-689056D01*
X-1221264Y-689316D01*
X-1220094Y-690096D01*
G01X-1207849Y-692436D02*
X-1201609D01*
X-1202194Y-690616D01*
X-1203169Y-689576D01*
X-1204534Y-689056D01*
X-1205899Y-689316D01*
X-1207069Y-690096D01*
X-1207849Y-691916D01*
X-1208239Y-693476D01*
Y-695036D01*
X-1207849Y-696596D01*
X-1206874Y-698156D01*
X-1205704Y-699196D01*
X-1204339Y-699456D01*
X-1202974Y-698936D01*
X-1201609Y-697376D01*
G01X-1189949Y-697636D02*
X-1188974Y-698676D01*
X-1187609Y-699456D01*
X-1186439D01*
X-1185269Y-698936D01*
X-1184489Y-698156D01*
X-1184099Y-697116D01*
X-1184294Y-695556D01*
X-1185074Y-694776D01*
X-1188584Y-693216D01*
X-1189364Y-691396D01*
X-1188974Y-690096D01*
X-1188194Y-689316D01*
X-1187024Y-689056D01*
X-1185854Y-689316D01*
X-1184684Y-690096D01*
G01X-1172049Y-697636D02*
X-1171074Y-698676D01*
X-1169709Y-699456D01*
X-1168539D01*
X-1167369Y-698936D01*
X-1166589Y-698156D01*
X-1166199Y-697116D01*
X-1166394Y-695556D01*
X-1167174Y-694776D01*
X-1170684Y-693216D01*
X-1171464Y-691396D01*
X-1171074Y-690096D01*
X-1170294Y-689316D01*
X-1169124Y-689056D01*
X-1167954Y-689316D01*
X-1166784Y-690096D01*
G01X-1153759Y-694256D02*
X-1148689D01*
G01X-1134494Y-699456D02*
Y-686196D01*
X-1134104Y-684896D01*
X-1133324Y-684116D01*
X-1132154Y-683856D01*
X-1130984Y-684376D01*
X-1130399Y-685676D01*
G01X-1132739Y-690096D02*
X-1136639D01*
G01X-1115424Y-689056D02*
Y-699456D01*
G01Y-684896D02*
X-1115814Y-684636D01*
Y-684116D01*
X-1115424Y-683856D01*
X-1115034Y-684116D01*
Y-684636D01*
X-1115424Y-684896D01*
G01X-1097524Y-683856D02*
Y-699456D01*
G01X-1100254Y-689056D02*
X-1094794D01*
G01X-1065039Y-699456D02*
Y-683856D01*
G01Y-691396D02*
X-1064064Y-690096D01*
X-1063089Y-689316D01*
X-1061529Y-689056D01*
X-1060359Y-689316D01*
X-1058994Y-690356D01*
X-1058409Y-691916D01*
Y-699456D01*
G01X-1043824D02*
X-1044994Y-699196D01*
X-1046164Y-698156D01*
X-1046944Y-696336D01*
X-1047334Y-694256D01*
X-1046944Y-692176D01*
X-1046164Y-690356D01*
X-1044994Y-689316D01*
X-1043824Y-689056D01*
X-1042654Y-689316D01*
X-1041484Y-690356D01*
X-1040704Y-692176D01*
X-1040509Y-694256D01*
X-1040704Y-696336D01*
X-1041484Y-698156D01*
X-1042654Y-699196D01*
X-1043824Y-699456D01*
G01X-1025924D02*
Y-683856D01*
G01X-1010949Y-692436D02*
X-1004709D01*
X-1005294Y-690616D01*
X-1006269Y-689576D01*
X-1007634Y-689056D01*
X-1008999Y-689316D01*
X-1010169Y-690096D01*
X-1010949Y-691916D01*
X-1011339Y-693476D01*
Y-695036D01*
X-1010949Y-696596D01*
X-1009974Y-698156D01*
X-1008804Y-699196D01*
X-1007439Y-699456D01*
X-1006074Y-698936D01*
X-1004709Y-697376D01*
G01X-993049Y-697636D02*
X-992074Y-698676D01*
X-990709Y-699456D01*
X-989539D01*
X-988369Y-698936D01*
X-987589Y-698156D01*
X-987199Y-697116D01*
X-987394Y-695556D01*
X-988174Y-694776D01*
X-991684Y-693216D01*
X-992464Y-691396D01*
X-992074Y-690096D01*
X-991294Y-689316D01*
X-990124Y-689056D01*
X-988954Y-689316D01*
X-987784Y-690096D01*
G01X-950814Y-699456D02*
Y-689056D01*
G01Y-690876D02*
X-951594Y-689836D01*
X-952764Y-689316D01*
X-954129Y-689056D01*
X-955494Y-689576D01*
X-956664Y-690616D01*
X-957444Y-692176D01*
X-957834Y-694256D01*
X-957444Y-696336D01*
X-956664Y-697896D01*
X-955494Y-698936D01*
X-954129Y-699456D01*
X-952764Y-699196D01*
X-951594Y-698416D01*
X-950814Y-697376D01*
G01X-939739Y-699456D02*
Y-689056D01*
G01Y-691656D02*
X-938959Y-690356D01*
X-937789Y-689316D01*
X-936229Y-689056D01*
X-934864Y-689316D01*
X-933694Y-690356D01*
X-933109Y-692176D01*
Y-699456D01*
G01X-915014Y-683856D02*
Y-699456D01*
G01Y-697116D02*
X-915794Y-698416D01*
X-916964Y-699196D01*
X-918329Y-699456D01*
X-919889Y-698936D01*
X-921059Y-697636D01*
X-921839Y-696076D01*
X-922034Y-694256D01*
X-921839Y-692436D01*
X-921059Y-690876D01*
X-919889Y-689576D01*
X-918329Y-689056D01*
X-916964Y-689316D01*
X-915989Y-689836D01*
X-915014Y-690876D01*
G01X-879214Y-699456D02*
Y-689056D01*
G01Y-690876D02*
X-879994Y-689836D01*
X-881164Y-689316D01*
X-882529Y-689056D01*
X-883894Y-689576D01*
X-885064Y-690616D01*
X-885844Y-692176D01*
X-886234Y-694256D01*
X-885844Y-696336D01*
X-885064Y-697896D01*
X-883894Y-698936D01*
X-882529Y-699456D01*
X-881164Y-699196D01*
X-879994Y-698416D01*
X-879214Y-697376D01*
G01X-868334Y-689056D02*
X-864824Y-699456D01*
X-861314Y-689056D01*
G01X-849849Y-692436D02*
X-843609D01*
X-844194Y-690616D01*
X-845169Y-689576D01*
X-846534Y-689056D01*
X-847899Y-689316D01*
X-849069Y-690096D01*
X-849849Y-691916D01*
X-850239Y-693476D01*
Y-695036D01*
X-849849Y-696596D01*
X-848874Y-698156D01*
X-847704Y-699196D01*
X-846339Y-699456D01*
X-844974Y-698936D01*
X-843609Y-697376D01*
G01X-831754Y-699456D02*
Y-689056D01*
G01Y-691136D02*
X-830779Y-690096D01*
X-829804Y-689316D01*
X-828439Y-689056D01*
X-827464Y-689316D01*
X-826294Y-690096D01*
G01X-807614Y-699456D02*
Y-689056D01*
G01Y-690876D02*
X-808394Y-689836D01*
X-809564Y-689316D01*
X-810929Y-689056D01*
X-812294Y-689576D01*
X-813464Y-690616D01*
X-814244Y-692176D01*
X-814634Y-694256D01*
X-814244Y-696336D01*
X-813464Y-697896D01*
X-812294Y-698936D01*
X-810929Y-699456D01*
X-809564Y-699196D01*
X-808394Y-698416D01*
X-807614Y-697376D01*
G01X-795954Y-703356D02*
X-794589Y-704396D01*
X-793029Y-704656D01*
X-791664Y-704396D01*
X-790494Y-703096D01*
X-789714Y-701276D01*
Y-689056D01*
G01Y-691136D02*
X-790494Y-690096D01*
X-791664Y-689316D01*
X-793029Y-689056D01*
X-794589Y-689576D01*
X-795564Y-690616D01*
X-796344Y-692436D01*
X-796734Y-694256D01*
X-796539Y-695816D01*
X-795759Y-697636D01*
X-794589Y-698936D01*
X-793029Y-699456D01*
X-791859Y-699196D01*
X-790494Y-698156D01*
X-789714Y-697116D01*
G01X-778249Y-692436D02*
X-772009D01*
X-772594Y-690616D01*
X-773569Y-689576D01*
X-774934Y-689056D01*
X-776299Y-689316D01*
X-777469Y-690096D01*
X-778249Y-691916D01*
X-778639Y-693476D01*
Y-695036D01*
X-778249Y-696596D01*
X-777274Y-698156D01*
X-776104Y-699196D01*
X-774739Y-699456D01*
X-773374Y-698936D01*
X-772009Y-697376D01*
G01X-743034Y-704656D02*
Y-689056D01*
G01Y-691396D02*
X-742059Y-690096D01*
X-741084Y-689316D01*
X-739524Y-689056D01*
X-738159Y-689316D01*
X-736794Y-690616D01*
X-736209Y-692436D01*
X-736014Y-694256D01*
X-736209Y-696076D01*
X-736794Y-697896D01*
X-737964Y-698936D01*
X-739524Y-699456D01*
X-740889Y-699196D01*
X-742254Y-698416D01*
X-743034Y-697376D01*
G01X-721624Y-699456D02*
Y-683856D01*
G01X-700214Y-699456D02*
Y-689056D01*
G01Y-690876D02*
X-700994Y-689836D01*
X-702164Y-689316D01*
X-703529Y-689056D01*
X-704894Y-689576D01*
X-706064Y-690616D01*
X-706844Y-692176D01*
X-707234Y-694256D01*
X-706844Y-696336D01*
X-706064Y-697896D01*
X-704894Y-698936D01*
X-703529Y-699456D01*
X-702164Y-699196D01*
X-700994Y-698416D01*
X-700214Y-697376D01*
G01X-685824Y-683856D02*
Y-699456D01*
G01X-688554Y-689056D02*
X-683094D01*
G01X-667924D02*
Y-699456D01*
G01Y-684896D02*
X-668314Y-684636D01*
Y-684116D01*
X-667924Y-683856D01*
X-667534Y-684116D01*
Y-684636D01*
X-667924Y-684896D01*
G01X-653339Y-699456D02*
Y-689056D01*
G01Y-691656D02*
X-652559Y-690356D01*
X-651389Y-689316D01*
X-649829Y-689056D01*
X-648464Y-689316D01*
X-647294Y-690356D01*
X-646709Y-692176D01*
Y-699456D01*
G01X-634854Y-703356D02*
X-633489Y-704396D01*
X-631929Y-704656D01*
X-630564Y-704396D01*
X-629394Y-703096D01*
X-628614Y-701276D01*
Y-689056D01*
G01Y-691136D02*
X-629394Y-690096D01*
X-630564Y-689316D01*
X-631929Y-689056D01*
X-633489Y-689576D01*
X-634464Y-690616D01*
X-635244Y-692436D01*
X-635634Y-694256D01*
X-635439Y-695816D01*
X-634659Y-697636D01*
X-633489Y-698936D01*
X-631929Y-699456D01*
X-630759Y-699196D01*
X-629394Y-698156D01*
X-628614Y-697116D01*
G01X-596324Y-683856D02*
Y-699456D01*
G01X-599054Y-689056D02*
X-593594D01*
G01X-581739Y-699456D02*
Y-683856D01*
G01Y-691396D02*
X-580764Y-690096D01*
X-579789Y-689316D01*
X-578229Y-689056D01*
X-577059Y-689316D01*
X-575694Y-690356D01*
X-575109Y-691916D01*
Y-699456D01*
G01X-560524Y-689056D02*
Y-699456D01*
G01Y-684896D02*
X-560914Y-684636D01*
Y-684116D01*
X-560524Y-683856D01*
X-560134Y-684116D01*
Y-684636D01*
X-560524Y-684896D01*
G01X-539504Y-690356D02*
X-540869Y-689316D01*
X-542039Y-689056D01*
X-543599Y-689576D01*
X-544769Y-690616D01*
X-545549Y-692436D01*
X-545744Y-694256D01*
X-545549Y-696076D01*
X-544769Y-697636D01*
X-543599Y-698936D01*
X-542039Y-699456D01*
X-540674Y-698936D01*
X-539504Y-697896D01*
G01X-528039Y-699456D02*
Y-683856D01*
G01X-521799Y-689056D02*
X-528039Y-695036D01*
G01X-525504Y-692696D02*
X-521409Y-699456D01*
G01X-510139D02*
Y-689056D01*
G01Y-691656D02*
X-509359Y-690356D01*
X-508189Y-689316D01*
X-506629Y-689056D01*
X-505264Y-689316D01*
X-504094Y-690356D01*
X-503509Y-692176D01*
Y-699456D01*
G01X-491849Y-692436D02*
X-485609D01*
X-486194Y-690616D01*
X-487169Y-689576D01*
X-488534Y-689056D01*
X-489899Y-689316D01*
X-491069Y-690096D01*
X-491849Y-691916D01*
X-492239Y-693476D01*
Y-695036D01*
X-491849Y-696596D01*
X-490874Y-698156D01*
X-489704Y-699196D01*
X-488339Y-699456D01*
X-486974Y-698936D01*
X-485609Y-697376D01*
G01X-473949Y-697636D02*
X-472974Y-698676D01*
X-471609Y-699456D01*
X-470439D01*
X-469269Y-698936D01*
X-468489Y-698156D01*
X-468099Y-697116D01*
X-468294Y-695556D01*
X-469074Y-694776D01*
X-472584Y-693216D01*
X-473364Y-691396D01*
X-472974Y-690096D01*
X-472194Y-689316D01*
X-471024Y-689056D01*
X-469854Y-689316D01*
X-468684Y-690096D01*
G01X-456049Y-697636D02*
X-455074Y-698676D01*
X-453709Y-699456D01*
X-452539D01*
X-451369Y-698936D01*
X-450589Y-698156D01*
X-450199Y-697116D01*
X-450394Y-695556D01*
X-451174Y-694776D01*
X-454684Y-693216D01*
X-455464Y-691396D01*
X-455074Y-690096D01*
X-454294Y-689316D01*
X-453124Y-689056D01*
X-451954Y-689316D01*
X-450784Y-690096D01*
G01X-2140429Y-512956D02*
X-2139064Y-511136D01*
X-2137894Y-510096D01*
X-2136334Y-509576D01*
X-2134969Y-510096D01*
X-2133994Y-511136D01*
X-2133214Y-512696D01*
X-2133019Y-514516D01*
X-2133214Y-516076D01*
X-2133994Y-517636D01*
X-2135164Y-518936D01*
X-2136529Y-519456D01*
X-2138089Y-518936D01*
X-2139454Y-517376D01*
X-2140234Y-515036D01*
X-2140429Y-512436D01*
X-2140039Y-509056D01*
X-2139454Y-507236D01*
X-2138479Y-505416D01*
X-2137114Y-504116D01*
X-2135749Y-503856D01*
X-2134384Y-504376D01*
X-2133409Y-505676D01*
G01X-2118824Y-519976D02*
X-2119214Y-519716D01*
Y-519196D01*
X-2118824Y-518936D01*
X-2118434Y-519196D01*
Y-519716D01*
X-2118824Y-519976D01*
G01X-2081854Y-511656D02*
X-2077954D01*
Y-516336D01*
X-2079124Y-517896D01*
X-2080489Y-518936D01*
X-2082439Y-519456D01*
X-2084389Y-518936D01*
X-2085754Y-517896D01*
X-2086924Y-516336D01*
X-2087704Y-514516D01*
X-2088094Y-512436D01*
Y-510616D01*
X-2087704Y-509056D01*
X-2086924Y-507236D01*
X-2085754Y-505676D01*
X-2084584Y-504636D01*
X-2083024Y-503856D01*
X-2081659D01*
X-2080099Y-504376D01*
X-2078929Y-505416D01*
G01X-2065124Y-519456D02*
X-2066294Y-519196D01*
X-2067464Y-518156D01*
X-2068244Y-516336D01*
X-2068634Y-514256D01*
X-2068244Y-512176D01*
X-2067464Y-510356D01*
X-2066294Y-509316D01*
X-2065124Y-509056D01*
X-2063954Y-509316D01*
X-2062784Y-510356D01*
X-2062004Y-512176D01*
X-2061809Y-514256D01*
X-2062004Y-516336D01*
X-2062784Y-518156D01*
X-2063954Y-519196D01*
X-2065124Y-519456D01*
G01X-2047224D02*
Y-503856D01*
G01X-2025814D02*
Y-519456D01*
G01Y-517116D02*
X-2026594Y-518416D01*
X-2027764Y-519196D01*
X-2029129Y-519456D01*
X-2030689Y-518936D01*
X-2031859Y-517636D01*
X-2032639Y-516076D01*
X-2032834Y-514256D01*
X-2032639Y-512436D01*
X-2031859Y-510876D01*
X-2030689Y-509576D01*
X-2029129Y-509056D01*
X-2027764Y-509316D01*
X-2026789Y-509836D01*
X-2025814Y-510876D01*
G01X-1997229Y-519456D02*
Y-503856D01*
X-1989819D01*
G01X-1992549Y-511396D02*
X-1997229D01*
G01X-1975624Y-509056D02*
Y-519456D01*
G01Y-504896D02*
X-1976014Y-504636D01*
Y-504116D01*
X-1975624Y-503856D01*
X-1975234Y-504116D01*
Y-504636D01*
X-1975624Y-504896D01*
G01X-1961039Y-519456D02*
Y-509056D01*
G01Y-511656D02*
X-1960259Y-510356D01*
X-1959089Y-509316D01*
X-1957529Y-509056D01*
X-1956164Y-509316D01*
X-1954994Y-510356D01*
X-1954409Y-512176D01*
Y-519456D01*
G01X-1942554Y-523356D02*
X-1941189Y-524396D01*
X-1939629Y-524656D01*
X-1938264Y-524396D01*
X-1937094Y-523096D01*
X-1936314Y-521276D01*
Y-509056D01*
G01Y-511136D02*
X-1937094Y-510096D01*
X-1938264Y-509316D01*
X-1939629Y-509056D01*
X-1941189Y-509576D01*
X-1942164Y-510616D01*
X-1942944Y-512436D01*
X-1943334Y-514256D01*
X-1943139Y-515816D01*
X-1942359Y-517636D01*
X-1941189Y-518936D01*
X-1939629Y-519456D01*
X-1938459Y-519196D01*
X-1937094Y-518156D01*
X-1936314Y-517116D01*
G01X-1924849Y-512436D02*
X-1918609D01*
X-1919194Y-510616D01*
X-1920169Y-509576D01*
X-1921534Y-509056D01*
X-1922899Y-509316D01*
X-1924069Y-510096D01*
X-1924849Y-511916D01*
X-1925239Y-513476D01*
Y-515036D01*
X-1924849Y-516596D01*
X-1923874Y-518156D01*
X-1922704Y-519196D01*
X-1921339Y-519456D01*
X-1919974Y-518936D01*
X-1918609Y-517376D01*
G01X-1906754Y-519456D02*
Y-509056D01*
G01Y-511136D02*
X-1905779Y-510096D01*
X-1904804Y-509316D01*
X-1903439Y-509056D01*
X-1902464Y-509316D01*
X-1901294Y-510096D01*
G01X-1886124Y-519976D02*
X-1886514Y-519716D01*
Y-519196D01*
X-1886124Y-518936D01*
X-1885734Y-519196D01*
Y-519716D01*
X-1886124Y-519976D01*
G01Y-512956D02*
X-1886514Y-512696D01*
Y-512176D01*
X-1886124Y-511916D01*
X-1885734Y-512176D01*
Y-512696D01*
X-1886124Y-512956D01*
G01X-2137014Y-194616D02*
X-2135844Y-195916D01*
X-2134479Y-196696D01*
X-2132724Y-196956D01*
X-2130969Y-196436D01*
X-2129604Y-195396D01*
X-2128629Y-193576D01*
X-2128434Y-191496D01*
X-2128824Y-189416D01*
X-2129799Y-188116D01*
X-2131164Y-187076D01*
X-2132529Y-186816D01*
X-2133894Y-187076D01*
X-2135649Y-188116D01*
X-2135064Y-181356D01*
X-2129799D01*
G01X-2114824Y-197476D02*
X-2115214Y-197216D01*
Y-196696D01*
X-2114824Y-196436D01*
X-2114434Y-196696D01*
Y-197216D01*
X-2114824Y-197476D01*
G01X-2077464Y-188636D02*
X-2076684Y-187856D01*
X-2076099Y-186556D01*
X-2075709Y-184736D01*
X-2076099Y-183176D01*
X-2076879Y-182136D01*
X-2078244Y-181356D01*
X-2083509D01*
Y-196956D01*
X-2077074D01*
X-2075709Y-195916D01*
X-2074929Y-194356D01*
X-2074539Y-192536D01*
X-2074929Y-190716D01*
X-2076099Y-189156D01*
X-2077464Y-188636D01*
X-2083509D01*
G01X-2057614Y-196956D02*
Y-186556D01*
G01Y-188376D02*
X-2058394Y-187336D01*
X-2059564Y-186816D01*
X-2060929Y-186556D01*
X-2062294Y-187076D01*
X-2063464Y-188116D01*
X-2064244Y-189676D01*
X-2064634Y-191756D01*
X-2064244Y-193836D01*
X-2063464Y-195396D01*
X-2062294Y-196436D01*
X-2060929Y-196956D01*
X-2059564Y-196696D01*
X-2058394Y-195916D01*
X-2057614Y-194876D01*
G01X-2040104Y-187856D02*
X-2041469Y-186816D01*
X-2042639Y-186556D01*
X-2044199Y-187076D01*
X-2045369Y-188116D01*
X-2046149Y-189936D01*
X-2046344Y-191756D01*
X-2046149Y-193576D01*
X-2045369Y-195136D01*
X-2044199Y-196436D01*
X-2042639Y-196956D01*
X-2041274Y-196436D01*
X-2040104Y-195396D01*
G01X-2028639Y-196956D02*
Y-181356D01*
G01X-2022399Y-186556D02*
X-2028639Y-192536D01*
G01X-2026104Y-190196D02*
X-2022009Y-196956D01*
G01X-2003914Y-181356D02*
Y-196956D01*
G01Y-194616D02*
X-2004694Y-195916D01*
X-2005864Y-196696D01*
X-2007229Y-196956D01*
X-2008789Y-196436D01*
X-2009959Y-195136D01*
X-2010739Y-193576D01*
X-2010934Y-191756D01*
X-2010739Y-189936D01*
X-2009959Y-188376D01*
X-2008789Y-187076D01*
X-2007229Y-186556D01*
X-2005864Y-186816D01*
X-2004889Y-187336D01*
X-2003914Y-188376D01*
G01X-1992254Y-196956D02*
Y-186556D01*
G01Y-188636D02*
X-1991279Y-187596D01*
X-1990304Y-186816D01*
X-1988939Y-186556D01*
X-1987964Y-186816D01*
X-1986794Y-187596D01*
G01X-1971624Y-186556D02*
Y-196956D01*
G01Y-182396D02*
X-1972014Y-182136D01*
Y-181616D01*
X-1971624Y-181356D01*
X-1971234Y-181616D01*
Y-182136D01*
X-1971624Y-182396D01*
G01X-1953724Y-196956D02*
Y-181356D01*
G01X-1935824Y-196956D02*
Y-181356D01*
G01X-1900024Y-196956D02*
Y-181356D01*
G01X-1885049Y-189936D02*
X-1878809D01*
X-1879394Y-188116D01*
X-1880369Y-187076D01*
X-1881734Y-186556D01*
X-1883099Y-186816D01*
X-1884269Y-187596D01*
X-1885049Y-189416D01*
X-1885439Y-190976D01*
Y-192536D01*
X-1885049Y-194096D01*
X-1884074Y-195656D01*
X-1882904Y-196696D01*
X-1881539Y-196956D01*
X-1880174Y-196436D01*
X-1878809Y-194876D01*
G01X-1866954Y-200856D02*
X-1865589Y-201896D01*
X-1864029Y-202156D01*
X-1862664Y-201896D01*
X-1861494Y-200596D01*
X-1860714Y-198776D01*
Y-186556D01*
G01Y-188636D02*
X-1861494Y-187596D01*
X-1862664Y-186816D01*
X-1864029Y-186556D01*
X-1865589Y-187076D01*
X-1866564Y-188116D01*
X-1867344Y-189936D01*
X-1867734Y-191756D01*
X-1867539Y-193316D01*
X-1866759Y-195136D01*
X-1865589Y-196436D01*
X-1864029Y-196956D01*
X-1862859Y-196696D01*
X-1861494Y-195656D01*
X-1860714Y-194616D01*
G01X-1849249Y-189936D02*
X-1843009D01*
X-1843594Y-188116D01*
X-1844569Y-187076D01*
X-1845934Y-186556D01*
X-1847299Y-186816D01*
X-1848469Y-187596D01*
X-1849249Y-189416D01*
X-1849639Y-190976D01*
Y-192536D01*
X-1849249Y-194096D01*
X-1848274Y-195656D01*
X-1847104Y-196696D01*
X-1845739Y-196956D01*
X-1844374Y-196436D01*
X-1843009Y-194876D01*
G01X-1831739Y-196956D02*
Y-186556D01*
G01Y-189156D02*
X-1830959Y-187856D01*
X-1829789Y-186816D01*
X-1828229Y-186556D01*
X-1826864Y-186816D01*
X-1825694Y-187856D01*
X-1825109Y-189676D01*
Y-196956D01*
G01X-1807014Y-181356D02*
Y-196956D01*
G01Y-194616D02*
X-1807794Y-195916D01*
X-1808964Y-196696D01*
X-1810329Y-196956D01*
X-1811889Y-196436D01*
X-1813059Y-195136D01*
X-1813839Y-193576D01*
X-1814034Y-191756D01*
X-1813839Y-189936D01*
X-1813059Y-188376D01*
X-1811889Y-187076D01*
X-1810329Y-186556D01*
X-1808964Y-186816D01*
X-1807989Y-187336D01*
X-1807014Y-188376D01*
G01X-1792624Y-197476D02*
X-1793014Y-197216D01*
Y-196696D01*
X-1792624Y-196436D01*
X-1792234Y-196696D01*
Y-197216D01*
X-1792624Y-197476D01*
G01Y-190456D02*
X-1793014Y-190196D01*
Y-189676D01*
X-1792624Y-189416D01*
X-1792234Y-189676D01*
Y-190196D01*
X-1792624Y-190456D01*
G01X-2130384Y129044D02*
Y144644D01*
X-2137599Y133464D01*
X-2127849D01*
G01X-2114824Y128524D02*
X-2115214Y128784D01*
Y129304D01*
X-2114824Y129564D01*
X-2114434Y129304D01*
Y128784D01*
X-2114824Y128524D01*
G01X-2084094Y129044D02*
Y144644D01*
X-2079024Y131644D01*
X-2073954Y144644D01*
Y129044D01*
G01X-2057614D02*
Y139444D01*
G01Y137624D02*
X-2058394Y138664D01*
X-2059564Y139184D01*
X-2060929Y139444D01*
X-2062294Y138924D01*
X-2063464Y137884D01*
X-2064244Y136324D01*
X-2064634Y134244D01*
X-2064244Y132164D01*
X-2063464Y130604D01*
X-2062294Y129564D01*
X-2060929Y129044D01*
X-2059564Y129304D01*
X-2058394Y130084D01*
X-2057614Y131124D01*
G01X-2045954Y129044D02*
Y139444D01*
G01Y137364D02*
X-2044979Y138404D01*
X-2044004Y139184D01*
X-2042639Y139444D01*
X-2041664Y139184D01*
X-2040494Y138404D01*
G01X-2028639Y129044D02*
Y144644D01*
G01X-2022399Y139444D02*
X-2028639Y133464D01*
G01X-2026104Y135804D02*
X-2022009Y129044D01*
G01X-2007424Y139444D02*
Y129044D01*
G01Y143604D02*
X-2007814Y143864D01*
Y144384D01*
X-2007424Y144644D01*
X-2007034Y144384D01*
Y143864D01*
X-2007424Y143604D01*
G01X-1992839Y129044D02*
Y139444D01*
G01Y136844D02*
X-1992059Y138144D01*
X-1990889Y139184D01*
X-1989329Y139444D01*
X-1987964Y139184D01*
X-1986794Y138144D01*
X-1986209Y136324D01*
Y129044D01*
G01X-1974354Y125144D02*
X-1972989Y124104D01*
X-1971429Y123844D01*
X-1970064Y124104D01*
X-1968894Y125404D01*
X-1968114Y127224D01*
Y139444D01*
G01Y137364D02*
X-1968894Y138404D01*
X-1970064Y139184D01*
X-1971429Y139444D01*
X-1972989Y138924D01*
X-1973964Y137884D01*
X-1974744Y136064D01*
X-1975134Y134244D01*
X-1974939Y132684D01*
X-1974159Y130864D01*
X-1972989Y129564D01*
X-1971429Y129044D01*
X-1970259Y129304D01*
X-1968894Y130344D01*
X-1968114Y131384D01*
G01X-1953724Y128524D02*
X-1954114Y128784D01*
Y129304D01*
X-1953724Y129564D01*
X-1953334Y129304D01*
Y128784D01*
X-1953724Y128524D01*
G01Y135544D02*
X-1954114Y135804D01*
Y136324D01*
X-1953724Y136584D01*
X-1953334Y136324D01*
Y135804D01*
X-1953724Y135544D01*
G01X-2137014Y322164D02*
X-2135844Y320344D01*
X-2134284Y319304D01*
X-2132529Y319044D01*
X-2130969Y319304D01*
X-2129409Y320604D01*
X-2128434Y322164D01*
X-2128239Y323724D01*
X-2128629Y325544D01*
X-2129994Y326844D01*
X-2131359Y327364D01*
X-2133114D01*
G01X-2131359D02*
X-2130189Y328144D01*
X-2129214Y329444D01*
X-2128824Y331004D01*
X-2129214Y332564D01*
X-2130189Y333864D01*
X-2131944Y334644D01*
X-2133699Y334384D01*
X-2135454Y333344D01*
G01X-2114824Y318524D02*
X-2115214Y318784D01*
Y319304D01*
X-2114824Y319564D01*
X-2114434Y319304D01*
Y318784D01*
X-2114824Y318524D01*
G01X-2083314Y319044D02*
Y334644D01*
X-2079414D01*
X-2077854Y333864D01*
X-2076684Y332824D01*
X-2075709Y331264D01*
X-2074929Y329444D01*
X-2074734Y326844D01*
X-2074929Y324244D01*
X-2075709Y322424D01*
X-2076684Y320864D01*
X-2077854Y319824D01*
X-2079414Y319044D01*
X-2083314D01*
G01X-2063854D02*
Y329444D01*
G01Y327364D02*
X-2062879Y328404D01*
X-2061904Y329184D01*
X-2060539Y329444D01*
X-2059564Y329184D01*
X-2058394Y328404D01*
G01X-2043224Y329444D02*
Y319044D01*
G01Y333604D02*
X-2043614Y333864D01*
Y334384D01*
X-2043224Y334644D01*
X-2042834Y334384D01*
Y333864D01*
X-2043224Y333604D01*
G01X-2025324Y319044D02*
Y334644D01*
G01X-2007424Y319044D02*
Y334644D01*
G01X-1989524Y329444D02*
Y319044D01*
G01Y333604D02*
X-1989914Y333864D01*
Y334384D01*
X-1989524Y334644D01*
X-1989134Y334384D01*
Y333864D01*
X-1989524Y333604D01*
G01X-1974939Y319044D02*
Y329444D01*
G01Y326844D02*
X-1974159Y328144D01*
X-1972989Y329184D01*
X-1971429Y329444D01*
X-1970064Y329184D01*
X-1968894Y328144D01*
X-1968309Y326324D01*
Y319044D01*
G01X-1956454Y315144D02*
X-1955089Y314104D01*
X-1953529Y313844D01*
X-1952164Y314104D01*
X-1950994Y315404D01*
X-1950214Y317224D01*
Y329444D01*
G01Y327364D02*
X-1950994Y328404D01*
X-1952164Y329184D01*
X-1953529Y329444D01*
X-1955089Y328924D01*
X-1956064Y327884D01*
X-1956844Y326064D01*
X-1957234Y324244D01*
X-1957039Y322684D01*
X-1956259Y320864D01*
X-1955089Y319564D01*
X-1953529Y319044D01*
X-1952359Y319304D01*
X-1950994Y320344D01*
X-1950214Y321384D01*
G01X-1935824Y318524D02*
X-1936214Y318784D01*
Y319304D01*
X-1935824Y319564D01*
X-1935434Y319304D01*
Y318784D01*
X-1935824Y318524D01*
G01Y325544D02*
X-1936214Y325804D01*
Y326324D01*
X-1935824Y326584D01*
X-1935434Y326324D01*
Y325804D01*
X-1935824Y325544D01*
G01X-2136429Y454044D02*
X-2135259Y455604D01*
X-2133894Y456384D01*
X-2132334Y456644D01*
X-2130384Y456124D01*
X-2129019Y454824D01*
X-2128629Y453264D01*
X-2128824Y451704D01*
X-2129604Y450404D01*
X-2133504Y447804D01*
X-2135259Y445984D01*
X-2136429Y443384D01*
X-2136819Y441044D01*
X-2128629D01*
G01X-2114824Y440524D02*
X-2115214Y440784D01*
Y441304D01*
X-2114824Y441564D01*
X-2114434Y441304D01*
Y440784D01*
X-2114824Y440524D01*
G01X-2083899Y456644D02*
X-2079024Y441044D01*
X-2074149Y456644D01*
G01X-2061124Y451444D02*
Y441044D01*
G01Y455604D02*
X-2061514Y455864D01*
Y456384D01*
X-2061124Y456644D01*
X-2060734Y456384D01*
Y455864D01*
X-2061124Y455604D01*
G01X-2039714Y441044D02*
Y451444D01*
G01Y449624D02*
X-2040494Y450664D01*
X-2041664Y451184D01*
X-2043029Y451444D01*
X-2044394Y450924D01*
X-2045564Y449884D01*
X-2046344Y448324D01*
X-2046734Y446244D01*
X-2046344Y444164D01*
X-2045564Y442604D01*
X-2044394Y441564D01*
X-2043029Y441044D01*
X-2041664Y441304D01*
X-2040494Y442084D01*
X-2039714Y443124D01*
G01X-2025324Y440524D02*
X-2025714Y440784D01*
Y441304D01*
X-2025324Y441564D01*
X-2024934Y441304D01*
Y440784D01*
X-2025324Y440524D01*
G01Y447544D02*
X-2025714Y447804D01*
Y448324D01*
X-2025324Y448584D01*
X-2024934Y448324D01*
Y447804D01*
X-2025324Y447544D01*
G01X-2132724Y1243044D02*
Y1258644D01*
X-2135064Y1255524D01*
G01Y1243044D02*
X-2130384D01*
G01X-2114824Y1242524D02*
X-2115214Y1242784D01*
Y1243304D01*
X-2114824Y1243564D01*
X-2114434Y1243304D01*
Y1242784D01*
X-2114824Y1242524D01*
G01X-2077854Y1250844D02*
X-2073954D01*
Y1246164D01*
X-2075124Y1244604D01*
X-2076489Y1243564D01*
X-2078439Y1243044D01*
X-2080389Y1243564D01*
X-2081754Y1244604D01*
X-2082924Y1246164D01*
X-2083704Y1247984D01*
X-2084094Y1250064D01*
Y1251884D01*
X-2083704Y1253444D01*
X-2082924Y1255264D01*
X-2081754Y1256824D01*
X-2080584Y1257864D01*
X-2079024Y1258644D01*
X-2077659D01*
X-2076099Y1258124D01*
X-2074929Y1257084D01*
G01X-2064049Y1250064D02*
X-2057809D01*
X-2058394Y1251884D01*
X-2059369Y1252924D01*
X-2060734Y1253444D01*
X-2062099Y1253184D01*
X-2063269Y1252404D01*
X-2064049Y1250584D01*
X-2064439Y1249024D01*
Y1247464D01*
X-2064049Y1245904D01*
X-2063074Y1244344D01*
X-2061904Y1243304D01*
X-2060539Y1243044D01*
X-2059174Y1243564D01*
X-2057809Y1245124D01*
G01X-2046539Y1243044D02*
Y1253444D01*
G01Y1250844D02*
X-2045759Y1252144D01*
X-2044589Y1253184D01*
X-2043029Y1253444D01*
X-2041664Y1253184D01*
X-2040494Y1252144D01*
X-2039909Y1250324D01*
Y1243044D01*
G01X-2028249Y1250064D02*
X-2022009D01*
X-2022594Y1251884D01*
X-2023569Y1252924D01*
X-2024934Y1253444D01*
X-2026299Y1253184D01*
X-2027469Y1252404D01*
X-2028249Y1250584D01*
X-2028639Y1249024D01*
Y1247464D01*
X-2028249Y1245904D01*
X-2027274Y1244344D01*
X-2026104Y1243304D01*
X-2024739Y1243044D01*
X-2023374Y1243564D01*
X-2022009Y1245124D01*
G01X-2010154Y1243044D02*
Y1253444D01*
G01Y1251364D02*
X-2009179Y1252404D01*
X-2008204Y1253184D01*
X-2006839Y1253444D01*
X-2005864Y1253184D01*
X-2004694Y1252404D01*
G01X-1986014Y1243044D02*
Y1253444D01*
G01Y1251624D02*
X-1986794Y1252664D01*
X-1987964Y1253184D01*
X-1989329Y1253444D01*
X-1990694Y1252924D01*
X-1991864Y1251884D01*
X-1992644Y1250324D01*
X-1993034Y1248244D01*
X-1992644Y1246164D01*
X-1991864Y1244604D01*
X-1990694Y1243564D01*
X-1989329Y1243044D01*
X-1987964Y1243304D01*
X-1986794Y1244084D01*
X-1986014Y1245124D01*
G01X-1971624Y1243044D02*
Y1258644D01*
G01X-1939724Y1243044D02*
Y1258644D01*
X-1934849D01*
X-1933289Y1257864D01*
X-1932314Y1256824D01*
X-1931924Y1254744D01*
X-1932314Y1252664D01*
X-1933484Y1251364D01*
X-1934849Y1250584D01*
X-1939724D01*
G01X-1934849D02*
X-1931924Y1243044D01*
G01X-1920849Y1250064D02*
X-1914609D01*
X-1915194Y1251884D01*
X-1916169Y1252924D01*
X-1917534Y1253444D01*
X-1918899Y1253184D01*
X-1920069Y1252404D01*
X-1920849Y1250584D01*
X-1921239Y1249024D01*
Y1247464D01*
X-1920849Y1245904D01*
X-1919874Y1244344D01*
X-1918704Y1243304D01*
X-1917339Y1243044D01*
X-1915974Y1243564D01*
X-1914609Y1245124D01*
G01X-1896514Y1237844D02*
Y1253444D01*
G01Y1251104D02*
X-1897489Y1252404D01*
X-1898659Y1253184D01*
X-1900024Y1253444D01*
X-1901194Y1253184D01*
X-1902559Y1251884D01*
X-1903339Y1250064D01*
X-1903534Y1248244D01*
X-1903339Y1246424D01*
X-1902559Y1244604D01*
X-1901194Y1243304D01*
X-1900024Y1243044D01*
X-1898659Y1243304D01*
X-1897489Y1244084D01*
X-1896514Y1245384D01*
G01X-1885439Y1253444D02*
Y1246164D01*
X-1884659Y1244344D01*
X-1883489Y1243304D01*
X-1882124Y1243044D01*
X-1880759Y1243304D01*
X-1879589Y1244344D01*
X-1878809Y1246164D01*
G01Y1243044D02*
Y1253444D01*
G01X-1864224D02*
Y1243044D01*
G01Y1257604D02*
X-1864614Y1257864D01*
Y1258384D01*
X-1864224Y1258644D01*
X-1863834Y1258384D01*
Y1257864D01*
X-1864224Y1257604D01*
G01X-1849054Y1243044D02*
Y1253444D01*
G01Y1251364D02*
X-1848079Y1252404D01*
X-1847104Y1253184D01*
X-1845739Y1253444D01*
X-1844764Y1253184D01*
X-1843594Y1252404D01*
G01X-1831349Y1250064D02*
X-1825109D01*
X-1825694Y1251884D01*
X-1826669Y1252924D01*
X-1828034Y1253444D01*
X-1829399Y1253184D01*
X-1830569Y1252404D01*
X-1831349Y1250584D01*
X-1831739Y1249024D01*
Y1247464D01*
X-1831349Y1245904D01*
X-1830374Y1244344D01*
X-1829204Y1243304D01*
X-1827839Y1243044D01*
X-1826474Y1243564D01*
X-1825109Y1245124D01*
G01X-1816374Y1243044D02*
Y1253444D01*
G01Y1250584D02*
X-1815789Y1251884D01*
X-1814814Y1252924D01*
X-1813449Y1253444D01*
X-1812084Y1252924D01*
X-1811109Y1251884D01*
X-1810524Y1250584D01*
Y1243044D01*
G01Y1250584D02*
X-1809939Y1251884D01*
X-1808964Y1252924D01*
X-1807599Y1253444D01*
X-1806234Y1252924D01*
X-1805259Y1251884D01*
X-1804674Y1250324D01*
Y1243044D01*
G01X-1795549Y1250064D02*
X-1789309D01*
X-1789894Y1251884D01*
X-1790869Y1252924D01*
X-1792234Y1253444D01*
X-1793599Y1253184D01*
X-1794769Y1252404D01*
X-1795549Y1250584D01*
X-1795939Y1249024D01*
Y1247464D01*
X-1795549Y1245904D01*
X-1794574Y1244344D01*
X-1793404Y1243304D01*
X-1792039Y1243044D01*
X-1790674Y1243564D01*
X-1789309Y1245124D01*
G01X-1778039Y1243044D02*
Y1253444D01*
G01Y1250844D02*
X-1777259Y1252144D01*
X-1776089Y1253184D01*
X-1774529Y1253444D01*
X-1773164Y1253184D01*
X-1771994Y1252144D01*
X-1771409Y1250324D01*
Y1243044D01*
G01X-1756824Y1258644D02*
Y1243044D01*
G01X-1759554Y1253444D02*
X-1754094D01*
G01X-1738924Y1242524D02*
X-1739314Y1242784D01*
Y1243304D01*
X-1738924Y1243564D01*
X-1738534Y1243304D01*
Y1242784D01*
X-1738924Y1242524D01*
G01Y1249544D02*
X-1739314Y1249804D01*
Y1250324D01*
X-1738924Y1250584D01*
X-1738534Y1250324D01*
Y1249804D01*
X-1738924Y1249544D01*
G01X-2084819Y-1117376D02*
X-2083259Y-1118676D01*
X-2081504Y-1119456D01*
X-2079944D01*
X-2078384Y-1118676D01*
X-2077214Y-1117376D01*
X-2076629Y-1115556D01*
X-2077019Y-1113736D01*
X-2077994Y-1112176D01*
X-2079749Y-1111136D01*
X-2082089Y-1110616D01*
X-2083454Y-1109576D01*
X-2084039Y-1107756D01*
X-2083649Y-1105936D01*
X-2082674Y-1104636D01*
X-2081309Y-1103856D01*
X-2079944D01*
X-2078579Y-1104376D01*
X-2077409Y-1105676D01*
G01X-2065749Y-1112436D02*
X-2059509D01*
X-2060094Y-1110616D01*
X-2061069Y-1109576D01*
X-2062434Y-1109056D01*
X-2063799Y-1109316D01*
X-2064969Y-1110096D01*
X-2065749Y-1111916D01*
X-2066139Y-1113476D01*
Y-1115036D01*
X-2065749Y-1116596D01*
X-2064774Y-1118156D01*
X-2063604Y-1119196D01*
X-2062239Y-1119456D01*
X-2060874Y-1118936D01*
X-2059509Y-1117376D01*
G01X-2048239Y-1119456D02*
Y-1109056D01*
G01Y-1111656D02*
X-2047459Y-1110356D01*
X-2046289Y-1109316D01*
X-2044729Y-1109056D01*
X-2043364Y-1109316D01*
X-2042194Y-1110356D01*
X-2041609Y-1112176D01*
Y-1119456D01*
G01X-2023514Y-1103856D02*
Y-1119456D01*
G01Y-1117116D02*
X-2024294Y-1118416D01*
X-2025464Y-1119196D01*
X-2026829Y-1119456D01*
X-2028389Y-1118936D01*
X-2029559Y-1117636D01*
X-2030339Y-1116076D01*
X-2030534Y-1114256D01*
X-2030339Y-1112436D01*
X-2029559Y-1110876D01*
X-2028389Y-1109576D01*
X-2026829Y-1109056D01*
X-2025464Y-1109316D01*
X-2024489Y-1109836D01*
X-2023514Y-1110876D01*
G01X-1994149Y-1117636D02*
X-1993174Y-1118676D01*
X-1991809Y-1119456D01*
X-1990639D01*
X-1989469Y-1118936D01*
X-1988689Y-1118156D01*
X-1988299Y-1117116D01*
X-1988494Y-1115556D01*
X-1989274Y-1114776D01*
X-1992784Y-1113216D01*
X-1993564Y-1111396D01*
X-1993174Y-1110096D01*
X-1992394Y-1109316D01*
X-1991224Y-1109056D01*
X-1990054Y-1109316D01*
X-1988884Y-1110096D01*
G01X-1973324Y-1119456D02*
X-1974494Y-1119196D01*
X-1975664Y-1118156D01*
X-1976444Y-1116336D01*
X-1976834Y-1114256D01*
X-1976444Y-1112176D01*
X-1975664Y-1110356D01*
X-1974494Y-1109316D01*
X-1973324Y-1109056D01*
X-1972154Y-1109316D01*
X-1970984Y-1110356D01*
X-1970204Y-1112176D01*
X-1970009Y-1114256D01*
X-1970204Y-1116336D01*
X-1970984Y-1118156D01*
X-1972154Y-1119196D01*
X-1973324Y-1119456D01*
G01X-1956594D02*
Y-1106196D01*
X-1956204Y-1104896D01*
X-1955424Y-1104116D01*
X-1954254Y-1103856D01*
X-1953084Y-1104376D01*
X-1952499Y-1105676D01*
G01X-1954839Y-1110096D02*
X-1958739D01*
G01X-1937524Y-1103856D02*
Y-1119456D01*
G01X-1940254Y-1109056D02*
X-1934794D01*
G01X-1898604Y-1110356D02*
X-1899969Y-1109316D01*
X-1901139Y-1109056D01*
X-1902699Y-1109576D01*
X-1903869Y-1110616D01*
X-1904649Y-1112436D01*
X-1904844Y-1114256D01*
X-1904649Y-1116076D01*
X-1903869Y-1117636D01*
X-1902699Y-1118936D01*
X-1901139Y-1119456D01*
X-1899774Y-1118936D01*
X-1898604Y-1117896D01*
G01X-1883824Y-1119456D02*
X-1884994Y-1119196D01*
X-1886164Y-1118156D01*
X-1886944Y-1116336D01*
X-1887334Y-1114256D01*
X-1886944Y-1112176D01*
X-1886164Y-1110356D01*
X-1884994Y-1109316D01*
X-1883824Y-1109056D01*
X-1882654Y-1109316D01*
X-1881484Y-1110356D01*
X-1880704Y-1112176D01*
X-1880509Y-1114256D01*
X-1880704Y-1116336D01*
X-1881484Y-1118156D01*
X-1882654Y-1119196D01*
X-1883824Y-1119456D01*
G01X-1869434Y-1124656D02*
Y-1109056D01*
G01Y-1111396D02*
X-1868459Y-1110096D01*
X-1867484Y-1109316D01*
X-1865924Y-1109056D01*
X-1864559Y-1109316D01*
X-1863194Y-1110616D01*
X-1862609Y-1112436D01*
X-1862414Y-1114256D01*
X-1862609Y-1116076D01*
X-1863194Y-1117896D01*
X-1864364Y-1118936D01*
X-1865924Y-1119456D01*
X-1867289Y-1119196D01*
X-1868654Y-1118416D01*
X-1869434Y-1117376D01*
G01X-1852119Y-1124136D02*
X-1850949Y-1124656D01*
X-1849389Y-1124136D01*
X-1848414Y-1123096D01*
X-1847634Y-1121796D01*
X-1846464Y-1117636D01*
X-1843929Y-1109056D01*
G01X-1850169D02*
X-1846464Y-1117636D01*
G01X-1812224Y-1103856D02*
Y-1119456D01*
G01X-1814954Y-1109056D02*
X-1809494D01*
G01X-1794324Y-1119456D02*
X-1795494Y-1119196D01*
X-1796664Y-1118156D01*
X-1797444Y-1116336D01*
X-1797834Y-1114256D01*
X-1797444Y-1112176D01*
X-1796664Y-1110356D01*
X-1795494Y-1109316D01*
X-1794324Y-1109056D01*
X-1793154Y-1109316D01*
X-1791984Y-1110356D01*
X-1791204Y-1112176D01*
X-1791009Y-1114256D01*
X-1791204Y-1116336D01*
X-1791984Y-1118156D01*
X-1793154Y-1119196D01*
X-1794324Y-1119456D01*
G01X-1757354Y-1111656D02*
X-1753454D01*
Y-1116336D01*
X-1754624Y-1117896D01*
X-1755989Y-1118936D01*
X-1757939Y-1119456D01*
X-1759889Y-1118936D01*
X-1761254Y-1117896D01*
X-1762424Y-1116336D01*
X-1763204Y-1114516D01*
X-1763594Y-1112436D01*
Y-1110616D01*
X-1763204Y-1109056D01*
X-1762424Y-1107236D01*
X-1761254Y-1105676D01*
X-1760084Y-1104636D01*
X-1758524Y-1103856D01*
X-1757159D01*
X-1755599Y-1104376D01*
X-1754429Y-1105416D01*
G01X-1744914Y-1119456D02*
Y-1103856D01*
X-1741014D01*
X-1739454Y-1104636D01*
X-1738284Y-1105676D01*
X-1737309Y-1107236D01*
X-1736529Y-1109056D01*
X-1736334Y-1111656D01*
X-1736529Y-1114256D01*
X-1737309Y-1116076D01*
X-1738284Y-1117636D01*
X-1739454Y-1118676D01*
X-1741014Y-1119456D01*
X-1744914D01*
G01X-1726819Y-1117376D02*
X-1725259Y-1118676D01*
X-1723504Y-1119456D01*
X-1721944D01*
X-1720384Y-1118676D01*
X-1719214Y-1117376D01*
X-1718629Y-1115556D01*
X-1719019Y-1113736D01*
X-1719994Y-1112176D01*
X-1721749Y-1111136D01*
X-1724089Y-1110616D01*
X-1725454Y-1109576D01*
X-1726039Y-1107756D01*
X-1725649Y-1105936D01*
X-1724674Y-1104636D01*
X-1723309Y-1103856D01*
X-1721944D01*
X-1720579Y-1104376D01*
X-1719409Y-1105676D01*
G01X-1689849Y-1112436D02*
X-1683609D01*
X-1684194Y-1110616D01*
X-1685169Y-1109576D01*
X-1686534Y-1109056D01*
X-1687899Y-1109316D01*
X-1689069Y-1110096D01*
X-1689849Y-1111916D01*
X-1690239Y-1113476D01*
Y-1115036D01*
X-1689849Y-1116596D01*
X-1688874Y-1118156D01*
X-1687704Y-1119196D01*
X-1686339Y-1119456D01*
X-1684974Y-1118936D01*
X-1683609Y-1117376D01*
G01X-1672339Y-1119456D02*
Y-1109056D01*
G01Y-1111656D02*
X-1671559Y-1110356D01*
X-1670389Y-1109316D01*
X-1668829Y-1109056D01*
X-1667464Y-1109316D01*
X-1666294Y-1110356D01*
X-1665709Y-1112176D01*
Y-1119456D01*
G01X-1653854Y-1123356D02*
X-1652489Y-1124396D01*
X-1650929Y-1124656D01*
X-1649564Y-1124396D01*
X-1648394Y-1123096D01*
X-1647614Y-1121276D01*
Y-1109056D01*
G01Y-1111136D02*
X-1648394Y-1110096D01*
X-1649564Y-1109316D01*
X-1650929Y-1109056D01*
X-1652489Y-1109576D01*
X-1653464Y-1110616D01*
X-1654244Y-1112436D01*
X-1654634Y-1114256D01*
X-1654439Y-1115816D01*
X-1653659Y-1117636D01*
X-1652489Y-1118936D01*
X-1650929Y-1119456D01*
X-1649759Y-1119196D01*
X-1648394Y-1118156D01*
X-1647614Y-1117116D01*
G01X-1633224Y-1109056D02*
Y-1119456D01*
G01Y-1104896D02*
X-1633614Y-1104636D01*
Y-1104116D01*
X-1633224Y-1103856D01*
X-1632834Y-1104116D01*
Y-1104636D01*
X-1633224Y-1104896D01*
G01X-1618639Y-1119456D02*
Y-1109056D01*
G01Y-1111656D02*
X-1617859Y-1110356D01*
X-1616689Y-1109316D01*
X-1615129Y-1109056D01*
X-1613764Y-1109316D01*
X-1612594Y-1110356D01*
X-1612009Y-1112176D01*
Y-1119456D01*
G01X-1600349Y-1112436D02*
X-1594109D01*
X-1594694Y-1110616D01*
X-1595669Y-1109576D01*
X-1597034Y-1109056D01*
X-1598399Y-1109316D01*
X-1599569Y-1110096D01*
X-1600349Y-1111916D01*
X-1600739Y-1113476D01*
Y-1115036D01*
X-1600349Y-1116596D01*
X-1599374Y-1118156D01*
X-1598204Y-1119196D01*
X-1596839Y-1119456D01*
X-1595474Y-1118936D01*
X-1594109Y-1117376D01*
G01X-1582449Y-1112436D02*
X-1576209D01*
X-1576794Y-1110616D01*
X-1577769Y-1109576D01*
X-1579134Y-1109056D01*
X-1580499Y-1109316D01*
X-1581669Y-1110096D01*
X-1582449Y-1111916D01*
X-1582839Y-1113476D01*
Y-1115036D01*
X-1582449Y-1116596D01*
X-1581474Y-1118156D01*
X-1580304Y-1119196D01*
X-1578939Y-1119456D01*
X-1577574Y-1118936D01*
X-1576209Y-1117376D01*
G01X-1564354Y-1119456D02*
Y-1109056D01*
G01Y-1111136D02*
X-1563379Y-1110096D01*
X-1562404Y-1109316D01*
X-1561039Y-1109056D01*
X-1560064Y-1109316D01*
X-1558894Y-1110096D01*
G01X-1544114Y-1122316D02*
X-1543334Y-1118936D01*
G01X-1512799Y-1109056D02*
X-1510459Y-1119456D01*
X-1507924Y-1109056D01*
X-1505389Y-1119456D01*
X-1503049Y-1109056D01*
G01X-1493339Y-1119456D02*
Y-1103856D01*
G01Y-1111396D02*
X-1492364Y-1110096D01*
X-1491389Y-1109316D01*
X-1489829Y-1109056D01*
X-1488659Y-1109316D01*
X-1487294Y-1110356D01*
X-1486709Y-1111916D01*
Y-1119456D01*
G01X-1472124D02*
X-1473294Y-1119196D01*
X-1474464Y-1118156D01*
X-1475244Y-1116336D01*
X-1475634Y-1114256D01*
X-1475244Y-1112176D01*
X-1474464Y-1110356D01*
X-1473294Y-1109316D01*
X-1472124Y-1109056D01*
X-1470954Y-1109316D01*
X-1469784Y-1110356D01*
X-1469004Y-1112176D01*
X-1468809Y-1114256D01*
X-1469004Y-1116336D01*
X-1469784Y-1118156D01*
X-1470954Y-1119196D01*
X-1472124Y-1119456D01*
G01X-1439054D02*
Y-1109056D01*
G01Y-1111136D02*
X-1438079Y-1110096D01*
X-1437104Y-1109316D01*
X-1435739Y-1109056D01*
X-1434764Y-1109316D01*
X-1433594Y-1110096D01*
G01X-1421349Y-1112436D02*
X-1415109D01*
X-1415694Y-1110616D01*
X-1416669Y-1109576D01*
X-1418034Y-1109056D01*
X-1419399Y-1109316D01*
X-1420569Y-1110096D01*
X-1421349Y-1111916D01*
X-1421739Y-1113476D01*
Y-1115036D01*
X-1421349Y-1116596D01*
X-1420374Y-1118156D01*
X-1419204Y-1119196D01*
X-1417839Y-1119456D01*
X-1416474Y-1118936D01*
X-1415109Y-1117376D01*
G01X-1400524Y-1119456D02*
Y-1103856D01*
G01X-1385549Y-1112436D02*
X-1379309D01*
X-1379894Y-1110616D01*
X-1380869Y-1109576D01*
X-1382234Y-1109056D01*
X-1383599Y-1109316D01*
X-1384769Y-1110096D01*
X-1385549Y-1111916D01*
X-1385939Y-1113476D01*
Y-1115036D01*
X-1385549Y-1116596D01*
X-1384574Y-1118156D01*
X-1383404Y-1119196D01*
X-1382039Y-1119456D01*
X-1380674Y-1118936D01*
X-1379309Y-1117376D01*
G01X-1361214Y-1119456D02*
Y-1109056D01*
G01Y-1110876D02*
X-1361994Y-1109836D01*
X-1363164Y-1109316D01*
X-1364529Y-1109056D01*
X-1365894Y-1109576D01*
X-1367064Y-1110616D01*
X-1367844Y-1112176D01*
X-1368234Y-1114256D01*
X-1367844Y-1116336D01*
X-1367064Y-1117896D01*
X-1365894Y-1118936D01*
X-1364529Y-1119456D01*
X-1363164Y-1119196D01*
X-1361994Y-1118416D01*
X-1361214Y-1117376D01*
G01X-1349749Y-1117636D02*
X-1348774Y-1118676D01*
X-1347409Y-1119456D01*
X-1346239D01*
X-1345069Y-1118936D01*
X-1344289Y-1118156D01*
X-1343899Y-1117116D01*
X-1344094Y-1115556D01*
X-1344874Y-1114776D01*
X-1348384Y-1113216D01*
X-1349164Y-1111396D01*
X-1348774Y-1110096D01*
X-1347994Y-1109316D01*
X-1346824Y-1109056D01*
X-1345654Y-1109316D01*
X-1344484Y-1110096D01*
G01X-1331849Y-1112436D02*
X-1325609D01*
X-1326194Y-1110616D01*
X-1327169Y-1109576D01*
X-1328534Y-1109056D01*
X-1329899Y-1109316D01*
X-1331069Y-1110096D01*
X-1331849Y-1111916D01*
X-1332239Y-1113476D01*
Y-1115036D01*
X-1331849Y-1116596D01*
X-1330874Y-1118156D01*
X-1329704Y-1119196D01*
X-1328339Y-1119456D01*
X-1326974Y-1118936D01*
X-1325609Y-1117376D01*
G01X-1291954Y-1111656D02*
X-1288054D01*
Y-1116336D01*
X-1289224Y-1117896D01*
X-1290589Y-1118936D01*
X-1292539Y-1119456D01*
X-1294489Y-1118936D01*
X-1295854Y-1117896D01*
X-1297024Y-1116336D01*
X-1297804Y-1114516D01*
X-1298194Y-1112436D01*
Y-1110616D01*
X-1297804Y-1109056D01*
X-1297024Y-1107236D01*
X-1295854Y-1105676D01*
X-1294684Y-1104636D01*
X-1293124Y-1103856D01*
X-1291759D01*
X-1290199Y-1104376D01*
X-1289029Y-1105416D01*
G01X-1278149Y-1112436D02*
X-1271909D01*
X-1272494Y-1110616D01*
X-1273469Y-1109576D01*
X-1274834Y-1109056D01*
X-1276199Y-1109316D01*
X-1277369Y-1110096D01*
X-1278149Y-1111916D01*
X-1278539Y-1113476D01*
Y-1115036D01*
X-1278149Y-1116596D01*
X-1277174Y-1118156D01*
X-1276004Y-1119196D01*
X-1274639Y-1119456D01*
X-1273274Y-1118936D01*
X-1271909Y-1117376D01*
G01X-1260054Y-1119456D02*
Y-1109056D01*
G01Y-1111136D02*
X-1259079Y-1110096D01*
X-1258104Y-1109316D01*
X-1256739Y-1109056D01*
X-1255764Y-1109316D01*
X-1254594Y-1110096D01*
G01X-1242934Y-1119456D02*
Y-1103856D01*
G01Y-1111656D02*
X-1241959Y-1110096D01*
X-1240789Y-1109316D01*
X-1239619Y-1109056D01*
X-1237864Y-1109576D01*
X-1236694Y-1110616D01*
X-1235914Y-1112436D01*
Y-1114516D01*
X-1236304Y-1116596D01*
X-1237084Y-1118156D01*
X-1238449Y-1119196D01*
X-1239619Y-1119456D01*
X-1240789Y-1119196D01*
X-1241959Y-1118416D01*
X-1242934Y-1117116D01*
G01X-1224449Y-1112436D02*
X-1218209D01*
X-1218794Y-1110616D01*
X-1219769Y-1109576D01*
X-1221134Y-1109056D01*
X-1222499Y-1109316D01*
X-1223669Y-1110096D01*
X-1224449Y-1111916D01*
X-1224839Y-1113476D01*
Y-1115036D01*
X-1224449Y-1116596D01*
X-1223474Y-1118156D01*
X-1222304Y-1119196D01*
X-1220939Y-1119456D01*
X-1219574Y-1118936D01*
X-1218209Y-1117376D01*
G01X-1206354Y-1119456D02*
Y-1109056D01*
G01Y-1111136D02*
X-1205379Y-1110096D01*
X-1204404Y-1109316D01*
X-1203039Y-1109056D01*
X-1202064Y-1109316D01*
X-1200894Y-1110096D01*
G01X-1171334Y-1124656D02*
Y-1109056D01*
G01Y-1111396D02*
X-1170359Y-1110096D01*
X-1169384Y-1109316D01*
X-1167824Y-1109056D01*
X-1166459Y-1109316D01*
X-1165094Y-1110616D01*
X-1164509Y-1112436D01*
X-1164314Y-1114256D01*
X-1164509Y-1116076D01*
X-1165094Y-1117896D01*
X-1166264Y-1118936D01*
X-1167824Y-1119456D01*
X-1169189Y-1119196D01*
X-1170554Y-1118416D01*
X-1171334Y-1117376D01*
G01X-1146414Y-1119456D02*
Y-1109056D01*
G01Y-1110876D02*
X-1147194Y-1109836D01*
X-1148364Y-1109316D01*
X-1149729Y-1109056D01*
X-1151094Y-1109576D01*
X-1152264Y-1110616D01*
X-1153044Y-1112176D01*
X-1153434Y-1114256D01*
X-1153044Y-1116336D01*
X-1152264Y-1117896D01*
X-1151094Y-1118936D01*
X-1149729Y-1119456D01*
X-1148364Y-1119196D01*
X-1147194Y-1118416D01*
X-1146414Y-1117376D01*
G01X-1128904Y-1110356D02*
X-1130269Y-1109316D01*
X-1131439Y-1109056D01*
X-1132999Y-1109576D01*
X-1134169Y-1110616D01*
X-1134949Y-1112436D01*
X-1135144Y-1114256D01*
X-1134949Y-1116076D01*
X-1134169Y-1117636D01*
X-1132999Y-1118936D01*
X-1131439Y-1119456D01*
X-1130074Y-1118936D01*
X-1128904Y-1117896D01*
G01X-1117439Y-1119456D02*
Y-1103856D01*
G01X-1111199Y-1109056D02*
X-1117439Y-1115036D01*
G01X-1114904Y-1112696D02*
X-1110809Y-1119456D01*
G01X-1092714D02*
Y-1109056D01*
G01Y-1110876D02*
X-1093494Y-1109836D01*
X-1094664Y-1109316D01*
X-1096029Y-1109056D01*
X-1097394Y-1109576D01*
X-1098564Y-1110616D01*
X-1099344Y-1112176D01*
X-1099734Y-1114256D01*
X-1099344Y-1116336D01*
X-1098564Y-1117896D01*
X-1097394Y-1118936D01*
X-1096029Y-1119456D01*
X-1094664Y-1119196D01*
X-1093494Y-1118416D01*
X-1092714Y-1117376D01*
G01X-1081054Y-1123356D02*
X-1079689Y-1124396D01*
X-1078129Y-1124656D01*
X-1076764Y-1124396D01*
X-1075594Y-1123096D01*
X-1074814Y-1121276D01*
Y-1109056D01*
G01Y-1111136D02*
X-1075594Y-1110096D01*
X-1076764Y-1109316D01*
X-1078129Y-1109056D01*
X-1079689Y-1109576D01*
X-1080664Y-1110616D01*
X-1081444Y-1112436D01*
X-1081834Y-1114256D01*
X-1081639Y-1115816D01*
X-1080859Y-1117636D01*
X-1079689Y-1118936D01*
X-1078129Y-1119456D01*
X-1076959Y-1119196D01*
X-1075594Y-1118156D01*
X-1074814Y-1117116D01*
G01X-1063349Y-1112436D02*
X-1057109D01*
X-1057694Y-1110616D01*
X-1058669Y-1109576D01*
X-1060034Y-1109056D01*
X-1061399Y-1109316D01*
X-1062569Y-1110096D01*
X-1063349Y-1111916D01*
X-1063739Y-1113476D01*
Y-1115036D01*
X-1063349Y-1116596D01*
X-1062374Y-1118156D01*
X-1061204Y-1119196D01*
X-1059839Y-1119456D01*
X-1058474Y-1118936D01*
X-1057109Y-1117376D01*
G01X-1042524Y-1119976D02*
X-1042914Y-1119716D01*
Y-1119196D01*
X-1042524Y-1118936D01*
X-1042134Y-1119196D01*
Y-1119716D01*
X-1042524Y-1119976D01*
G01X-1010819Y-1119456D02*
Y-1103856D01*
G01X-1002629D02*
Y-1119456D01*
G01Y-1111656D02*
X-1010819D01*
G01X-985314Y-1119456D02*
Y-1109056D01*
G01Y-1110876D02*
X-986094Y-1109836D01*
X-987264Y-1109316D01*
X-988629Y-1109056D01*
X-989994Y-1109576D01*
X-991164Y-1110616D01*
X-991944Y-1112176D01*
X-992334Y-1114256D01*
X-991944Y-1116336D01*
X-991164Y-1117896D01*
X-989994Y-1118936D01*
X-988629Y-1119456D01*
X-987264Y-1119196D01*
X-986094Y-1118416D01*
X-985314Y-1117376D01*
G01X-973654Y-1119456D02*
Y-1109056D01*
G01Y-1111136D02*
X-972679Y-1110096D01*
X-971704Y-1109316D01*
X-970339Y-1109056D01*
X-969364Y-1109316D01*
X-968194Y-1110096D01*
G01X-949514Y-1103856D02*
Y-1119456D01*
G01Y-1117116D02*
X-950294Y-1118416D01*
X-951464Y-1119196D01*
X-952829Y-1119456D01*
X-954389Y-1118936D01*
X-955559Y-1117636D01*
X-956339Y-1116076D01*
X-956534Y-1114256D01*
X-956339Y-1112436D01*
X-955559Y-1110876D01*
X-954389Y-1109576D01*
X-952829Y-1109056D01*
X-951464Y-1109316D01*
X-950489Y-1109836D01*
X-949514Y-1110876D01*
G01X-914104Y-1110356D02*
X-915469Y-1109316D01*
X-916639Y-1109056D01*
X-918199Y-1109576D01*
X-919369Y-1110616D01*
X-920149Y-1112436D01*
X-920344Y-1114256D01*
X-920149Y-1116076D01*
X-919369Y-1117636D01*
X-918199Y-1118936D01*
X-916639Y-1119456D01*
X-915274Y-1118936D01*
X-914104Y-1117896D01*
G01X-899324Y-1119456D02*
X-900494Y-1119196D01*
X-901664Y-1118156D01*
X-902444Y-1116336D01*
X-902834Y-1114256D01*
X-902444Y-1112176D01*
X-901664Y-1110356D01*
X-900494Y-1109316D01*
X-899324Y-1109056D01*
X-898154Y-1109316D01*
X-896984Y-1110356D01*
X-896204Y-1112176D01*
X-896009Y-1114256D01*
X-896204Y-1116336D01*
X-896984Y-1118156D01*
X-898154Y-1119196D01*
X-899324Y-1119456D01*
G01X-884934Y-1124656D02*
Y-1109056D01*
G01Y-1111396D02*
X-883959Y-1110096D01*
X-882984Y-1109316D01*
X-881424Y-1109056D01*
X-880059Y-1109316D01*
X-878694Y-1110616D01*
X-878109Y-1112436D01*
X-877914Y-1114256D01*
X-878109Y-1116076D01*
X-878694Y-1117896D01*
X-879864Y-1118936D01*
X-881424Y-1119456D01*
X-882789Y-1119196D01*
X-884154Y-1118416D01*
X-884934Y-1117376D01*
G01X-867619Y-1124136D02*
X-866449Y-1124656D01*
X-864889Y-1124136D01*
X-863914Y-1123096D01*
X-863134Y-1121796D01*
X-861964Y-1117636D01*
X-859429Y-1109056D01*
G01X-865669D02*
X-861964Y-1117636D01*
G01X-827724Y-1109056D02*
Y-1119456D01*
G01Y-1104896D02*
X-828114Y-1104636D01*
Y-1104116D01*
X-827724Y-1103856D01*
X-827334Y-1104116D01*
Y-1104636D01*
X-827724Y-1104896D01*
G01X-812749Y-1117636D02*
X-811774Y-1118676D01*
X-810409Y-1119456D01*
X-809239D01*
X-808069Y-1118936D01*
X-807289Y-1118156D01*
X-806899Y-1117116D01*
X-807094Y-1115556D01*
X-807874Y-1114776D01*
X-811384Y-1113216D01*
X-812164Y-1111396D01*
X-811774Y-1110096D01*
X-810994Y-1109316D01*
X-809824Y-1109056D01*
X-808654Y-1109316D01*
X-807484Y-1110096D01*
G01X-776754Y-1119456D02*
Y-1109056D01*
G01Y-1111136D02*
X-775779Y-1110096D01*
X-774804Y-1109316D01*
X-773439Y-1109056D01*
X-772464Y-1109316D01*
X-771294Y-1110096D01*
G01X-759049Y-1112436D02*
X-752809D01*
X-753394Y-1110616D01*
X-754369Y-1109576D01*
X-755734Y-1109056D01*
X-757099Y-1109316D01*
X-758269Y-1110096D01*
X-759049Y-1111916D01*
X-759439Y-1113476D01*
Y-1115036D01*
X-759049Y-1116596D01*
X-758074Y-1118156D01*
X-756904Y-1119196D01*
X-755539Y-1119456D01*
X-754174Y-1118936D01*
X-752809Y-1117376D01*
G01X-734714Y-1124656D02*
Y-1109056D01*
G01Y-1111396D02*
X-735689Y-1110096D01*
X-736859Y-1109316D01*
X-738224Y-1109056D01*
X-739394Y-1109316D01*
X-740759Y-1110616D01*
X-741539Y-1112436D01*
X-741734Y-1114256D01*
X-741539Y-1116076D01*
X-740759Y-1117896D01*
X-739394Y-1119196D01*
X-738224Y-1119456D01*
X-736859Y-1119196D01*
X-735689Y-1118416D01*
X-734714Y-1117116D01*
G01X-723639Y-1109056D02*
Y-1116336D01*
X-722859Y-1118156D01*
X-721689Y-1119196D01*
X-720324Y-1119456D01*
X-718959Y-1119196D01*
X-717789Y-1118156D01*
X-717009Y-1116336D01*
G01Y-1119456D02*
Y-1109056D01*
G01X-702424D02*
Y-1119456D01*
G01Y-1104896D02*
X-702814Y-1104636D01*
Y-1104116D01*
X-702424Y-1103856D01*
X-702034Y-1104116D01*
Y-1104636D01*
X-702424Y-1104896D01*
G01X-687254Y-1119456D02*
Y-1109056D01*
G01Y-1111136D02*
X-686279Y-1110096D01*
X-685304Y-1109316D01*
X-683939Y-1109056D01*
X-682964Y-1109316D01*
X-681794Y-1110096D01*
G01X-669549Y-1112436D02*
X-663309D01*
X-663894Y-1110616D01*
X-664869Y-1109576D01*
X-666234Y-1109056D01*
X-667599Y-1109316D01*
X-668769Y-1110096D01*
X-669549Y-1111916D01*
X-669939Y-1113476D01*
Y-1115036D01*
X-669549Y-1116596D01*
X-668574Y-1118156D01*
X-667404Y-1119196D01*
X-666039Y-1119456D01*
X-664674Y-1118936D01*
X-663309Y-1117376D01*
G01X-645214Y-1103856D02*
Y-1119456D01*
G01Y-1117116D02*
X-645994Y-1118416D01*
X-647164Y-1119196D01*
X-648529Y-1119456D01*
X-650089Y-1118936D01*
X-651259Y-1117636D01*
X-652039Y-1116076D01*
X-652234Y-1114256D01*
X-652039Y-1112436D01*
X-651259Y-1110876D01*
X-650089Y-1109576D01*
X-648529Y-1109056D01*
X-647164Y-1109316D01*
X-646189Y-1109836D01*
X-645214Y-1110876D01*
G01X-612924Y-1109056D02*
Y-1119456D01*
G01Y-1104896D02*
X-613314Y-1104636D01*
Y-1104116D01*
X-612924Y-1103856D01*
X-612534Y-1104116D01*
Y-1104636D01*
X-612924Y-1104896D01*
G01X-598339Y-1119456D02*
Y-1109056D01*
G01Y-1111656D02*
X-597559Y-1110356D01*
X-596389Y-1109316D01*
X-594829Y-1109056D01*
X-593464Y-1109316D01*
X-592294Y-1110356D01*
X-591709Y-1112176D01*
Y-1119456D01*
G01X-555714Y-1103856D02*
Y-1119456D01*
G01Y-1117116D02*
X-556494Y-1118416D01*
X-557664Y-1119196D01*
X-559029Y-1119456D01*
X-560589Y-1118936D01*
X-561759Y-1117636D01*
X-562539Y-1116076D01*
X-562734Y-1114256D01*
X-562539Y-1112436D01*
X-561759Y-1110876D01*
X-560589Y-1109576D01*
X-559029Y-1109056D01*
X-557664Y-1109316D01*
X-556689Y-1109836D01*
X-555714Y-1110876D01*
G01X-544249Y-1112436D02*
X-538009D01*
X-538594Y-1110616D01*
X-539569Y-1109576D01*
X-540934Y-1109056D01*
X-542299Y-1109316D01*
X-543469Y-1110096D01*
X-544249Y-1111916D01*
X-544639Y-1113476D01*
Y-1115036D01*
X-544249Y-1116596D01*
X-543274Y-1118156D01*
X-542104Y-1119196D01*
X-540739Y-1119456D01*
X-539374Y-1118936D01*
X-538009Y-1117376D01*
G01X-523424Y-1119456D02*
Y-1103856D01*
G01X-505524Y-1109056D02*
Y-1119456D01*
G01Y-1104896D02*
X-505914Y-1104636D01*
Y-1104116D01*
X-505524Y-1103856D01*
X-505134Y-1104116D01*
Y-1104636D01*
X-505524Y-1104896D01*
G01X-491134Y-1109056D02*
X-487624Y-1119456D01*
X-484114Y-1109056D01*
G01X-472649Y-1112436D02*
X-466409D01*
X-466994Y-1110616D01*
X-467969Y-1109576D01*
X-469334Y-1109056D01*
X-470699Y-1109316D01*
X-471869Y-1110096D01*
X-472649Y-1111916D01*
X-473039Y-1113476D01*
Y-1115036D01*
X-472649Y-1116596D01*
X-471674Y-1118156D01*
X-470504Y-1119196D01*
X-469139Y-1119456D01*
X-467774Y-1118936D01*
X-466409Y-1117376D01*
G01X-454554Y-1119456D02*
Y-1109056D01*
G01Y-1111136D02*
X-453579Y-1110096D01*
X-452604Y-1109316D01*
X-451239Y-1109056D01*
X-450264Y-1109316D01*
X-449094Y-1110096D01*
G01X-438019Y-1124136D02*
X-436849Y-1124656D01*
X-435289Y-1124136D01*
X-434314Y-1123096D01*
X-433534Y-1121796D01*
X-432364Y-1117636D01*
X-429829Y-1109056D01*
G01X-436069D02*
X-432364Y-1117636D01*
G01X-400854Y-1119456D02*
Y-1109056D01*
G01Y-1111136D02*
X-399879Y-1110096D01*
X-398904Y-1109316D01*
X-397539Y-1109056D01*
X-396564Y-1109316D01*
X-395394Y-1110096D01*
G01X-383149Y-1112436D02*
X-376909D01*
X-377494Y-1110616D01*
X-378469Y-1109576D01*
X-379834Y-1109056D01*
X-381199Y-1109316D01*
X-382369Y-1110096D01*
X-383149Y-1111916D01*
X-383539Y-1113476D01*
Y-1115036D01*
X-383149Y-1116596D01*
X-382174Y-1118156D01*
X-381004Y-1119196D01*
X-379639Y-1119456D01*
X-378274Y-1118936D01*
X-376909Y-1117376D01*
G01X-365834Y-1124656D02*
Y-1109056D01*
G01Y-1111396D02*
X-364859Y-1110096D01*
X-363884Y-1109316D01*
X-362324Y-1109056D01*
X-360959Y-1109316D01*
X-359594Y-1110616D01*
X-359009Y-1112436D01*
X-358814Y-1114256D01*
X-359009Y-1116076D01*
X-359594Y-1117896D01*
X-360764Y-1118936D01*
X-362324Y-1119456D01*
X-363689Y-1119196D01*
X-365054Y-1118416D01*
X-365834Y-1117376D01*
G01X-344424Y-1119456D02*
X-345594Y-1119196D01*
X-346764Y-1118156D01*
X-347544Y-1116336D01*
X-347934Y-1114256D01*
X-347544Y-1112176D01*
X-346764Y-1110356D01*
X-345594Y-1109316D01*
X-344424Y-1109056D01*
X-343254Y-1109316D01*
X-342084Y-1110356D01*
X-341304Y-1112176D01*
X-341109Y-1114256D01*
X-341304Y-1116336D01*
X-342084Y-1118156D01*
X-343254Y-1119196D01*
X-344424Y-1119456D01*
G01X-329254D02*
Y-1109056D01*
G01Y-1111136D02*
X-328279Y-1110096D01*
X-327304Y-1109316D01*
X-325939Y-1109056D01*
X-324964Y-1109316D01*
X-323794Y-1110096D01*
G01X-308624Y-1103856D02*
Y-1119456D01*
G01X-311354Y-1109056D02*
X-305894D01*
G01X-290724Y-1119976D02*
X-291114Y-1119716D01*
Y-1119196D01*
X-290724Y-1118936D01*
X-290334Y-1119196D01*
Y-1119716D01*
X-290724Y-1119976D01*
G01X-2084429Y-1031456D02*
Y-1015856D01*
X-2077019D01*
G01X-2079749Y-1023396D02*
X-2084429D01*
G01X-2062824Y-1031456D02*
X-2063994Y-1031196D01*
X-2065164Y-1030156D01*
X-2065944Y-1028336D01*
X-2066334Y-1026256D01*
X-2065944Y-1024176D01*
X-2065164Y-1022356D01*
X-2063994Y-1021316D01*
X-2062824Y-1021056D01*
X-2061654Y-1021316D01*
X-2060484Y-1022356D01*
X-2059704Y-1024176D01*
X-2059509Y-1026256D01*
X-2059704Y-1028336D01*
X-2060484Y-1030156D01*
X-2061654Y-1031196D01*
X-2062824Y-1031456D01*
G01X-2047654D02*
Y-1021056D01*
G01Y-1023136D02*
X-2046679Y-1022096D01*
X-2045704Y-1021316D01*
X-2044339Y-1021056D01*
X-2043364Y-1021316D01*
X-2042194Y-1022096D01*
G01X-2005614Y-1031456D02*
Y-1021056D01*
G01Y-1022876D02*
X-2006394Y-1021836D01*
X-2007564Y-1021316D01*
X-2008929Y-1021056D01*
X-2010294Y-1021576D01*
X-2011464Y-1022616D01*
X-2012244Y-1024176D01*
X-2012634Y-1026256D01*
X-2012244Y-1028336D01*
X-2011464Y-1029896D01*
X-2010294Y-1030936D01*
X-2008929Y-1031456D01*
X-2007564Y-1031196D01*
X-2006394Y-1030416D01*
X-2005614Y-1029376D01*
G01X-1991224Y-1031456D02*
Y-1015856D01*
G01X-1973324Y-1031456D02*
Y-1015856D01*
G01X-1940449Y-1029636D02*
X-1939474Y-1030676D01*
X-1938109Y-1031456D01*
X-1936939D01*
X-1935769Y-1030936D01*
X-1934989Y-1030156D01*
X-1934599Y-1029116D01*
X-1934794Y-1027556D01*
X-1935574Y-1026776D01*
X-1939084Y-1025216D01*
X-1939864Y-1023396D01*
X-1939474Y-1022096D01*
X-1938694Y-1021316D01*
X-1937524Y-1021056D01*
X-1936354Y-1021316D01*
X-1935184Y-1022096D01*
G01X-1922939Y-1031456D02*
Y-1015856D01*
G01Y-1023396D02*
X-1921964Y-1022096D01*
X-1920989Y-1021316D01*
X-1919429Y-1021056D01*
X-1918259Y-1021316D01*
X-1916894Y-1022356D01*
X-1916309Y-1023916D01*
Y-1031456D01*
G01X-1901724Y-1021056D02*
Y-1031456D01*
G01Y-1016896D02*
X-1902114Y-1016636D01*
Y-1016116D01*
X-1901724Y-1015856D01*
X-1901334Y-1016116D01*
Y-1016636D01*
X-1901724Y-1016896D01*
G01X-1887334Y-1036656D02*
Y-1021056D01*
G01Y-1023396D02*
X-1886359Y-1022096D01*
X-1885384Y-1021316D01*
X-1883824Y-1021056D01*
X-1882459Y-1021316D01*
X-1881094Y-1022616D01*
X-1880509Y-1024436D01*
X-1880314Y-1026256D01*
X-1880509Y-1028076D01*
X-1881094Y-1029896D01*
X-1882264Y-1030936D01*
X-1883824Y-1031456D01*
X-1885189Y-1031196D01*
X-1886554Y-1030416D01*
X-1887334Y-1029376D01*
G01X-1871774Y-1031456D02*
Y-1021056D01*
G01Y-1023916D02*
X-1871189Y-1022616D01*
X-1870214Y-1021576D01*
X-1868849Y-1021056D01*
X-1867484Y-1021576D01*
X-1866509Y-1022616D01*
X-1865924Y-1023916D01*
Y-1031456D01*
G01Y-1023916D02*
X-1865339Y-1022616D01*
X-1864364Y-1021576D01*
X-1862999Y-1021056D01*
X-1861634Y-1021576D01*
X-1860659Y-1022616D01*
X-1860074Y-1024176D01*
Y-1031456D01*
G01X-1850949Y-1024436D02*
X-1844709D01*
X-1845294Y-1022616D01*
X-1846269Y-1021576D01*
X-1847634Y-1021056D01*
X-1848999Y-1021316D01*
X-1850169Y-1022096D01*
X-1850949Y-1023916D01*
X-1851339Y-1025476D01*
Y-1027036D01*
X-1850949Y-1028596D01*
X-1849974Y-1030156D01*
X-1848804Y-1031196D01*
X-1847439Y-1031456D01*
X-1846074Y-1030936D01*
X-1844709Y-1029376D01*
G01X-1833439Y-1031456D02*
Y-1021056D01*
G01Y-1023656D02*
X-1832659Y-1022356D01*
X-1831489Y-1021316D01*
X-1829929Y-1021056D01*
X-1828564Y-1021316D01*
X-1827394Y-1022356D01*
X-1826809Y-1024176D01*
Y-1031456D01*
G01X-1812224Y-1015856D02*
Y-1031456D01*
G01X-1814954Y-1021056D02*
X-1809494D01*
G01X-1797249Y-1029636D02*
X-1796274Y-1030676D01*
X-1794909Y-1031456D01*
X-1793739D01*
X-1792569Y-1030936D01*
X-1791789Y-1030156D01*
X-1791399Y-1029116D01*
X-1791594Y-1027556D01*
X-1792374Y-1026776D01*
X-1795884Y-1025216D01*
X-1796664Y-1023396D01*
X-1796274Y-1022096D01*
X-1795494Y-1021316D01*
X-1794324Y-1021056D01*
X-1793154Y-1021316D01*
X-1791984Y-1022096D01*
G01X-1776814Y-1034316D02*
X-1776034Y-1030936D01*
G01X-1741794Y-1031456D02*
Y-1018196D01*
X-1741404Y-1016896D01*
X-1740624Y-1016116D01*
X-1739454Y-1015856D01*
X-1738284Y-1016376D01*
X-1737699Y-1017676D01*
G01X-1740039Y-1022096D02*
X-1743939D01*
G01X-1722724Y-1031456D02*
Y-1015856D01*
G01X-1701314Y-1031456D02*
Y-1021056D01*
G01Y-1022876D02*
X-1702094Y-1021836D01*
X-1703264Y-1021316D01*
X-1704629Y-1021056D01*
X-1705994Y-1021576D01*
X-1707164Y-1022616D01*
X-1707944Y-1024176D01*
X-1708334Y-1026256D01*
X-1707944Y-1028336D01*
X-1707164Y-1029896D01*
X-1705994Y-1030936D01*
X-1704629Y-1031456D01*
X-1703264Y-1031196D01*
X-1702094Y-1030416D01*
X-1701314Y-1029376D01*
G01X-1686924Y-1015856D02*
Y-1031456D01*
G01X-1689654Y-1021056D02*
X-1684194D01*
G01X-1672339Y-1031456D02*
Y-1021056D01*
G01Y-1023656D02*
X-1671559Y-1022356D01*
X-1670389Y-1021316D01*
X-1668829Y-1021056D01*
X-1667464Y-1021316D01*
X-1666294Y-1022356D01*
X-1665709Y-1024176D01*
Y-1031456D01*
G01X-1654049Y-1024436D02*
X-1647809D01*
X-1648394Y-1022616D01*
X-1649369Y-1021576D01*
X-1650734Y-1021056D01*
X-1652099Y-1021316D01*
X-1653269Y-1022096D01*
X-1654049Y-1023916D01*
X-1654439Y-1025476D01*
Y-1027036D01*
X-1654049Y-1028596D01*
X-1653074Y-1030156D01*
X-1651904Y-1031196D01*
X-1650539Y-1031456D01*
X-1649174Y-1030936D01*
X-1647809Y-1029376D01*
G01X-1636149Y-1029636D02*
X-1635174Y-1030676D01*
X-1633809Y-1031456D01*
X-1632639D01*
X-1631469Y-1030936D01*
X-1630689Y-1030156D01*
X-1630299Y-1029116D01*
X-1630494Y-1027556D01*
X-1631274Y-1026776D01*
X-1634784Y-1025216D01*
X-1635564Y-1023396D01*
X-1635174Y-1022096D01*
X-1634394Y-1021316D01*
X-1633224Y-1021056D01*
X-1632054Y-1021316D01*
X-1630884Y-1022096D01*
G01X-1618249Y-1029636D02*
X-1617274Y-1030676D01*
X-1615909Y-1031456D01*
X-1614739D01*
X-1613569Y-1030936D01*
X-1612789Y-1030156D01*
X-1612399Y-1029116D01*
X-1612594Y-1027556D01*
X-1613374Y-1026776D01*
X-1616884Y-1025216D01*
X-1617664Y-1023396D01*
X-1617274Y-1022096D01*
X-1616494Y-1021316D01*
X-1615324Y-1021056D01*
X-1614154Y-1021316D01*
X-1612984Y-1022096D01*
G01X-1576014Y-1015856D02*
Y-1031456D01*
G01Y-1029116D02*
X-1576794Y-1030416D01*
X-1577964Y-1031196D01*
X-1579329Y-1031456D01*
X-1580889Y-1030936D01*
X-1582059Y-1029636D01*
X-1582839Y-1028076D01*
X-1583034Y-1026256D01*
X-1582839Y-1024436D01*
X-1582059Y-1022876D01*
X-1580889Y-1021576D01*
X-1579329Y-1021056D01*
X-1577964Y-1021316D01*
X-1576989Y-1021836D01*
X-1576014Y-1022876D01*
G01X-1558114Y-1031456D02*
Y-1021056D01*
G01Y-1022876D02*
X-1558894Y-1021836D01*
X-1560064Y-1021316D01*
X-1561429Y-1021056D01*
X-1562794Y-1021576D01*
X-1563964Y-1022616D01*
X-1564744Y-1024176D01*
X-1565134Y-1026256D01*
X-1564744Y-1028336D01*
X-1563964Y-1029896D01*
X-1562794Y-1030936D01*
X-1561429Y-1031456D01*
X-1560064Y-1031196D01*
X-1558894Y-1030416D01*
X-1558114Y-1029376D01*
G01X-1543724Y-1015856D02*
Y-1031456D01*
G01X-1546454Y-1021056D02*
X-1540994D01*
G01X-1522314Y-1031456D02*
Y-1021056D01*
G01Y-1022876D02*
X-1523094Y-1021836D01*
X-1524264Y-1021316D01*
X-1525629Y-1021056D01*
X-1526994Y-1021576D01*
X-1528164Y-1022616D01*
X-1528944Y-1024176D01*
X-1529334Y-1026256D01*
X-1528944Y-1028336D01*
X-1528164Y-1029896D01*
X-1526994Y-1030936D01*
X-1525629Y-1031456D01*
X-1524264Y-1031196D01*
X-1523094Y-1030416D01*
X-1522314Y-1029376D01*
G01X-1490024Y-1021056D02*
Y-1031456D01*
G01Y-1016896D02*
X-1490414Y-1016636D01*
Y-1016116D01*
X-1490024Y-1015856D01*
X-1489634Y-1016116D01*
Y-1016636D01*
X-1490024Y-1016896D01*
G01X-1475049Y-1029636D02*
X-1474074Y-1030676D01*
X-1472709Y-1031456D01*
X-1471539D01*
X-1470369Y-1030936D01*
X-1469589Y-1030156D01*
X-1469199Y-1029116D01*
X-1469394Y-1027556D01*
X-1470174Y-1026776D01*
X-1473684Y-1025216D01*
X-1474464Y-1023396D01*
X-1474074Y-1022096D01*
X-1473294Y-1021316D01*
X-1472124Y-1021056D01*
X-1470954Y-1021316D01*
X-1469784Y-1022096D01*
G01X-1439054Y-1031456D02*
Y-1021056D01*
G01Y-1023136D02*
X-1438079Y-1022096D01*
X-1437104Y-1021316D01*
X-1435739Y-1021056D01*
X-1434764Y-1021316D01*
X-1433594Y-1022096D01*
G01X-1421349Y-1024436D02*
X-1415109D01*
X-1415694Y-1022616D01*
X-1416669Y-1021576D01*
X-1418034Y-1021056D01*
X-1419399Y-1021316D01*
X-1420569Y-1022096D01*
X-1421349Y-1023916D01*
X-1421739Y-1025476D01*
Y-1027036D01*
X-1421349Y-1028596D01*
X-1420374Y-1030156D01*
X-1419204Y-1031196D01*
X-1417839Y-1031456D01*
X-1416474Y-1030936D01*
X-1415109Y-1029376D01*
G01X-1397014Y-1036656D02*
Y-1021056D01*
G01Y-1023396D02*
X-1397989Y-1022096D01*
X-1399159Y-1021316D01*
X-1400524Y-1021056D01*
X-1401694Y-1021316D01*
X-1403059Y-1022616D01*
X-1403839Y-1024436D01*
X-1404034Y-1026256D01*
X-1403839Y-1028076D01*
X-1403059Y-1029896D01*
X-1401694Y-1031196D01*
X-1400524Y-1031456D01*
X-1399159Y-1031196D01*
X-1397989Y-1030416D01*
X-1397014Y-1029116D01*
G01X-1385939Y-1021056D02*
Y-1028336D01*
X-1385159Y-1030156D01*
X-1383989Y-1031196D01*
X-1382624Y-1031456D01*
X-1381259Y-1031196D01*
X-1380089Y-1030156D01*
X-1379309Y-1028336D01*
G01Y-1031456D02*
Y-1021056D01*
G01X-1364724D02*
Y-1031456D01*
G01Y-1016896D02*
X-1365114Y-1016636D01*
Y-1016116D01*
X-1364724Y-1015856D01*
X-1364334Y-1016116D01*
Y-1016636D01*
X-1364724Y-1016896D01*
G01X-1349554Y-1031456D02*
Y-1021056D01*
G01Y-1023136D02*
X-1348579Y-1022096D01*
X-1347604Y-1021316D01*
X-1346239Y-1021056D01*
X-1345264Y-1021316D01*
X-1344094Y-1022096D01*
G01X-1331849Y-1024436D02*
X-1325609D01*
X-1326194Y-1022616D01*
X-1327169Y-1021576D01*
X-1328534Y-1021056D01*
X-1329899Y-1021316D01*
X-1331069Y-1022096D01*
X-1331849Y-1023916D01*
X-1332239Y-1025476D01*
Y-1027036D01*
X-1331849Y-1028596D01*
X-1330874Y-1030156D01*
X-1329704Y-1031196D01*
X-1328339Y-1031456D01*
X-1326974Y-1030936D01*
X-1325609Y-1029376D01*
G01X-1307514Y-1015856D02*
Y-1031456D01*
G01Y-1029116D02*
X-1308294Y-1030416D01*
X-1309464Y-1031196D01*
X-1310829Y-1031456D01*
X-1312389Y-1030936D01*
X-1313559Y-1029636D01*
X-1314339Y-1028076D01*
X-1314534Y-1026256D01*
X-1314339Y-1024436D01*
X-1313559Y-1022876D01*
X-1312389Y-1021576D01*
X-1310829Y-1021056D01*
X-1309464Y-1021316D01*
X-1308489Y-1021836D01*
X-1307514Y-1022876D01*
G01X-1293124Y-1031976D02*
X-1293514Y-1031716D01*
Y-1031196D01*
X-1293124Y-1030936D01*
X-1292734Y-1031196D01*
Y-1031716D01*
X-1293124Y-1031976D01*
G01X-2080724Y-981856D02*
X-2082284Y-982376D01*
X-2083454Y-983676D01*
X-2084234Y-985236D01*
X-2084819Y-987316D01*
X-2085014Y-989656D01*
X-2084819Y-991996D01*
X-2084234Y-994076D01*
X-2083454Y-995636D01*
X-2082284Y-996936D01*
X-2080724Y-997456D01*
X-2079164Y-996936D01*
X-2077994Y-995636D01*
X-2077214Y-994076D01*
X-2076629Y-991996D01*
X-2076434Y-989656D01*
X-2076629Y-987316D01*
X-2077214Y-985236D01*
X-2077994Y-983676D01*
X-2079164Y-982376D01*
X-2080724Y-981856D01*
G01X-2062824Y-997976D02*
X-2063214Y-997716D01*
Y-997196D01*
X-2062824Y-996936D01*
X-2062434Y-997196D01*
Y-997716D01*
X-2062824Y-997976D01*
G01X-2044924Y-981856D02*
X-2046484Y-982376D01*
X-2047654Y-983676D01*
X-2048434Y-985236D01*
X-2049019Y-987316D01*
X-2049214Y-989656D01*
X-2049019Y-991996D01*
X-2048434Y-994076D01*
X-2047654Y-995636D01*
X-2046484Y-996936D01*
X-2044924Y-997456D01*
X-2043364Y-996936D01*
X-2042194Y-995636D01*
X-2041414Y-994076D01*
X-2040829Y-991996D01*
X-2040634Y-989656D01*
X-2040829Y-987316D01*
X-2041414Y-985236D01*
X-2042194Y-983676D01*
X-2043364Y-982376D01*
X-2044924Y-981856D01*
G01X-2027024D02*
X-2028584Y-982376D01*
X-2029754Y-983676D01*
X-2030534Y-985236D01*
X-2031119Y-987316D01*
X-2031314Y-989656D01*
X-2031119Y-991996D01*
X-2030534Y-994076D01*
X-2029754Y-995636D01*
X-2028584Y-996936D01*
X-2027024Y-997456D01*
X-2025464Y-996936D01*
X-2024294Y-995636D01*
X-2023514Y-994076D01*
X-2022929Y-991996D01*
X-2022734Y-989656D01*
X-2022929Y-987316D01*
X-2023514Y-985236D01*
X-2024294Y-983676D01*
X-2025464Y-982376D01*
X-2027024Y-981856D01*
G01X-2006784Y-997456D02*
Y-981856D01*
X-2013999Y-993036D01*
X-2004249D01*
G01X-1973324Y-987056D02*
Y-997456D01*
G01Y-982896D02*
X-1973714Y-982636D01*
Y-982116D01*
X-1973324Y-981856D01*
X-1972934Y-982116D01*
Y-982636D01*
X-1973324Y-982896D01*
G01X-1958739Y-997456D02*
Y-987056D01*
G01Y-989656D02*
X-1957959Y-988356D01*
X-1956789Y-987316D01*
X-1955229Y-987056D01*
X-1953864Y-987316D01*
X-1952694Y-988356D01*
X-1952109Y-990176D01*
Y-997456D01*
G01X-1934404Y-988356D02*
X-1935769Y-987316D01*
X-1936939Y-987056D01*
X-1938499Y-987576D01*
X-1939669Y-988616D01*
X-1940449Y-990436D01*
X-1940644Y-992256D01*
X-1940449Y-994076D01*
X-1939669Y-995636D01*
X-1938499Y-996936D01*
X-1936939Y-997456D01*
X-1935574Y-996936D01*
X-1934404Y-995896D01*
G01X-1922939Y-997456D02*
Y-981856D01*
G01Y-989396D02*
X-1921964Y-988096D01*
X-1920989Y-987316D01*
X-1919429Y-987056D01*
X-1918259Y-987316D01*
X-1916894Y-988356D01*
X-1916309Y-989916D01*
Y-997456D01*
G01X-1904649Y-990436D02*
X-1898409D01*
X-1898994Y-988616D01*
X-1899969Y-987576D01*
X-1901334Y-987056D01*
X-1902699Y-987316D01*
X-1903869Y-988096D01*
X-1904649Y-989916D01*
X-1905039Y-991476D01*
Y-993036D01*
X-1904649Y-994596D01*
X-1903674Y-996156D01*
X-1902504Y-997196D01*
X-1901139Y-997456D01*
X-1899774Y-996936D01*
X-1898409Y-995376D01*
G01X-1886749Y-995636D02*
X-1885774Y-996676D01*
X-1884409Y-997456D01*
X-1883239D01*
X-1882069Y-996936D01*
X-1881289Y-996156D01*
X-1880899Y-995116D01*
X-1881094Y-993556D01*
X-1881874Y-992776D01*
X-1885384Y-991216D01*
X-1886164Y-989396D01*
X-1885774Y-988096D01*
X-1884994Y-987316D01*
X-1883824Y-987056D01*
X-1882654Y-987316D01*
X-1881484Y-988096D01*
G01X-1848024Y-997456D02*
X-1849194Y-997196D01*
X-1850364Y-996156D01*
X-1851144Y-994336D01*
X-1851534Y-992256D01*
X-1851144Y-990176D01*
X-1850364Y-988356D01*
X-1849194Y-987316D01*
X-1848024Y-987056D01*
X-1846854Y-987316D01*
X-1845684Y-988356D01*
X-1844904Y-990176D01*
X-1844709Y-992256D01*
X-1844904Y-994336D01*
X-1845684Y-996156D01*
X-1846854Y-997196D01*
X-1848024Y-997456D01*
G01X-1831294D02*
Y-984196D01*
X-1830904Y-982896D01*
X-1830124Y-982116D01*
X-1828954Y-981856D01*
X-1827784Y-982376D01*
X-1827199Y-983676D01*
G01X-1829539Y-988096D02*
X-1833439D01*
G01X-1797834Y-1002656D02*
Y-987056D01*
G01Y-989396D02*
X-1796859Y-988096D01*
X-1795884Y-987316D01*
X-1794324Y-987056D01*
X-1792959Y-987316D01*
X-1791594Y-988616D01*
X-1791009Y-990436D01*
X-1790814Y-992256D01*
X-1791009Y-994076D01*
X-1791594Y-995896D01*
X-1792764Y-996936D01*
X-1794324Y-997456D01*
X-1795689Y-997196D01*
X-1797054Y-996416D01*
X-1797834Y-995376D01*
G01X-1776424Y-997456D02*
Y-981856D01*
G01X-1755014Y-997456D02*
Y-987056D01*
G01Y-988876D02*
X-1755794Y-987836D01*
X-1756964Y-987316D01*
X-1758329Y-987056D01*
X-1759694Y-987576D01*
X-1760864Y-988616D01*
X-1761644Y-990176D01*
X-1762034Y-992256D01*
X-1761644Y-994336D01*
X-1760864Y-995896D01*
X-1759694Y-996936D01*
X-1758329Y-997456D01*
X-1756964Y-997196D01*
X-1755794Y-996416D01*
X-1755014Y-995376D01*
G01X-1743939Y-997456D02*
Y-987056D01*
G01Y-989656D02*
X-1743159Y-988356D01*
X-1741989Y-987316D01*
X-1740429Y-987056D01*
X-1739064Y-987316D01*
X-1737894Y-988356D01*
X-1737309Y-990176D01*
Y-997456D01*
G01X-1719214D02*
Y-987056D01*
G01Y-988876D02*
X-1719994Y-987836D01*
X-1721164Y-987316D01*
X-1722529Y-987056D01*
X-1723894Y-987576D01*
X-1725064Y-988616D01*
X-1725844Y-990176D01*
X-1726234Y-992256D01*
X-1725844Y-994336D01*
X-1725064Y-995896D01*
X-1723894Y-996936D01*
X-1722529Y-997456D01*
X-1721164Y-997196D01*
X-1719994Y-996416D01*
X-1719214Y-995376D01*
G01X-1707554Y-997456D02*
Y-987056D01*
G01Y-989136D02*
X-1706579Y-988096D01*
X-1705604Y-987316D01*
X-1704239Y-987056D01*
X-1703264Y-987316D01*
X-1702094Y-988096D01*
G01X-1672534Y-987056D02*
X-1669024Y-997456D01*
X-1665514Y-987056D01*
G01X-1647614Y-997456D02*
Y-987056D01*
G01Y-988876D02*
X-1648394Y-987836D01*
X-1649564Y-987316D01*
X-1650929Y-987056D01*
X-1652294Y-987576D01*
X-1653464Y-988616D01*
X-1654244Y-990176D01*
X-1654634Y-992256D01*
X-1654244Y-994336D01*
X-1653464Y-995896D01*
X-1652294Y-996936D01*
X-1650929Y-997456D01*
X-1649564Y-997196D01*
X-1648394Y-996416D01*
X-1647614Y-995376D01*
G01X-1635954Y-997456D02*
Y-987056D01*
G01Y-989136D02*
X-1634979Y-988096D01*
X-1634004Y-987316D01*
X-1632639Y-987056D01*
X-1631664Y-987316D01*
X-1630494Y-988096D01*
G01X-1615324Y-987056D02*
Y-997456D01*
G01Y-982896D02*
X-1615714Y-982636D01*
Y-982116D01*
X-1615324Y-981856D01*
X-1614934Y-982116D01*
Y-982636D01*
X-1615324Y-982896D01*
G01X-1593914Y-997456D02*
Y-987056D01*
G01Y-988876D02*
X-1594694Y-987836D01*
X-1595864Y-987316D01*
X-1597229Y-987056D01*
X-1598594Y-987576D01*
X-1599764Y-988616D01*
X-1600544Y-990176D01*
X-1600934Y-992256D01*
X-1600544Y-994336D01*
X-1599764Y-995896D01*
X-1598594Y-996936D01*
X-1597229Y-997456D01*
X-1595864Y-997196D01*
X-1594694Y-996416D01*
X-1593914Y-995376D01*
G01X-1579524Y-981856D02*
Y-997456D01*
G01X-1582254Y-987056D02*
X-1576794D01*
G01X-1561624D02*
Y-997456D01*
G01Y-982896D02*
X-1562014Y-982636D01*
Y-982116D01*
X-1561624Y-981856D01*
X-1561234Y-982116D01*
Y-982636D01*
X-1561624Y-982896D01*
G01X-1543724Y-997456D02*
X-1544894Y-997196D01*
X-1546064Y-996156D01*
X-1546844Y-994336D01*
X-1547234Y-992256D01*
X-1546844Y-990176D01*
X-1546064Y-988356D01*
X-1544894Y-987316D01*
X-1543724Y-987056D01*
X-1542554Y-987316D01*
X-1541384Y-988356D01*
X-1540604Y-990176D01*
X-1540409Y-992256D01*
X-1540604Y-994336D01*
X-1541384Y-996156D01*
X-1542554Y-997196D01*
X-1543724Y-997456D01*
G01X-1529139D02*
Y-987056D01*
G01Y-989656D02*
X-1528359Y-988356D01*
X-1527189Y-987316D01*
X-1525629Y-987056D01*
X-1524264Y-987316D01*
X-1523094Y-988356D01*
X-1522509Y-990176D01*
Y-997456D01*
G01X-1494899Y-987056D02*
X-1492559Y-997456D01*
X-1490024Y-987056D01*
X-1487489Y-997456D01*
X-1485149Y-987056D01*
G01X-1475439Y-997456D02*
Y-981856D01*
G01Y-989396D02*
X-1474464Y-988096D01*
X-1473489Y-987316D01*
X-1471929Y-987056D01*
X-1470759Y-987316D01*
X-1469394Y-988356D01*
X-1468809Y-989916D01*
Y-997456D01*
G01X-1457149Y-990436D02*
X-1450909D01*
X-1451494Y-988616D01*
X-1452469Y-987576D01*
X-1453834Y-987056D01*
X-1455199Y-987316D01*
X-1456369Y-988096D01*
X-1457149Y-989916D01*
X-1457539Y-991476D01*
Y-993036D01*
X-1457149Y-994596D01*
X-1456174Y-996156D01*
X-1455004Y-997196D01*
X-1453639Y-997456D01*
X-1452274Y-996936D01*
X-1450909Y-995376D01*
G01X-1439639Y-997456D02*
Y-987056D01*
G01Y-989656D02*
X-1438859Y-988356D01*
X-1437689Y-987316D01*
X-1436129Y-987056D01*
X-1434764Y-987316D01*
X-1433594Y-988356D01*
X-1433009Y-990176D01*
Y-997456D01*
G01X-1406374D02*
Y-987056D01*
G01Y-989916D02*
X-1405789Y-988616D01*
X-1404814Y-987576D01*
X-1403449Y-987056D01*
X-1402084Y-987576D01*
X-1401109Y-988616D01*
X-1400524Y-989916D01*
Y-997456D01*
G01Y-989916D02*
X-1399939Y-988616D01*
X-1398964Y-987576D01*
X-1397599Y-987056D01*
X-1396234Y-987576D01*
X-1395259Y-988616D01*
X-1394674Y-990176D01*
Y-997456D01*
G01X-1385549Y-990436D02*
X-1379309D01*
X-1379894Y-988616D01*
X-1380869Y-987576D01*
X-1382234Y-987056D01*
X-1383599Y-987316D01*
X-1384769Y-988096D01*
X-1385549Y-989916D01*
X-1385939Y-991476D01*
Y-993036D01*
X-1385549Y-994596D01*
X-1384574Y-996156D01*
X-1383404Y-997196D01*
X-1382039Y-997456D01*
X-1380674Y-996936D01*
X-1379309Y-995376D01*
G01X-1361214Y-997456D02*
Y-987056D01*
G01Y-988876D02*
X-1361994Y-987836D01*
X-1363164Y-987316D01*
X-1364529Y-987056D01*
X-1365894Y-987576D01*
X-1367064Y-988616D01*
X-1367844Y-990176D01*
X-1368234Y-992256D01*
X-1367844Y-994336D01*
X-1367064Y-995896D01*
X-1365894Y-996936D01*
X-1364529Y-997456D01*
X-1363164Y-997196D01*
X-1361994Y-996416D01*
X-1361214Y-995376D01*
G01X-1349749Y-995636D02*
X-1348774Y-996676D01*
X-1347409Y-997456D01*
X-1346239D01*
X-1345069Y-996936D01*
X-1344289Y-996156D01*
X-1343899Y-995116D01*
X-1344094Y-993556D01*
X-1344874Y-992776D01*
X-1348384Y-991216D01*
X-1349164Y-989396D01*
X-1348774Y-988096D01*
X-1347994Y-987316D01*
X-1346824Y-987056D01*
X-1345654Y-987316D01*
X-1344484Y-988096D01*
G01X-1332239Y-987056D02*
Y-994336D01*
X-1331459Y-996156D01*
X-1330289Y-997196D01*
X-1328924Y-997456D01*
X-1327559Y-997196D01*
X-1326389Y-996156D01*
X-1325609Y-994336D01*
G01Y-997456D02*
Y-987056D01*
G01X-1313754Y-997456D02*
Y-987056D01*
G01Y-989136D02*
X-1312779Y-988096D01*
X-1311804Y-987316D01*
X-1310439Y-987056D01*
X-1309464Y-987316D01*
X-1308294Y-988096D01*
G01X-1296049Y-990436D02*
X-1289809D01*
X-1290394Y-988616D01*
X-1291369Y-987576D01*
X-1292734Y-987056D01*
X-1294099Y-987316D01*
X-1295269Y-988096D01*
X-1296049Y-989916D01*
X-1296439Y-991476D01*
Y-993036D01*
X-1296049Y-994596D01*
X-1295074Y-996156D01*
X-1293904Y-997196D01*
X-1292539Y-997456D01*
X-1291174Y-996936D01*
X-1289809Y-995376D01*
G01X-1271714Y-981856D02*
Y-997456D01*
G01Y-995116D02*
X-1272494Y-996416D01*
X-1273664Y-997196D01*
X-1275029Y-997456D01*
X-1276589Y-996936D01*
X-1277759Y-995636D01*
X-1278539Y-994076D01*
X-1278734Y-992256D01*
X-1278539Y-990436D01*
X-1277759Y-988876D01*
X-1276589Y-987576D01*
X-1275029Y-987056D01*
X-1273664Y-987316D01*
X-1272689Y-987836D01*
X-1271714Y-988876D01*
G01X-1235914Y-981856D02*
Y-997456D01*
G01Y-995116D02*
X-1236694Y-996416D01*
X-1237864Y-997196D01*
X-1239229Y-997456D01*
X-1240789Y-996936D01*
X-1241959Y-995636D01*
X-1242739Y-994076D01*
X-1242934Y-992256D01*
X-1242739Y-990436D01*
X-1241959Y-988876D01*
X-1240789Y-987576D01*
X-1239229Y-987056D01*
X-1237864Y-987316D01*
X-1236889Y-987836D01*
X-1235914Y-988876D01*
G01X-1221524Y-987056D02*
Y-997456D01*
G01Y-982896D02*
X-1221914Y-982636D01*
Y-982116D01*
X-1221524Y-981856D01*
X-1221134Y-982116D01*
Y-982636D01*
X-1221524Y-982896D01*
G01X-1200114Y-997456D02*
Y-987056D01*
G01Y-988876D02*
X-1200894Y-987836D01*
X-1202064Y-987316D01*
X-1203429Y-987056D01*
X-1204794Y-987576D01*
X-1205964Y-988616D01*
X-1206744Y-990176D01*
X-1207134Y-992256D01*
X-1206744Y-994336D01*
X-1205964Y-995896D01*
X-1204794Y-996936D01*
X-1203429Y-997456D01*
X-1202064Y-997196D01*
X-1200894Y-996416D01*
X-1200114Y-995376D01*
G01X-1188454Y-1001356D02*
X-1187089Y-1002396D01*
X-1185529Y-1002656D01*
X-1184164Y-1002396D01*
X-1182994Y-1001096D01*
X-1182214Y-999276D01*
Y-987056D01*
G01Y-989136D02*
X-1182994Y-988096D01*
X-1184164Y-987316D01*
X-1185529Y-987056D01*
X-1187089Y-987576D01*
X-1188064Y-988616D01*
X-1188844Y-990436D01*
X-1189234Y-992256D01*
X-1189039Y-993816D01*
X-1188259Y-995636D01*
X-1187089Y-996936D01*
X-1185529Y-997456D01*
X-1184359Y-997196D01*
X-1182994Y-996156D01*
X-1182214Y-995116D01*
G01X-1167824Y-997456D02*
X-1168994Y-997196D01*
X-1170164Y-996156D01*
X-1170944Y-994336D01*
X-1171334Y-992256D01*
X-1170944Y-990176D01*
X-1170164Y-988356D01*
X-1168994Y-987316D01*
X-1167824Y-987056D01*
X-1166654Y-987316D01*
X-1165484Y-988356D01*
X-1164704Y-990176D01*
X-1164509Y-992256D01*
X-1164704Y-994336D01*
X-1165484Y-996156D01*
X-1166654Y-997196D01*
X-1167824Y-997456D01*
G01X-1153239D02*
Y-987056D01*
G01Y-989656D02*
X-1152459Y-988356D01*
X-1151289Y-987316D01*
X-1149729Y-987056D01*
X-1148364Y-987316D01*
X-1147194Y-988356D01*
X-1146609Y-990176D01*
Y-997456D01*
G01X-1128514D02*
Y-987056D01*
G01Y-988876D02*
X-1129294Y-987836D01*
X-1130464Y-987316D01*
X-1131829Y-987056D01*
X-1133194Y-987576D01*
X-1134364Y-988616D01*
X-1135144Y-990176D01*
X-1135534Y-992256D01*
X-1135144Y-994336D01*
X-1134364Y-995896D01*
X-1133194Y-996936D01*
X-1131829Y-997456D01*
X-1130464Y-997196D01*
X-1129294Y-996416D01*
X-1128514Y-995376D01*
G01X-1114124Y-997456D02*
Y-981856D01*
G01X-1096224Y-997456D02*
Y-981856D01*
G01X-1082419Y-1002136D02*
X-1081249Y-1002656D01*
X-1079689Y-1002136D01*
X-1078714Y-1001096D01*
X-1077934Y-999796D01*
X-1076764Y-995636D01*
X-1074229Y-987056D01*
G01X-1080469D02*
X-1076764Y-995636D01*
G01X-1039014Y-997456D02*
Y-987056D01*
G01Y-988876D02*
X-1039794Y-987836D01*
X-1040964Y-987316D01*
X-1042329Y-987056D01*
X-1043694Y-987576D01*
X-1044864Y-988616D01*
X-1045644Y-990176D01*
X-1046034Y-992256D01*
X-1045644Y-994336D01*
X-1044864Y-995896D01*
X-1043694Y-996936D01*
X-1042329Y-997456D01*
X-1040964Y-997196D01*
X-1039794Y-996416D01*
X-1039014Y-995376D01*
G01X-1021504Y-988356D02*
X-1022869Y-987316D01*
X-1024039Y-987056D01*
X-1025599Y-987576D01*
X-1026769Y-988616D01*
X-1027549Y-990436D01*
X-1027744Y-992256D01*
X-1027549Y-994076D01*
X-1026769Y-995636D01*
X-1025599Y-996936D01*
X-1024039Y-997456D01*
X-1022674Y-996936D01*
X-1021504Y-995896D01*
G01X-1009454Y-997456D02*
Y-987056D01*
G01Y-989136D02*
X-1008479Y-988096D01*
X-1007504Y-987316D01*
X-1006139Y-987056D01*
X-1005164Y-987316D01*
X-1003994Y-988096D01*
G01X-988824Y-997456D02*
X-989994Y-997196D01*
X-991164Y-996156D01*
X-991944Y-994336D01*
X-992334Y-992256D01*
X-991944Y-990176D01*
X-991164Y-988356D01*
X-989994Y-987316D01*
X-988824Y-987056D01*
X-987654Y-987316D01*
X-986484Y-988356D01*
X-985704Y-990176D01*
X-985509Y-992256D01*
X-985704Y-994336D01*
X-986484Y-996156D01*
X-987654Y-997196D01*
X-988824Y-997456D01*
G01X-973849Y-995636D02*
X-972874Y-996676D01*
X-971509Y-997456D01*
X-970339D01*
X-969169Y-996936D01*
X-968389Y-996156D01*
X-967999Y-995116D01*
X-968194Y-993556D01*
X-968974Y-992776D01*
X-972484Y-991216D01*
X-973264Y-989396D01*
X-972874Y-988096D01*
X-972094Y-987316D01*
X-970924Y-987056D01*
X-969754Y-987316D01*
X-968584Y-988096D01*
G01X-955949Y-995636D02*
X-954974Y-996676D01*
X-953609Y-997456D01*
X-952439D01*
X-951269Y-996936D01*
X-950489Y-996156D01*
X-950099Y-995116D01*
X-950294Y-993556D01*
X-951074Y-992776D01*
X-954584Y-991216D01*
X-955364Y-989396D01*
X-954974Y-988096D01*
X-954194Y-987316D01*
X-953024Y-987056D01*
X-951854Y-987316D01*
X-950684Y-988096D01*
G01X-917224Y-981856D02*
Y-997456D01*
G01X-919954Y-987056D02*
X-914494D01*
G01X-902639Y-997456D02*
Y-981856D01*
G01Y-989396D02*
X-901664Y-988096D01*
X-900689Y-987316D01*
X-899129Y-987056D01*
X-897959Y-987316D01*
X-896594Y-988356D01*
X-896009Y-989916D01*
Y-997456D01*
G01X-884349Y-990436D02*
X-878109D01*
X-878694Y-988616D01*
X-879669Y-987576D01*
X-881034Y-987056D01*
X-882399Y-987316D01*
X-883569Y-988096D01*
X-884349Y-989916D01*
X-884739Y-991476D01*
Y-993036D01*
X-884349Y-994596D01*
X-883374Y-996156D01*
X-882204Y-997196D01*
X-880839Y-997456D01*
X-879474Y-996936D01*
X-878109Y-995376D01*
G01X-848549Y-995636D02*
X-847574Y-996676D01*
X-846209Y-997456D01*
X-845039D01*
X-843869Y-996936D01*
X-843089Y-996156D01*
X-842699Y-995116D01*
X-842894Y-993556D01*
X-843674Y-992776D01*
X-847184Y-991216D01*
X-847964Y-989396D01*
X-847574Y-988096D01*
X-846794Y-987316D01*
X-845624Y-987056D01*
X-844454Y-987316D01*
X-843284Y-988096D01*
G01X-827724Y-987056D02*
Y-997456D01*
G01Y-982896D02*
X-828114Y-982636D01*
Y-982116D01*
X-827724Y-981856D01*
X-827334Y-982116D01*
Y-982636D01*
X-827724Y-982896D01*
G01X-809824Y-997456D02*
Y-981856D01*
G01X-795239Y-997456D02*
Y-981856D01*
G01X-788999Y-987056D02*
X-795239Y-993036D01*
G01X-792704Y-990696D02*
X-788609Y-997456D01*
G01X-776949Y-995636D02*
X-775974Y-996676D01*
X-774609Y-997456D01*
X-773439D01*
X-772269Y-996936D01*
X-771489Y-996156D01*
X-771099Y-995116D01*
X-771294Y-993556D01*
X-772074Y-992776D01*
X-775584Y-991216D01*
X-776364Y-989396D01*
X-775974Y-988096D01*
X-775194Y-987316D01*
X-774024Y-987056D01*
X-772854Y-987316D01*
X-771684Y-988096D01*
G01X-753004Y-988356D02*
X-754369Y-987316D01*
X-755539Y-987056D01*
X-757099Y-987576D01*
X-758269Y-988616D01*
X-759049Y-990436D01*
X-759244Y-992256D01*
X-759049Y-994076D01*
X-758269Y-995636D01*
X-757099Y-996936D01*
X-755539Y-997456D01*
X-754174Y-996936D01*
X-753004Y-995896D01*
G01X-740954Y-997456D02*
Y-987056D01*
G01Y-989136D02*
X-739979Y-988096D01*
X-739004Y-987316D01*
X-737639Y-987056D01*
X-736664Y-987316D01*
X-735494Y-988096D01*
G01X-723249Y-990436D02*
X-717009D01*
X-717594Y-988616D01*
X-718569Y-987576D01*
X-719934Y-987056D01*
X-721299Y-987316D01*
X-722469Y-988096D01*
X-723249Y-989916D01*
X-723639Y-991476D01*
Y-993036D01*
X-723249Y-994596D01*
X-722274Y-996156D01*
X-721104Y-997196D01*
X-719739Y-997456D01*
X-718374Y-996936D01*
X-717009Y-995376D01*
G01X-705349Y-990436D02*
X-699109D01*
X-699694Y-988616D01*
X-700669Y-987576D01*
X-702034Y-987056D01*
X-703399Y-987316D01*
X-704569Y-988096D01*
X-705349Y-989916D01*
X-705739Y-991476D01*
Y-993036D01*
X-705349Y-994596D01*
X-704374Y-996156D01*
X-703204Y-997196D01*
X-701839Y-997456D01*
X-700474Y-996936D01*
X-699109Y-995376D01*
G01X-687839Y-997456D02*
Y-987056D01*
G01Y-989656D02*
X-687059Y-988356D01*
X-685889Y-987316D01*
X-684329Y-987056D01*
X-682964Y-987316D01*
X-681794Y-988356D01*
X-681209Y-990176D01*
Y-997456D01*
G01X-645604Y-988356D02*
X-646969Y-987316D01*
X-648139Y-987056D01*
X-649699Y-987576D01*
X-650869Y-988616D01*
X-651649Y-990436D01*
X-651844Y-992256D01*
X-651649Y-994076D01*
X-650869Y-995636D01*
X-649699Y-996936D01*
X-648139Y-997456D01*
X-646774Y-996936D01*
X-645604Y-995896D01*
G01X-630824Y-997456D02*
X-631994Y-997196D01*
X-633164Y-996156D01*
X-633944Y-994336D01*
X-634334Y-992256D01*
X-633944Y-990176D01*
X-633164Y-988356D01*
X-631994Y-987316D01*
X-630824Y-987056D01*
X-629654Y-987316D01*
X-628484Y-988356D01*
X-627704Y-990176D01*
X-627509Y-992256D01*
X-627704Y-994336D01*
X-628484Y-996156D01*
X-629654Y-997196D01*
X-630824Y-997456D01*
G01X-615654D02*
Y-987056D01*
G01Y-989136D02*
X-614679Y-988096D01*
X-613704Y-987316D01*
X-612339Y-987056D01*
X-611364Y-987316D01*
X-610194Y-988096D01*
G01X-598339Y-997456D02*
Y-987056D01*
G01Y-989656D02*
X-597559Y-988356D01*
X-596389Y-987316D01*
X-594829Y-987056D01*
X-593464Y-987316D01*
X-592294Y-988356D01*
X-591709Y-990176D01*
Y-997456D01*
G01X-580049Y-990436D02*
X-573809D01*
X-574394Y-988616D01*
X-575369Y-987576D01*
X-576734Y-987056D01*
X-578099Y-987316D01*
X-579269Y-988096D01*
X-580049Y-989916D01*
X-580439Y-991476D01*
Y-993036D01*
X-580049Y-994596D01*
X-579074Y-996156D01*
X-577904Y-997196D01*
X-576539Y-997456D01*
X-575174Y-996936D01*
X-573809Y-995376D01*
G01X-561954Y-997456D02*
Y-987056D01*
G01Y-989136D02*
X-560979Y-988096D01*
X-560004Y-987316D01*
X-558639Y-987056D01*
X-557664Y-987316D01*
X-556494Y-988096D01*
G01X-544249Y-995636D02*
X-543274Y-996676D01*
X-541909Y-997456D01*
X-540739D01*
X-539569Y-996936D01*
X-538789Y-996156D01*
X-538399Y-995116D01*
X-538594Y-993556D01*
X-539374Y-992776D01*
X-542884Y-991216D01*
X-543664Y-989396D01*
X-543274Y-988096D01*
X-542494Y-987316D01*
X-541324Y-987056D01*
X-540154Y-987316D01*
X-538984Y-988096D01*
G01X-523424Y-997976D02*
X-523814Y-997716D01*
Y-997196D01*
X-523424Y-996936D01*
X-523034Y-997196D01*
Y-997716D01*
X-523424Y-997976D01*
G01X-2077604Y-846356D02*
X-2078969Y-845316D01*
X-2080139Y-845056D01*
X-2081699Y-845576D01*
X-2082869Y-846616D01*
X-2083649Y-848436D01*
X-2083844Y-850256D01*
X-2083649Y-852076D01*
X-2082869Y-853636D01*
X-2081699Y-854936D01*
X-2080139Y-855456D01*
X-2078774Y-854936D01*
X-2077604Y-853896D01*
G01X-2065554Y-855456D02*
Y-845056D01*
G01Y-847136D02*
X-2064579Y-846096D01*
X-2063604Y-845316D01*
X-2062239Y-845056D01*
X-2061264Y-845316D01*
X-2060094Y-846096D01*
G01X-2044924Y-845056D02*
Y-855456D01*
G01Y-840896D02*
X-2045314Y-840636D01*
Y-840116D01*
X-2044924Y-839856D01*
X-2044534Y-840116D01*
Y-840636D01*
X-2044924Y-840896D01*
G01X-2027024Y-839856D02*
Y-855456D01*
G01X-2029754Y-845056D02*
X-2024294D01*
G01X-2009124D02*
Y-855456D01*
G01Y-840896D02*
X-2009514Y-840636D01*
Y-840116D01*
X-2009124Y-839856D01*
X-2008734Y-840116D01*
Y-840636D01*
X-2009124Y-840896D01*
G01X-1988104Y-846356D02*
X-1989469Y-845316D01*
X-1990639Y-845056D01*
X-1992199Y-845576D01*
X-1993369Y-846616D01*
X-1994149Y-848436D01*
X-1994344Y-850256D01*
X-1994149Y-852076D01*
X-1993369Y-853636D01*
X-1992199Y-854936D01*
X-1990639Y-855456D01*
X-1989274Y-854936D01*
X-1988104Y-853896D01*
G01X-1969814Y-855456D02*
Y-845056D01*
G01Y-846876D02*
X-1970594Y-845836D01*
X-1971764Y-845316D01*
X-1973129Y-845056D01*
X-1974494Y-845576D01*
X-1975664Y-846616D01*
X-1976444Y-848176D01*
X-1976834Y-850256D01*
X-1976444Y-852336D01*
X-1975664Y-853896D01*
X-1974494Y-854936D01*
X-1973129Y-855456D01*
X-1971764Y-855196D01*
X-1970594Y-854416D01*
X-1969814Y-853376D01*
G01X-1955424Y-855456D02*
Y-839856D01*
G01X-1919624D02*
Y-855456D01*
G01X-1922354Y-845056D02*
X-1916894D01*
G01X-1901724Y-855456D02*
X-1902894Y-855196D01*
X-1904064Y-854156D01*
X-1904844Y-852336D01*
X-1905234Y-850256D01*
X-1904844Y-848176D01*
X-1904064Y-846356D01*
X-1902894Y-845316D01*
X-1901724Y-845056D01*
X-1900554Y-845316D01*
X-1899384Y-846356D01*
X-1898604Y-848176D01*
X-1898409Y-850256D01*
X-1898604Y-852336D01*
X-1899384Y-854156D01*
X-1900554Y-855196D01*
X-1901724Y-855456D01*
G01X-1867094D02*
Y-842196D01*
X-1866704Y-840896D01*
X-1865924Y-840116D01*
X-1864754Y-839856D01*
X-1863584Y-840376D01*
X-1862999Y-841676D01*
G01X-1865339Y-846096D02*
X-1869239D01*
G01X-1851339Y-845056D02*
Y-852336D01*
X-1850559Y-854156D01*
X-1849389Y-855196D01*
X-1848024Y-855456D01*
X-1846659Y-855196D01*
X-1845489Y-854156D01*
X-1844709Y-852336D01*
G01Y-855456D02*
Y-845056D01*
G01X-1833439Y-855456D02*
Y-845056D01*
G01Y-847656D02*
X-1832659Y-846356D01*
X-1831489Y-845316D01*
X-1829929Y-845056D01*
X-1828564Y-845316D01*
X-1827394Y-846356D01*
X-1826809Y-848176D01*
Y-855456D01*
G01X-1809104Y-846356D02*
X-1810469Y-845316D01*
X-1811639Y-845056D01*
X-1813199Y-845576D01*
X-1814369Y-846616D01*
X-1815149Y-848436D01*
X-1815344Y-850256D01*
X-1815149Y-852076D01*
X-1814369Y-853636D01*
X-1813199Y-854936D01*
X-1811639Y-855456D01*
X-1810274Y-854936D01*
X-1809104Y-853896D01*
G01X-1794324Y-839856D02*
Y-855456D01*
G01X-1797054Y-845056D02*
X-1791594D01*
G01X-1776424D02*
Y-855456D01*
G01Y-840896D02*
X-1776814Y-840636D01*
Y-840116D01*
X-1776424Y-839856D01*
X-1776034Y-840116D01*
Y-840636D01*
X-1776424Y-840896D01*
G01X-1758524Y-855456D02*
X-1759694Y-855196D01*
X-1760864Y-854156D01*
X-1761644Y-852336D01*
X-1762034Y-850256D01*
X-1761644Y-848176D01*
X-1760864Y-846356D01*
X-1759694Y-845316D01*
X-1758524Y-845056D01*
X-1757354Y-845316D01*
X-1756184Y-846356D01*
X-1755404Y-848176D01*
X-1755209Y-850256D01*
X-1755404Y-852336D01*
X-1756184Y-854156D01*
X-1757354Y-855196D01*
X-1758524Y-855456D01*
G01X-1743939D02*
Y-845056D01*
G01Y-847656D02*
X-1743159Y-846356D01*
X-1741989Y-845316D01*
X-1740429Y-845056D01*
X-1739064Y-845316D01*
X-1737894Y-846356D01*
X-1737309Y-848176D01*
Y-855456D01*
G01X-1710674D02*
Y-845056D01*
G01Y-847916D02*
X-1710089Y-846616D01*
X-1709114Y-845576D01*
X-1707749Y-845056D01*
X-1706384Y-845576D01*
X-1705409Y-846616D01*
X-1704824Y-847916D01*
Y-855456D01*
G01Y-847916D02*
X-1704239Y-846616D01*
X-1703264Y-845576D01*
X-1701899Y-845056D01*
X-1700534Y-845576D01*
X-1699559Y-846616D01*
X-1698974Y-848176D01*
Y-855456D01*
G01X-1683414D02*
Y-845056D01*
G01Y-846876D02*
X-1684194Y-845836D01*
X-1685364Y-845316D01*
X-1686729Y-845056D01*
X-1688094Y-845576D01*
X-1689264Y-846616D01*
X-1690044Y-848176D01*
X-1690434Y-850256D01*
X-1690044Y-852336D01*
X-1689264Y-853896D01*
X-1688094Y-854936D01*
X-1686729Y-855456D01*
X-1685364Y-855196D01*
X-1684194Y-854416D01*
X-1683414Y-853376D01*
G01X-1671754Y-855456D02*
Y-845056D01*
G01Y-847136D02*
X-1670779Y-846096D01*
X-1669804Y-845316D01*
X-1668439Y-845056D01*
X-1667464Y-845316D01*
X-1666294Y-846096D01*
G01X-1654439Y-855456D02*
Y-839856D01*
G01X-1648199Y-845056D02*
X-1654439Y-851036D01*
G01X-1651904Y-848696D02*
X-1647809Y-855456D01*
G01X-1636149Y-848436D02*
X-1629909D01*
X-1630494Y-846616D01*
X-1631469Y-845576D01*
X-1632834Y-845056D01*
X-1634199Y-845316D01*
X-1635369Y-846096D01*
X-1636149Y-847916D01*
X-1636539Y-849476D01*
Y-851036D01*
X-1636149Y-852596D01*
X-1635174Y-854156D01*
X-1634004Y-855196D01*
X-1632639Y-855456D01*
X-1631274Y-854936D01*
X-1629909Y-853376D01*
G01X-1611814Y-839856D02*
Y-855456D01*
G01Y-853116D02*
X-1612594Y-854416D01*
X-1613764Y-855196D01*
X-1615129Y-855456D01*
X-1616689Y-854936D01*
X-1617859Y-853636D01*
X-1618639Y-852076D01*
X-1618834Y-850256D01*
X-1618639Y-848436D01*
X-1617859Y-846876D01*
X-1616689Y-845576D01*
X-1615129Y-845056D01*
X-1613764Y-845316D01*
X-1612789Y-845836D01*
X-1611814Y-846876D01*
G01X-1576014Y-855456D02*
Y-845056D01*
G01Y-846876D02*
X-1576794Y-845836D01*
X-1577964Y-845316D01*
X-1579329Y-845056D01*
X-1580694Y-845576D01*
X-1581864Y-846616D01*
X-1582644Y-848176D01*
X-1583034Y-850256D01*
X-1582644Y-852336D01*
X-1581864Y-853896D01*
X-1580694Y-854936D01*
X-1579329Y-855456D01*
X-1577964Y-855196D01*
X-1576794Y-854416D01*
X-1576014Y-853376D01*
G01X-1564549Y-853636D02*
X-1563574Y-854676D01*
X-1562209Y-855456D01*
X-1561039D01*
X-1559869Y-854936D01*
X-1559089Y-854156D01*
X-1558699Y-853116D01*
X-1558894Y-851556D01*
X-1559674Y-850776D01*
X-1563184Y-849216D01*
X-1563964Y-847396D01*
X-1563574Y-846096D01*
X-1562794Y-845316D01*
X-1561624Y-845056D01*
X-1560454Y-845316D01*
X-1559284Y-846096D01*
G01X-1521534Y-841156D02*
X-1522704Y-840376D01*
X-1524069Y-839856D01*
X-1525629D01*
X-1527384Y-840636D01*
X-1528749Y-841936D01*
X-1529724Y-843496D01*
X-1530504Y-846096D01*
X-1530699Y-848436D01*
X-1530309Y-850776D01*
X-1529724Y-852336D01*
X-1528554Y-853896D01*
X-1527189Y-854936D01*
X-1525824Y-855456D01*
X-1524459D01*
X-1523094Y-854936D01*
X-1521924Y-854156D01*
X-1520949Y-853116D01*
G01X-1507924Y-839856D02*
Y-855456D01*
G01X-1512409Y-839856D02*
X-1503439D01*
G01X-1493729Y-855456D02*
Y-839856D01*
X-1486319D01*
G01X-1489049Y-847396D02*
X-1493729D01*
G01X-1454224Y-845056D02*
Y-855456D01*
G01Y-840896D02*
X-1454614Y-840636D01*
Y-840116D01*
X-1454224Y-839856D01*
X-1453834Y-840116D01*
Y-840636D01*
X-1454224Y-840896D01*
G01X-1439639Y-855456D02*
Y-845056D01*
G01Y-847656D02*
X-1438859Y-846356D01*
X-1437689Y-845316D01*
X-1436129Y-845056D01*
X-1434764Y-845316D01*
X-1433594Y-846356D01*
X-1433009Y-848176D01*
Y-855456D01*
G01X-1400524Y-839856D02*
Y-855456D01*
G01X-1403254Y-845056D02*
X-1397794D01*
G01X-1385939Y-855456D02*
Y-839856D01*
G01Y-847396D02*
X-1384964Y-846096D01*
X-1383989Y-845316D01*
X-1382429Y-845056D01*
X-1381259Y-845316D01*
X-1379894Y-846356D01*
X-1379309Y-847916D01*
Y-855456D01*
G01X-1367649Y-848436D02*
X-1361409D01*
X-1361994Y-846616D01*
X-1362969Y-845576D01*
X-1364334Y-845056D01*
X-1365699Y-845316D01*
X-1366869Y-846096D01*
X-1367649Y-847916D01*
X-1368039Y-849476D01*
Y-851036D01*
X-1367649Y-852596D01*
X-1366674Y-854156D01*
X-1365504Y-855196D01*
X-1364139Y-855456D01*
X-1362774Y-854936D01*
X-1361409Y-853376D01*
G01X-1325414Y-839856D02*
Y-855456D01*
G01Y-853116D02*
X-1326194Y-854416D01*
X-1327364Y-855196D01*
X-1328729Y-855456D01*
X-1330289Y-854936D01*
X-1331459Y-853636D01*
X-1332239Y-852076D01*
X-1332434Y-850256D01*
X-1332239Y-848436D01*
X-1331459Y-846876D01*
X-1330289Y-845576D01*
X-1328729Y-845056D01*
X-1327364Y-845316D01*
X-1326389Y-845836D01*
X-1325414Y-846876D01*
G01X-1313754Y-855456D02*
Y-845056D01*
G01Y-847136D02*
X-1312779Y-846096D01*
X-1311804Y-845316D01*
X-1310439Y-845056D01*
X-1309464Y-845316D01*
X-1308294Y-846096D01*
G01X-1289614Y-855456D02*
Y-845056D01*
G01Y-846876D02*
X-1290394Y-845836D01*
X-1291564Y-845316D01*
X-1292929Y-845056D01*
X-1294294Y-845576D01*
X-1295464Y-846616D01*
X-1296244Y-848176D01*
X-1296634Y-850256D01*
X-1296244Y-852336D01*
X-1295464Y-853896D01*
X-1294294Y-854936D01*
X-1292929Y-855456D01*
X-1291564Y-855196D01*
X-1290394Y-854416D01*
X-1289614Y-853376D01*
G01X-1280099Y-845056D02*
X-1277759Y-855456D01*
X-1275224Y-845056D01*
X-1272689Y-855456D01*
X-1270349Y-845056D01*
G01X-1257324D02*
Y-855456D01*
G01Y-840896D02*
X-1257714Y-840636D01*
Y-840116D01*
X-1257324Y-839856D01*
X-1256934Y-840116D01*
Y-840636D01*
X-1257324Y-840896D01*
G01X-1242739Y-855456D02*
Y-845056D01*
G01Y-847656D02*
X-1241959Y-846356D01*
X-1240789Y-845316D01*
X-1239229Y-845056D01*
X-1237864Y-845316D01*
X-1236694Y-846356D01*
X-1236109Y-848176D01*
Y-855456D01*
G01X-1224254Y-859356D02*
X-1222889Y-860396D01*
X-1221329Y-860656D01*
X-1219964Y-860396D01*
X-1218794Y-859096D01*
X-1218014Y-857276D01*
Y-845056D01*
G01Y-847136D02*
X-1218794Y-846096D01*
X-1219964Y-845316D01*
X-1221329Y-845056D01*
X-1222889Y-845576D01*
X-1223864Y-846616D01*
X-1224644Y-848436D01*
X-1225034Y-850256D01*
X-1224839Y-851816D01*
X-1224059Y-853636D01*
X-1222889Y-854936D01*
X-1221329Y-855456D01*
X-1220159Y-855196D01*
X-1218794Y-854156D01*
X-1218014Y-853116D01*
G01X-1204014Y-858316D02*
X-1203234Y-854936D01*
G01X-1152654Y-855456D02*
Y-845056D01*
G01Y-847136D02*
X-1151679Y-846096D01*
X-1150704Y-845316D01*
X-1149339Y-845056D01*
X-1148364Y-845316D01*
X-1147194Y-846096D01*
G01X-1134949Y-848436D02*
X-1128709D01*
X-1129294Y-846616D01*
X-1130269Y-845576D01*
X-1131634Y-845056D01*
X-1132999Y-845316D01*
X-1134169Y-846096D01*
X-1134949Y-847916D01*
X-1135339Y-849476D01*
Y-851036D01*
X-1134949Y-852596D01*
X-1133974Y-854156D01*
X-1132804Y-855196D01*
X-1131439Y-855456D01*
X-1130074Y-854936D01*
X-1128709Y-853376D01*
G01X-1110614Y-860656D02*
Y-845056D01*
G01Y-847396D02*
X-1111589Y-846096D01*
X-1112759Y-845316D01*
X-1114124Y-845056D01*
X-1115294Y-845316D01*
X-1116659Y-846616D01*
X-1117439Y-848436D01*
X-1117634Y-850256D01*
X-1117439Y-852076D01*
X-1116659Y-853896D01*
X-1115294Y-855196D01*
X-1114124Y-855456D01*
X-1112759Y-855196D01*
X-1111589Y-854416D01*
X-1110614Y-853116D01*
G01X-1099539Y-845056D02*
Y-852336D01*
X-1098759Y-854156D01*
X-1097589Y-855196D01*
X-1096224Y-855456D01*
X-1094859Y-855196D01*
X-1093689Y-854156D01*
X-1092909Y-852336D01*
G01Y-855456D02*
Y-845056D01*
G01X-1078324D02*
Y-855456D01*
G01Y-840896D02*
X-1078714Y-840636D01*
Y-840116D01*
X-1078324Y-839856D01*
X-1077934Y-840116D01*
Y-840636D01*
X-1078324Y-840896D01*
G01X-1063154Y-855456D02*
Y-845056D01*
G01Y-847136D02*
X-1062179Y-846096D01*
X-1061204Y-845316D01*
X-1059839Y-845056D01*
X-1058864Y-845316D01*
X-1057694Y-846096D01*
G01X-1045449Y-848436D02*
X-1039209D01*
X-1039794Y-846616D01*
X-1040769Y-845576D01*
X-1042134Y-845056D01*
X-1043499Y-845316D01*
X-1044669Y-846096D01*
X-1045449Y-847916D01*
X-1045839Y-849476D01*
Y-851036D01*
X-1045449Y-852596D01*
X-1044474Y-854156D01*
X-1043304Y-855196D01*
X-1041939Y-855456D01*
X-1040574Y-854936D01*
X-1039209Y-853376D01*
G01X-1003214Y-855456D02*
Y-845056D01*
G01Y-846876D02*
X-1003994Y-845836D01*
X-1005164Y-845316D01*
X-1006529Y-845056D01*
X-1007894Y-845576D01*
X-1009064Y-846616D01*
X-1009844Y-848176D01*
X-1010234Y-850256D01*
X-1009844Y-852336D01*
X-1009064Y-853896D01*
X-1007894Y-854936D01*
X-1006529Y-855456D01*
X-1005164Y-855196D01*
X-1003994Y-854416D01*
X-1003214Y-853376D01*
G01X-976774Y-855456D02*
Y-845056D01*
G01Y-847916D02*
X-976189Y-846616D01*
X-975214Y-845576D01*
X-973849Y-845056D01*
X-972484Y-845576D01*
X-971509Y-846616D01*
X-970924Y-847916D01*
Y-855456D01*
G01Y-847916D02*
X-970339Y-846616D01*
X-969364Y-845576D01*
X-967999Y-845056D01*
X-966634Y-845576D01*
X-965659Y-846616D01*
X-965074Y-848176D01*
Y-855456D01*
G01X-953024Y-845056D02*
Y-855456D01*
G01Y-840896D02*
X-953414Y-840636D01*
Y-840116D01*
X-953024Y-839856D01*
X-952634Y-840116D01*
Y-840636D01*
X-953024Y-840896D01*
G01X-938439Y-855456D02*
Y-845056D01*
G01Y-847656D02*
X-937659Y-846356D01*
X-936489Y-845316D01*
X-934929Y-845056D01*
X-933564Y-845316D01*
X-932394Y-846356D01*
X-931809Y-848176D01*
Y-855456D01*
G01X-917224Y-845056D02*
Y-855456D01*
G01Y-840896D02*
X-917614Y-840636D01*
Y-840116D01*
X-917224Y-839856D01*
X-916834Y-840116D01*
Y-840636D01*
X-917224Y-840896D01*
G01X-905174Y-855456D02*
Y-845056D01*
G01Y-847916D02*
X-904589Y-846616D01*
X-903614Y-845576D01*
X-902249Y-845056D01*
X-900884Y-845576D01*
X-899909Y-846616D01*
X-899324Y-847916D01*
Y-855456D01*
G01Y-847916D02*
X-898739Y-846616D01*
X-897764Y-845576D01*
X-896399Y-845056D01*
X-895034Y-845576D01*
X-894059Y-846616D01*
X-893474Y-848176D01*
Y-855456D01*
G01X-877914D02*
Y-845056D01*
G01Y-846876D02*
X-878694Y-845836D01*
X-879864Y-845316D01*
X-881229Y-845056D01*
X-882594Y-845576D01*
X-883764Y-846616D01*
X-884544Y-848176D01*
X-884934Y-850256D01*
X-884544Y-852336D01*
X-883764Y-853896D01*
X-882594Y-854936D01*
X-881229Y-855456D01*
X-879864Y-855196D01*
X-878694Y-854416D01*
X-877914Y-853376D01*
G01X-863524Y-855456D02*
Y-839856D01*
G01X-831234Y-860656D02*
Y-845056D01*
G01Y-847396D02*
X-830259Y-846096D01*
X-829284Y-845316D01*
X-827724Y-845056D01*
X-826359Y-845316D01*
X-824994Y-846616D01*
X-824409Y-848436D01*
X-824214Y-850256D01*
X-824409Y-852076D01*
X-824994Y-853896D01*
X-826164Y-854936D01*
X-827724Y-855456D01*
X-829089Y-855196D01*
X-830454Y-854416D01*
X-831234Y-853376D01*
G01X-812554Y-855456D02*
Y-845056D01*
G01Y-847136D02*
X-811579Y-846096D01*
X-810604Y-845316D01*
X-809239Y-845056D01*
X-808264Y-845316D01*
X-807094Y-846096D01*
G01X-791924Y-855456D02*
X-793094Y-855196D01*
X-794264Y-854156D01*
X-795044Y-852336D01*
X-795434Y-850256D01*
X-795044Y-848176D01*
X-794264Y-846356D01*
X-793094Y-845316D01*
X-791924Y-845056D01*
X-790754Y-845316D01*
X-789584Y-846356D01*
X-788804Y-848176D01*
X-788609Y-850256D01*
X-788804Y-852336D01*
X-789584Y-854156D01*
X-790754Y-855196D01*
X-791924Y-855456D01*
G01X-770904Y-846356D02*
X-772269Y-845316D01*
X-773439Y-845056D01*
X-774999Y-845576D01*
X-776169Y-846616D01*
X-776949Y-848436D01*
X-777144Y-850256D01*
X-776949Y-852076D01*
X-776169Y-853636D01*
X-774999Y-854936D01*
X-773439Y-855456D01*
X-772074Y-854936D01*
X-770904Y-853896D01*
G01X-759049Y-848436D02*
X-752809D01*
X-753394Y-846616D01*
X-754369Y-845576D01*
X-755734Y-845056D01*
X-757099Y-845316D01*
X-758269Y-846096D01*
X-759049Y-847916D01*
X-759439Y-849476D01*
Y-851036D01*
X-759049Y-852596D01*
X-758074Y-854156D01*
X-756904Y-855196D01*
X-755539Y-855456D01*
X-754174Y-854936D01*
X-752809Y-853376D01*
G01X-741149Y-853636D02*
X-740174Y-854676D01*
X-738809Y-855456D01*
X-737639D01*
X-736469Y-854936D01*
X-735689Y-854156D01*
X-735299Y-853116D01*
X-735494Y-851556D01*
X-736274Y-850776D01*
X-739784Y-849216D01*
X-740564Y-847396D01*
X-740174Y-846096D01*
X-739394Y-845316D01*
X-738224Y-845056D01*
X-737054Y-845316D01*
X-735884Y-846096D01*
G01X-723249Y-853636D02*
X-722274Y-854676D01*
X-720909Y-855456D01*
X-719739D01*
X-718569Y-854936D01*
X-717789Y-854156D01*
X-717399Y-853116D01*
X-717594Y-851556D01*
X-718374Y-850776D01*
X-721884Y-849216D01*
X-722664Y-847396D01*
X-722274Y-846096D01*
X-721494Y-845316D01*
X-720324Y-845056D01*
X-719154Y-845316D01*
X-717984Y-846096D01*
G01X-681404Y-846356D02*
X-682769Y-845316D01*
X-683939Y-845056D01*
X-685499Y-845576D01*
X-686669Y-846616D01*
X-687449Y-848436D01*
X-687644Y-850256D01*
X-687449Y-852076D01*
X-686669Y-853636D01*
X-685499Y-854936D01*
X-683939Y-855456D01*
X-682574Y-854936D01*
X-681404Y-853896D01*
G01X-666624Y-855456D02*
X-667794Y-855196D01*
X-668964Y-854156D01*
X-669744Y-852336D01*
X-670134Y-850256D01*
X-669744Y-848176D01*
X-668964Y-846356D01*
X-667794Y-845316D01*
X-666624Y-845056D01*
X-665454Y-845316D01*
X-664284Y-846356D01*
X-663504Y-848176D01*
X-663309Y-850256D01*
X-663504Y-852336D01*
X-664284Y-854156D01*
X-665454Y-855196D01*
X-666624Y-855456D01*
G01X-652039D02*
Y-845056D01*
G01Y-847656D02*
X-651259Y-846356D01*
X-650089Y-845316D01*
X-648529Y-845056D01*
X-647164Y-845316D01*
X-645994Y-846356D01*
X-645409Y-848176D01*
Y-855456D01*
G01X-630824Y-839856D02*
Y-855456D01*
G01X-633554Y-845056D02*
X-628094D01*
G01X-615654Y-855456D02*
Y-845056D01*
G01Y-847136D02*
X-614679Y-846096D01*
X-613704Y-845316D01*
X-612339Y-845056D01*
X-611364Y-845316D01*
X-610194Y-846096D01*
G01X-595024Y-855456D02*
X-596194Y-855196D01*
X-597364Y-854156D01*
X-598144Y-852336D01*
X-598534Y-850256D01*
X-598144Y-848176D01*
X-597364Y-846356D01*
X-596194Y-845316D01*
X-595024Y-845056D01*
X-593854Y-845316D01*
X-592684Y-846356D01*
X-591904Y-848176D01*
X-591709Y-850256D01*
X-591904Y-852336D01*
X-592684Y-854156D01*
X-593854Y-855196D01*
X-595024Y-855456D01*
G01X-577124D02*
Y-839856D01*
G01X-544834Y-845056D02*
X-541324Y-855456D01*
X-537814Y-845056D01*
G01X-519914Y-855456D02*
Y-845056D01*
G01Y-846876D02*
X-520694Y-845836D01*
X-521864Y-845316D01*
X-523229Y-845056D01*
X-524594Y-845576D01*
X-525764Y-846616D01*
X-526544Y-848176D01*
X-526934Y-850256D01*
X-526544Y-852336D01*
X-525764Y-853896D01*
X-524594Y-854936D01*
X-523229Y-855456D01*
X-521864Y-855196D01*
X-520694Y-854416D01*
X-519914Y-853376D01*
G01X-505524Y-855456D02*
Y-839856D01*
G01X-490939Y-845056D02*
Y-852336D01*
X-490159Y-854156D01*
X-488989Y-855196D01*
X-487624Y-855456D01*
X-486259Y-855196D01*
X-485089Y-854156D01*
X-484309Y-852336D01*
G01Y-855456D02*
Y-845056D01*
G01X-472649Y-848436D02*
X-466409D01*
X-466994Y-846616D01*
X-467969Y-845576D01*
X-469334Y-845056D01*
X-470699Y-845316D01*
X-471869Y-846096D01*
X-472649Y-847916D01*
X-473039Y-849476D01*
Y-851036D01*
X-472649Y-852596D01*
X-471674Y-854156D01*
X-470504Y-855196D01*
X-469139Y-855456D01*
X-467774Y-854936D01*
X-466409Y-853376D01*
G01X-433924Y-855456D02*
X-435094Y-855196D01*
X-436264Y-854156D01*
X-437044Y-852336D01*
X-437434Y-850256D01*
X-437044Y-848176D01*
X-436264Y-846356D01*
X-435094Y-845316D01*
X-433924Y-845056D01*
X-432754Y-845316D01*
X-431584Y-846356D01*
X-430804Y-848176D01*
X-430609Y-850256D01*
X-430804Y-852336D01*
X-431584Y-854156D01*
X-432754Y-855196D01*
X-433924Y-855456D01*
G01X-417194D02*
Y-842196D01*
X-416804Y-840896D01*
X-416024Y-840116D01*
X-414854Y-839856D01*
X-413684Y-840376D01*
X-413099Y-841676D01*
G01X-415439Y-846096D02*
X-419339D01*
G01X-375934Y-841156D02*
X-377104Y-840376D01*
X-378469Y-839856D01*
X-380029D01*
X-381784Y-840636D01*
X-383149Y-841936D01*
X-384124Y-843496D01*
X-384904Y-846096D01*
X-385099Y-848436D01*
X-384709Y-850776D01*
X-384124Y-852336D01*
X-382954Y-853896D01*
X-381589Y-854936D01*
X-380224Y-855456D01*
X-378859D01*
X-377494Y-854936D01*
X-376324Y-854156D01*
X-375349Y-853116D01*
G01X-365834Y-860656D02*
Y-845056D01*
G01Y-847396D02*
X-364859Y-846096D01*
X-363884Y-845316D01*
X-362324Y-845056D01*
X-360959Y-845316D01*
X-359594Y-846616D01*
X-359009Y-848436D01*
X-358814Y-850256D01*
X-359009Y-852076D01*
X-359594Y-853896D01*
X-360764Y-854936D01*
X-362324Y-855456D01*
X-363689Y-855196D01*
X-365054Y-854416D01*
X-365834Y-853376D01*
G01X-347739Y-855456D02*
Y-839856D01*
G01X-341499Y-845056D02*
X-347739Y-851036D01*
G01X-345204Y-848696D02*
X-341109Y-855456D01*
G01X-312524D02*
X-304724Y-850256D01*
X-312524Y-845056D01*
G01X-293259Y-852596D02*
X-288189D01*
G01Y-847916D02*
X-293259D01*
G01X-272824Y-855456D02*
Y-839856D01*
X-275164Y-842976D01*
G01Y-855456D02*
X-270484D01*
G01X-254924Y-855976D02*
X-255314Y-855716D01*
Y-855196D01*
X-254924Y-854936D01*
X-254534Y-855196D01*
Y-855716D01*
X-254924Y-855976D01*
G01X-240729Y-848956D02*
X-239364Y-847136D01*
X-238194Y-846096D01*
X-236634Y-845576D01*
X-235269Y-846096D01*
X-234294Y-847136D01*
X-233514Y-848696D01*
X-233319Y-850516D01*
X-233514Y-852076D01*
X-234294Y-853636D01*
X-235464Y-854936D01*
X-236829Y-855456D01*
X-238389Y-854936D01*
X-239754Y-853376D01*
X-240534Y-851036D01*
X-240729Y-848436D01*
X-240339Y-845056D01*
X-239754Y-843236D01*
X-238779Y-841416D01*
X-237414Y-840116D01*
X-236049Y-839856D01*
X-234684Y-840376D01*
X-233709Y-841676D01*
G01X-219514Y-855456D02*
X-219124Y-852076D01*
X-218539Y-849216D01*
X-217759Y-846616D01*
X-216784Y-843756D01*
X-215224Y-839856D01*
X-223024D01*
G01X-201224Y-855976D02*
X-201614Y-855716D01*
Y-855196D01*
X-201224Y-854936D01*
X-200834Y-855196D01*
Y-855716D01*
X-201224Y-855976D01*
G01X-2077214Y-821456D02*
Y-811056D01*
G01Y-812876D02*
X-2077994Y-811836D01*
X-2079164Y-811316D01*
X-2080529Y-811056D01*
X-2081894Y-811576D01*
X-2083064Y-812616D01*
X-2083844Y-814176D01*
X-2084234Y-816256D01*
X-2083844Y-818336D01*
X-2083064Y-819896D01*
X-2081894Y-820936D01*
X-2080529Y-821456D01*
X-2079164Y-821196D01*
X-2077994Y-820416D01*
X-2077214Y-819376D01*
G01X-2066139Y-821456D02*
Y-811056D01*
G01Y-813656D02*
X-2065359Y-812356D01*
X-2064189Y-811316D01*
X-2062629Y-811056D01*
X-2061264Y-811316D01*
X-2060094Y-812356D01*
X-2059509Y-814176D01*
Y-821456D01*
G01X-2041414Y-805856D02*
Y-821456D01*
G01Y-819116D02*
X-2042194Y-820416D01*
X-2043364Y-821196D01*
X-2044729Y-821456D01*
X-2046289Y-820936D01*
X-2047459Y-819636D01*
X-2048239Y-818076D01*
X-2048434Y-816256D01*
X-2048239Y-814436D01*
X-2047459Y-812876D01*
X-2046289Y-811576D01*
X-2044729Y-811056D01*
X-2043364Y-811316D01*
X-2042389Y-811836D01*
X-2041414Y-812876D01*
G01X-2011854Y-821456D02*
Y-811056D01*
G01Y-813136D02*
X-2010879Y-812096D01*
X-2009904Y-811316D01*
X-2008539Y-811056D01*
X-2007564Y-811316D01*
X-2006394Y-812096D01*
G01X-1994149Y-814436D02*
X-1987909D01*
X-1988494Y-812616D01*
X-1989469Y-811576D01*
X-1990834Y-811056D01*
X-1992199Y-811316D01*
X-1993369Y-812096D01*
X-1994149Y-813916D01*
X-1994539Y-815476D01*
Y-817036D01*
X-1994149Y-818596D01*
X-1993174Y-820156D01*
X-1992004Y-821196D01*
X-1990639Y-821456D01*
X-1989274Y-820936D01*
X-1987909Y-819376D01*
G01X-1969814Y-826656D02*
Y-811056D01*
G01Y-813396D02*
X-1970789Y-812096D01*
X-1971959Y-811316D01*
X-1973324Y-811056D01*
X-1974494Y-811316D01*
X-1975859Y-812616D01*
X-1976639Y-814436D01*
X-1976834Y-816256D01*
X-1976639Y-818076D01*
X-1975859Y-819896D01*
X-1974494Y-821196D01*
X-1973324Y-821456D01*
X-1971959Y-821196D01*
X-1970789Y-820416D01*
X-1969814Y-819116D01*
G01X-1958739Y-811056D02*
Y-818336D01*
X-1957959Y-820156D01*
X-1956789Y-821196D01*
X-1955424Y-821456D01*
X-1954059Y-821196D01*
X-1952889Y-820156D01*
X-1952109Y-818336D01*
G01Y-821456D02*
Y-811056D01*
G01X-1937524D02*
Y-821456D01*
G01Y-806896D02*
X-1937914Y-806636D01*
Y-806116D01*
X-1937524Y-805856D01*
X-1937134Y-806116D01*
Y-806636D01*
X-1937524Y-806896D01*
G01X-1922354Y-821456D02*
Y-811056D01*
G01Y-813136D02*
X-1921379Y-812096D01*
X-1920404Y-811316D01*
X-1919039Y-811056D01*
X-1918064Y-811316D01*
X-1916894Y-812096D01*
G01X-1904649Y-814436D02*
X-1898409D01*
X-1898994Y-812616D01*
X-1899969Y-811576D01*
X-1901334Y-811056D01*
X-1902699Y-811316D01*
X-1903869Y-812096D01*
X-1904649Y-813916D01*
X-1905039Y-815476D01*
Y-817036D01*
X-1904649Y-818596D01*
X-1903674Y-820156D01*
X-1902504Y-821196D01*
X-1901139Y-821456D01*
X-1899774Y-820936D01*
X-1898409Y-819376D01*
G01X-1862414Y-821456D02*
Y-811056D01*
G01Y-812876D02*
X-1863194Y-811836D01*
X-1864364Y-811316D01*
X-1865729Y-811056D01*
X-1867094Y-811576D01*
X-1868264Y-812616D01*
X-1869044Y-814176D01*
X-1869434Y-816256D01*
X-1869044Y-818336D01*
X-1868264Y-819896D01*
X-1867094Y-820936D01*
X-1865729Y-821456D01*
X-1864364Y-821196D01*
X-1863194Y-820416D01*
X-1862414Y-819376D01*
G01X-1835974Y-821456D02*
Y-811056D01*
G01Y-813916D02*
X-1835389Y-812616D01*
X-1834414Y-811576D01*
X-1833049Y-811056D01*
X-1831684Y-811576D01*
X-1830709Y-812616D01*
X-1830124Y-813916D01*
Y-821456D01*
G01Y-813916D02*
X-1829539Y-812616D01*
X-1828564Y-811576D01*
X-1827199Y-811056D01*
X-1825834Y-811576D01*
X-1824859Y-812616D01*
X-1824274Y-814176D01*
Y-821456D01*
G01X-1812224Y-811056D02*
Y-821456D01*
G01Y-806896D02*
X-1812614Y-806636D01*
Y-806116D01*
X-1812224Y-805856D01*
X-1811834Y-806116D01*
Y-806636D01*
X-1812224Y-806896D01*
G01X-1797639Y-821456D02*
Y-811056D01*
G01Y-813656D02*
X-1796859Y-812356D01*
X-1795689Y-811316D01*
X-1794129Y-811056D01*
X-1792764Y-811316D01*
X-1791594Y-812356D01*
X-1791009Y-814176D01*
Y-821456D01*
G01X-1776424Y-811056D02*
Y-821456D01*
G01Y-806896D02*
X-1776814Y-806636D01*
Y-806116D01*
X-1776424Y-805856D01*
X-1776034Y-806116D01*
Y-806636D01*
X-1776424Y-806896D01*
G01X-1764374Y-821456D02*
Y-811056D01*
G01Y-813916D02*
X-1763789Y-812616D01*
X-1762814Y-811576D01*
X-1761449Y-811056D01*
X-1760084Y-811576D01*
X-1759109Y-812616D01*
X-1758524Y-813916D01*
Y-821456D01*
G01Y-813916D02*
X-1757939Y-812616D01*
X-1756964Y-811576D01*
X-1755599Y-811056D01*
X-1754234Y-811576D01*
X-1753259Y-812616D01*
X-1752674Y-814176D01*
Y-821456D01*
G01X-1737114D02*
Y-811056D01*
G01Y-812876D02*
X-1737894Y-811836D01*
X-1739064Y-811316D01*
X-1740429Y-811056D01*
X-1741794Y-811576D01*
X-1742964Y-812616D01*
X-1743744Y-814176D01*
X-1744134Y-816256D01*
X-1743744Y-818336D01*
X-1742964Y-819896D01*
X-1741794Y-820936D01*
X-1740429Y-821456D01*
X-1739064Y-821196D01*
X-1737894Y-820416D01*
X-1737114Y-819376D01*
G01X-1722724Y-821456D02*
Y-805856D01*
G01X-1690434Y-826656D02*
Y-811056D01*
G01Y-813396D02*
X-1689459Y-812096D01*
X-1688484Y-811316D01*
X-1686924Y-811056D01*
X-1685559Y-811316D01*
X-1684194Y-812616D01*
X-1683609Y-814436D01*
X-1683414Y-816256D01*
X-1683609Y-818076D01*
X-1684194Y-819896D01*
X-1685364Y-820936D01*
X-1686924Y-821456D01*
X-1688289Y-821196D01*
X-1689654Y-820416D01*
X-1690434Y-819376D01*
G01X-1671754Y-821456D02*
Y-811056D01*
G01Y-813136D02*
X-1670779Y-812096D01*
X-1669804Y-811316D01*
X-1668439Y-811056D01*
X-1667464Y-811316D01*
X-1666294Y-812096D01*
G01X-1651124Y-821456D02*
X-1652294Y-821196D01*
X-1653464Y-820156D01*
X-1654244Y-818336D01*
X-1654634Y-816256D01*
X-1654244Y-814176D01*
X-1653464Y-812356D01*
X-1652294Y-811316D01*
X-1651124Y-811056D01*
X-1649954Y-811316D01*
X-1648784Y-812356D01*
X-1648004Y-814176D01*
X-1647809Y-816256D01*
X-1648004Y-818336D01*
X-1648784Y-820156D01*
X-1649954Y-821196D01*
X-1651124Y-821456D01*
G01X-1630104Y-812356D02*
X-1631469Y-811316D01*
X-1632639Y-811056D01*
X-1634199Y-811576D01*
X-1635369Y-812616D01*
X-1636149Y-814436D01*
X-1636344Y-816256D01*
X-1636149Y-818076D01*
X-1635369Y-819636D01*
X-1634199Y-820936D01*
X-1632639Y-821456D01*
X-1631274Y-820936D01*
X-1630104Y-819896D01*
G01X-1618249Y-814436D02*
X-1612009D01*
X-1612594Y-812616D01*
X-1613569Y-811576D01*
X-1614934Y-811056D01*
X-1616299Y-811316D01*
X-1617469Y-812096D01*
X-1618249Y-813916D01*
X-1618639Y-815476D01*
Y-817036D01*
X-1618249Y-818596D01*
X-1617274Y-820156D01*
X-1616104Y-821196D01*
X-1614739Y-821456D01*
X-1613374Y-820936D01*
X-1612009Y-819376D01*
G01X-1600349Y-819636D02*
X-1599374Y-820676D01*
X-1598009Y-821456D01*
X-1596839D01*
X-1595669Y-820936D01*
X-1594889Y-820156D01*
X-1594499Y-819116D01*
X-1594694Y-817556D01*
X-1595474Y-816776D01*
X-1598984Y-815216D01*
X-1599764Y-813396D01*
X-1599374Y-812096D01*
X-1598594Y-811316D01*
X-1597424Y-811056D01*
X-1596254Y-811316D01*
X-1595084Y-812096D01*
G01X-1582449Y-819636D02*
X-1581474Y-820676D01*
X-1580109Y-821456D01*
X-1578939D01*
X-1577769Y-820936D01*
X-1576989Y-820156D01*
X-1576599Y-819116D01*
X-1576794Y-817556D01*
X-1577574Y-816776D01*
X-1581084Y-815216D01*
X-1581864Y-813396D01*
X-1581474Y-812096D01*
X-1580694Y-811316D01*
X-1579524Y-811056D01*
X-1578354Y-811316D01*
X-1577184Y-812096D01*
G01X-1540604Y-812356D02*
X-1541969Y-811316D01*
X-1543139Y-811056D01*
X-1544699Y-811576D01*
X-1545869Y-812616D01*
X-1546649Y-814436D01*
X-1546844Y-816256D01*
X-1546649Y-818076D01*
X-1545869Y-819636D01*
X-1544699Y-820936D01*
X-1543139Y-821456D01*
X-1541774Y-820936D01*
X-1540604Y-819896D01*
G01X-1525824Y-821456D02*
X-1526994Y-821196D01*
X-1528164Y-820156D01*
X-1528944Y-818336D01*
X-1529334Y-816256D01*
X-1528944Y-814176D01*
X-1528164Y-812356D01*
X-1526994Y-811316D01*
X-1525824Y-811056D01*
X-1524654Y-811316D01*
X-1523484Y-812356D01*
X-1522704Y-814176D01*
X-1522509Y-816256D01*
X-1522704Y-818336D01*
X-1523484Y-820156D01*
X-1524654Y-821196D01*
X-1525824Y-821456D01*
G01X-1511239D02*
Y-811056D01*
G01Y-813656D02*
X-1510459Y-812356D01*
X-1509289Y-811316D01*
X-1507729Y-811056D01*
X-1506364Y-811316D01*
X-1505194Y-812356D01*
X-1504609Y-814176D01*
Y-821456D01*
G01X-1490024Y-805856D02*
Y-821456D01*
G01X-1492754Y-811056D02*
X-1487294D01*
G01X-1474854Y-821456D02*
Y-811056D01*
G01Y-813136D02*
X-1473879Y-812096D01*
X-1472904Y-811316D01*
X-1471539Y-811056D01*
X-1470564Y-811316D01*
X-1469394Y-812096D01*
G01X-1454224Y-821456D02*
X-1455394Y-821196D01*
X-1456564Y-820156D01*
X-1457344Y-818336D01*
X-1457734Y-816256D01*
X-1457344Y-814176D01*
X-1456564Y-812356D01*
X-1455394Y-811316D01*
X-1454224Y-811056D01*
X-1453054Y-811316D01*
X-1451884Y-812356D01*
X-1451104Y-814176D01*
X-1450909Y-816256D01*
X-1451104Y-818336D01*
X-1451884Y-820156D01*
X-1453054Y-821196D01*
X-1454224Y-821456D01*
G01X-1436324D02*
Y-805856D01*
G01X-1404034Y-811056D02*
X-1400524Y-821456D01*
X-1397014Y-811056D01*
G01X-1379114Y-821456D02*
Y-811056D01*
G01Y-812876D02*
X-1379894Y-811836D01*
X-1381064Y-811316D01*
X-1382429Y-811056D01*
X-1383794Y-811576D01*
X-1384964Y-812616D01*
X-1385744Y-814176D01*
X-1386134Y-816256D01*
X-1385744Y-818336D01*
X-1384964Y-819896D01*
X-1383794Y-820936D01*
X-1382429Y-821456D01*
X-1381064Y-821196D01*
X-1379894Y-820416D01*
X-1379114Y-819376D01*
G01X-1364724Y-821456D02*
Y-805856D01*
G01X-1350139Y-811056D02*
Y-818336D01*
X-1349359Y-820156D01*
X-1348189Y-821196D01*
X-1346824Y-821456D01*
X-1345459Y-821196D01*
X-1344289Y-820156D01*
X-1343509Y-818336D01*
G01Y-821456D02*
Y-811056D01*
G01X-1331849Y-814436D02*
X-1325609D01*
X-1326194Y-812616D01*
X-1327169Y-811576D01*
X-1328534Y-811056D01*
X-1329899Y-811316D01*
X-1331069Y-812096D01*
X-1331849Y-813916D01*
X-1332239Y-815476D01*
Y-817036D01*
X-1331849Y-818596D01*
X-1330874Y-820156D01*
X-1329704Y-821196D01*
X-1328339Y-821456D01*
X-1326974Y-820936D01*
X-1325609Y-819376D01*
G01X-1293124Y-821456D02*
X-1294294Y-821196D01*
X-1295464Y-820156D01*
X-1296244Y-818336D01*
X-1296634Y-816256D01*
X-1296244Y-814176D01*
X-1295464Y-812356D01*
X-1294294Y-811316D01*
X-1293124Y-811056D01*
X-1291954Y-811316D01*
X-1290784Y-812356D01*
X-1290004Y-814176D01*
X-1289809Y-816256D01*
X-1290004Y-818336D01*
X-1290784Y-820156D01*
X-1291954Y-821196D01*
X-1293124Y-821456D01*
G01X-1276394D02*
Y-808196D01*
X-1276004Y-806896D01*
X-1275224Y-806116D01*
X-1274054Y-805856D01*
X-1272884Y-806376D01*
X-1272299Y-807676D01*
G01X-1274639Y-812096D02*
X-1278539D01*
G01X-1235134Y-807156D02*
X-1236304Y-806376D01*
X-1237669Y-805856D01*
X-1239229D01*
X-1240984Y-806636D01*
X-1242349Y-807936D01*
X-1243324Y-809496D01*
X-1244104Y-812096D01*
X-1244299Y-814436D01*
X-1243909Y-816776D01*
X-1243324Y-818336D01*
X-1242154Y-819896D01*
X-1240789Y-820936D01*
X-1239424Y-821456D01*
X-1238059D01*
X-1236694Y-820936D01*
X-1235524Y-820156D01*
X-1234549Y-819116D01*
G01X-1225034Y-826656D02*
Y-811056D01*
G01Y-813396D02*
X-1224059Y-812096D01*
X-1223084Y-811316D01*
X-1221524Y-811056D01*
X-1220159Y-811316D01*
X-1218794Y-812616D01*
X-1218209Y-814436D01*
X-1218014Y-816256D01*
X-1218209Y-818076D01*
X-1218794Y-819896D01*
X-1219964Y-820936D01*
X-1221524Y-821456D01*
X-1222889Y-821196D01*
X-1224254Y-820416D01*
X-1225034Y-819376D01*
G01X-1206939Y-821456D02*
Y-805856D01*
G01X-1200699Y-811056D02*
X-1206939Y-817036D01*
G01X-1204404Y-814696D02*
X-1200309Y-821456D01*
G01X-1171724D02*
X-1163924Y-816256D01*
X-1171724Y-811056D01*
G01X-1152459Y-818596D02*
X-1147389D01*
G01Y-813916D02*
X-1152459D01*
G01X-1132024Y-821456D02*
Y-805856D01*
X-1134364Y-808976D01*
G01Y-821456D02*
X-1129684D01*
G01X-1114124Y-821976D02*
X-1114514Y-821716D01*
Y-821196D01*
X-1114124Y-820936D01*
X-1113734Y-821196D01*
Y-821716D01*
X-1114124Y-821976D01*
G01X-1100514Y-818336D02*
X-1099344Y-820156D01*
X-1097784Y-821196D01*
X-1096029Y-821456D01*
X-1094469Y-821196D01*
X-1092909Y-819896D01*
X-1091934Y-818336D01*
X-1091739Y-816776D01*
X-1092129Y-814956D01*
X-1093494Y-813656D01*
X-1094859Y-813136D01*
X-1096614D01*
G01X-1094859D02*
X-1093689Y-812356D01*
X-1092714Y-811056D01*
X-1092324Y-809496D01*
X-1092714Y-807936D01*
X-1093689Y-806636D01*
X-1095444Y-805856D01*
X-1097199Y-806116D01*
X-1098954Y-807156D01*
G01X-1082614Y-818336D02*
X-1081444Y-820156D01*
X-1079884Y-821196D01*
X-1078129Y-821456D01*
X-1076569Y-821196D01*
X-1075009Y-819896D01*
X-1074034Y-818336D01*
X-1073839Y-816776D01*
X-1074229Y-814956D01*
X-1075594Y-813656D01*
X-1076959Y-813136D01*
X-1078714D01*
G01X-1076959D02*
X-1075789Y-812356D01*
X-1074814Y-811056D01*
X-1074424Y-809496D01*
X-1074814Y-807936D01*
X-1075789Y-806636D01*
X-1077544Y-805856D01*
X-1079299Y-806116D01*
X-1081054Y-807156D01*
G01X-1060424Y-821976D02*
X-1060814Y-821716D01*
Y-821196D01*
X-1060424Y-820936D01*
X-1060034Y-821196D01*
Y-821716D01*
X-1060424Y-821976D01*
G01X-1024624Y-805856D02*
Y-821456D01*
G01X-1029109Y-805856D02*
X-1020139D01*
G01X-1010039Y-821456D02*
Y-805856D01*
G01Y-813396D02*
X-1009064Y-812096D01*
X-1008089Y-811316D01*
X-1006529Y-811056D01*
X-1005359Y-811316D01*
X-1003994Y-812356D01*
X-1003409Y-813916D01*
Y-821456D01*
G01X-991749Y-814436D02*
X-985509D01*
X-986094Y-812616D01*
X-987069Y-811576D01*
X-988434Y-811056D01*
X-989799Y-811316D01*
X-990969Y-812096D01*
X-991749Y-813916D01*
X-992139Y-815476D01*
Y-817036D01*
X-991749Y-818596D01*
X-990774Y-820156D01*
X-989604Y-821196D01*
X-988239Y-821456D01*
X-986874Y-820936D01*
X-985509Y-819376D01*
G01X-973654Y-821456D02*
Y-811056D01*
G01Y-813136D02*
X-972679Y-812096D01*
X-971704Y-811316D01*
X-970339Y-811056D01*
X-969364Y-811316D01*
X-968194Y-812096D01*
G01X-955949Y-814436D02*
X-949709D01*
X-950294Y-812616D01*
X-951269Y-811576D01*
X-952634Y-811056D01*
X-953999Y-811316D01*
X-955169Y-812096D01*
X-955949Y-813916D01*
X-956339Y-815476D01*
Y-817036D01*
X-955949Y-818596D01*
X-954974Y-820156D01*
X-953804Y-821196D01*
X-952439Y-821456D01*
X-951074Y-820936D01*
X-949709Y-819376D01*
G01X-913714Y-821456D02*
Y-811056D01*
G01Y-812876D02*
X-914494Y-811836D01*
X-915664Y-811316D01*
X-917029Y-811056D01*
X-918394Y-811576D01*
X-919564Y-812616D01*
X-920344Y-814176D01*
X-920734Y-816256D01*
X-920344Y-818336D01*
X-919564Y-819896D01*
X-918394Y-820936D01*
X-917029Y-821456D01*
X-915664Y-821196D01*
X-914494Y-820416D01*
X-913714Y-819376D01*
G01X-902054Y-821456D02*
Y-811056D01*
G01Y-813136D02*
X-901079Y-812096D01*
X-900104Y-811316D01*
X-898739Y-811056D01*
X-897764Y-811316D01*
X-896594Y-812096D01*
G01X-884349Y-814436D02*
X-878109D01*
X-878694Y-812616D01*
X-879669Y-811576D01*
X-881034Y-811056D01*
X-882399Y-811316D01*
X-883569Y-812096D01*
X-884349Y-813916D01*
X-884739Y-815476D01*
Y-817036D01*
X-884349Y-818596D01*
X-883374Y-820156D01*
X-882204Y-821196D01*
X-880839Y-821456D01*
X-879474Y-820936D01*
X-878109Y-819376D01*
G01X-848549Y-819636D02*
X-847574Y-820676D01*
X-846209Y-821456D01*
X-845039D01*
X-843869Y-820936D01*
X-843089Y-820156D01*
X-842699Y-819116D01*
X-842894Y-817556D01*
X-843674Y-816776D01*
X-847184Y-815216D01*
X-847964Y-813396D01*
X-847574Y-812096D01*
X-846794Y-811316D01*
X-845624Y-811056D01*
X-844454Y-811316D01*
X-843284Y-812096D01*
G01X-831234Y-826656D02*
Y-811056D01*
G01Y-813396D02*
X-830259Y-812096D01*
X-829284Y-811316D01*
X-827724Y-811056D01*
X-826359Y-811316D01*
X-824994Y-812616D01*
X-824409Y-814436D01*
X-824214Y-816256D01*
X-824409Y-818076D01*
X-824994Y-819896D01*
X-826164Y-820936D01*
X-827724Y-821456D01*
X-829089Y-821196D01*
X-830454Y-820416D01*
X-831234Y-819376D01*
G01X-812749Y-814436D02*
X-806509D01*
X-807094Y-812616D01*
X-808069Y-811576D01*
X-809434Y-811056D01*
X-810799Y-811316D01*
X-811969Y-812096D01*
X-812749Y-813916D01*
X-813139Y-815476D01*
Y-817036D01*
X-812749Y-818596D01*
X-811774Y-820156D01*
X-810604Y-821196D01*
X-809239Y-821456D01*
X-807874Y-820936D01*
X-806509Y-819376D01*
G01X-788804Y-812356D02*
X-790169Y-811316D01*
X-791339Y-811056D01*
X-792899Y-811576D01*
X-794069Y-812616D01*
X-794849Y-814436D01*
X-795044Y-816256D01*
X-794849Y-818076D01*
X-794069Y-819636D01*
X-792899Y-820936D01*
X-791339Y-821456D01*
X-789974Y-820936D01*
X-788804Y-819896D01*
G01X-774024Y-811056D02*
Y-821456D01*
G01Y-806896D02*
X-774414Y-806636D01*
Y-806116D01*
X-774024Y-805856D01*
X-773634Y-806116D01*
Y-806636D01*
X-774024Y-806896D01*
G01X-757294Y-821456D02*
Y-808196D01*
X-756904Y-806896D01*
X-756124Y-806116D01*
X-754954Y-805856D01*
X-753784Y-806376D01*
X-753199Y-807676D01*
G01X-755539Y-812096D02*
X-759439D01*
G01X-738224Y-811056D02*
Y-821456D01*
G01Y-806896D02*
X-738614Y-806636D01*
Y-806116D01*
X-738224Y-805856D01*
X-737834Y-806116D01*
Y-806636D01*
X-738224Y-806896D01*
G01X-723249Y-814436D02*
X-717009D01*
X-717594Y-812616D01*
X-718569Y-811576D01*
X-719934Y-811056D01*
X-721299Y-811316D01*
X-722469Y-812096D01*
X-723249Y-813916D01*
X-723639Y-815476D01*
Y-817036D01*
X-723249Y-818596D01*
X-722274Y-820156D01*
X-721104Y-821196D01*
X-719739Y-821456D01*
X-718374Y-820936D01*
X-717009Y-819376D01*
G01X-698914Y-805856D02*
Y-821456D01*
G01Y-819116D02*
X-699694Y-820416D01*
X-700864Y-821196D01*
X-702229Y-821456D01*
X-703789Y-820936D01*
X-704959Y-819636D01*
X-705739Y-818076D01*
X-705934Y-816256D01*
X-705739Y-814436D01*
X-704959Y-812876D01*
X-703789Y-811576D01*
X-702229Y-811056D01*
X-700864Y-811316D01*
X-699889Y-811836D01*
X-698914Y-812876D01*
G01X-669354Y-821456D02*
Y-811056D01*
G01Y-813136D02*
X-668379Y-812096D01*
X-667404Y-811316D01*
X-666039Y-811056D01*
X-665064Y-811316D01*
X-663894Y-812096D01*
G01X-651649Y-814436D02*
X-645409D01*
X-645994Y-812616D01*
X-646969Y-811576D01*
X-648334Y-811056D01*
X-649699Y-811316D01*
X-650869Y-812096D01*
X-651649Y-813916D01*
X-652039Y-815476D01*
Y-817036D01*
X-651649Y-818596D01*
X-650674Y-820156D01*
X-649504Y-821196D01*
X-648139Y-821456D01*
X-646774Y-820936D01*
X-645409Y-819376D01*
G01X-627314Y-826656D02*
Y-811056D01*
G01Y-813396D02*
X-628289Y-812096D01*
X-629459Y-811316D01*
X-630824Y-811056D01*
X-631994Y-811316D01*
X-633359Y-812616D01*
X-634139Y-814436D01*
X-634334Y-816256D01*
X-634139Y-818076D01*
X-633359Y-819896D01*
X-631994Y-821196D01*
X-630824Y-821456D01*
X-629459Y-821196D01*
X-628289Y-820416D01*
X-627314Y-819116D01*
G01X-616239Y-811056D02*
Y-818336D01*
X-615459Y-820156D01*
X-614289Y-821196D01*
X-612924Y-821456D01*
X-611559Y-821196D01*
X-610389Y-820156D01*
X-609609Y-818336D01*
G01Y-821456D02*
Y-811056D01*
G01X-595024D02*
Y-821456D01*
G01Y-806896D02*
X-595414Y-806636D01*
Y-806116D01*
X-595024Y-805856D01*
X-594634Y-806116D01*
Y-806636D01*
X-595024Y-806896D01*
G01X-579854Y-821456D02*
Y-811056D01*
G01Y-813136D02*
X-578879Y-812096D01*
X-577904Y-811316D01*
X-576539Y-811056D01*
X-575564Y-811316D01*
X-574394Y-812096D01*
G01X-562149Y-814436D02*
X-555909D01*
X-556494Y-812616D01*
X-557469Y-811576D01*
X-558834Y-811056D01*
X-560199Y-811316D01*
X-561369Y-812096D01*
X-562149Y-813916D01*
X-562539Y-815476D01*
Y-817036D01*
X-562149Y-818596D01*
X-561174Y-820156D01*
X-560004Y-821196D01*
X-558639Y-821456D01*
X-557274Y-820936D01*
X-555909Y-819376D01*
G01X-547174Y-821456D02*
Y-811056D01*
G01Y-813916D02*
X-546589Y-812616D01*
X-545614Y-811576D01*
X-544249Y-811056D01*
X-542884Y-811576D01*
X-541909Y-812616D01*
X-541324Y-813916D01*
Y-821456D01*
G01Y-813916D02*
X-540739Y-812616D01*
X-539764Y-811576D01*
X-538399Y-811056D01*
X-537034Y-811576D01*
X-536059Y-812616D01*
X-535474Y-814176D01*
Y-821456D01*
G01X-526349Y-814436D02*
X-520109D01*
X-520694Y-812616D01*
X-521669Y-811576D01*
X-523034Y-811056D01*
X-524399Y-811316D01*
X-525569Y-812096D01*
X-526349Y-813916D01*
X-526739Y-815476D01*
Y-817036D01*
X-526349Y-818596D01*
X-525374Y-820156D01*
X-524204Y-821196D01*
X-522839Y-821456D01*
X-521474Y-820936D01*
X-520109Y-819376D01*
G01X-508839Y-821456D02*
Y-811056D01*
G01Y-813656D02*
X-508059Y-812356D01*
X-506889Y-811316D01*
X-505329Y-811056D01*
X-503964Y-811316D01*
X-502794Y-812356D01*
X-502209Y-814176D01*
Y-821456D01*
G01X-487624Y-805856D02*
Y-821456D01*
G01X-490354Y-811056D02*
X-484894D01*
G01X-448314Y-821456D02*
Y-811056D01*
G01Y-812876D02*
X-449094Y-811836D01*
X-450264Y-811316D01*
X-451629Y-811056D01*
X-452994Y-811576D01*
X-454164Y-812616D01*
X-454944Y-814176D01*
X-455334Y-816256D01*
X-454944Y-818336D01*
X-454164Y-819896D01*
X-452994Y-820936D01*
X-451629Y-821456D01*
X-450264Y-821196D01*
X-449094Y-820416D01*
X-448314Y-819376D01*
G01X-437434Y-821456D02*
Y-805856D01*
G01Y-813656D02*
X-436459Y-812096D01*
X-435289Y-811316D01*
X-434119Y-811056D01*
X-432364Y-811576D01*
X-431194Y-812616D01*
X-430414Y-814436D01*
Y-816516D01*
X-430804Y-818596D01*
X-431584Y-820156D01*
X-432949Y-821196D01*
X-434119Y-821456D01*
X-435289Y-821196D01*
X-436459Y-820416D01*
X-437434Y-819116D01*
G01X-416024Y-821456D02*
X-417194Y-821196D01*
X-418364Y-820156D01*
X-419144Y-818336D01*
X-419534Y-816256D01*
X-419144Y-814176D01*
X-418364Y-812356D01*
X-417194Y-811316D01*
X-416024Y-811056D01*
X-414854Y-811316D01*
X-413684Y-812356D01*
X-412904Y-814176D01*
X-412709Y-816256D01*
X-412904Y-818336D01*
X-413684Y-820156D01*
X-414854Y-821196D01*
X-416024Y-821456D01*
G01X-401439Y-811056D02*
Y-818336D01*
X-400659Y-820156D01*
X-399489Y-821196D01*
X-398124Y-821456D01*
X-396759Y-821196D01*
X-395589Y-820156D01*
X-394809Y-818336D01*
G01Y-821456D02*
Y-811056D01*
G01X-380224Y-805856D02*
Y-821456D01*
G01X-382954Y-811056D02*
X-377494D01*
G01X-2080724Y-723056D02*
Y-733456D01*
G01Y-718896D02*
X-2081114Y-718636D01*
Y-718116D01*
X-2080724Y-717856D01*
X-2080334Y-718116D01*
Y-718636D01*
X-2080724Y-718896D01*
G01X-2066139Y-733456D02*
Y-723056D01*
G01Y-725656D02*
X-2065359Y-724356D01*
X-2064189Y-723316D01*
X-2062629Y-723056D01*
X-2061264Y-723316D01*
X-2060094Y-724356D01*
X-2059509Y-726176D01*
Y-733456D01*
G01X-2030534Y-738656D02*
Y-723056D01*
G01Y-725396D02*
X-2029559Y-724096D01*
X-2028584Y-723316D01*
X-2027024Y-723056D01*
X-2025659Y-723316D01*
X-2024294Y-724616D01*
X-2023709Y-726436D01*
X-2023514Y-728256D01*
X-2023709Y-730076D01*
X-2024294Y-731896D01*
X-2025464Y-732936D01*
X-2027024Y-733456D01*
X-2028389Y-733196D01*
X-2029754Y-732416D01*
X-2030534Y-731376D01*
G01X-2011854Y-733456D02*
Y-723056D01*
G01Y-725136D02*
X-2010879Y-724096D01*
X-2009904Y-723316D01*
X-2008539Y-723056D01*
X-2007564Y-723316D01*
X-2006394Y-724096D01*
G01X-1994149Y-726436D02*
X-1987909D01*
X-1988494Y-724616D01*
X-1989469Y-723576D01*
X-1990834Y-723056D01*
X-1992199Y-723316D01*
X-1993369Y-724096D01*
X-1994149Y-725916D01*
X-1994539Y-727476D01*
Y-729036D01*
X-1994149Y-730596D01*
X-1993174Y-732156D01*
X-1992004Y-733196D01*
X-1990639Y-733456D01*
X-1989274Y-732936D01*
X-1987909Y-731376D01*
G01X-1976249Y-731636D02*
X-1975274Y-732676D01*
X-1973909Y-733456D01*
X-1972739D01*
X-1971569Y-732936D01*
X-1970789Y-732156D01*
X-1970399Y-731116D01*
X-1970594Y-729556D01*
X-1971374Y-728776D01*
X-1974884Y-727216D01*
X-1975664Y-725396D01*
X-1975274Y-724096D01*
X-1974494Y-723316D01*
X-1973324Y-723056D01*
X-1972154Y-723316D01*
X-1970984Y-724096D01*
G01X-1958349Y-731636D02*
X-1957374Y-732676D01*
X-1956009Y-733456D01*
X-1954839D01*
X-1953669Y-732936D01*
X-1952889Y-732156D01*
X-1952499Y-731116D01*
X-1952694Y-729556D01*
X-1953474Y-728776D01*
X-1956984Y-727216D01*
X-1957764Y-725396D01*
X-1957374Y-724096D01*
X-1956594Y-723316D01*
X-1955424Y-723056D01*
X-1954254Y-723316D01*
X-1953084Y-724096D01*
G01X-1940059Y-728256D02*
X-1934989D01*
G01X-1920794Y-733456D02*
Y-720196D01*
X-1920404Y-718896D01*
X-1919624Y-718116D01*
X-1918454Y-717856D01*
X-1917284Y-718376D01*
X-1916699Y-719676D01*
G01X-1919039Y-724096D02*
X-1922939D01*
G01X-1901724Y-723056D02*
Y-733456D01*
G01Y-718896D02*
X-1902114Y-718636D01*
Y-718116D01*
X-1901724Y-717856D01*
X-1901334Y-718116D01*
Y-718636D01*
X-1901724Y-718896D01*
G01X-1883824Y-717856D02*
Y-733456D01*
G01X-1886554Y-723056D02*
X-1881094D01*
G01X-1851339Y-733456D02*
Y-717856D01*
G01Y-725396D02*
X-1850364Y-724096D01*
X-1849389Y-723316D01*
X-1847829Y-723056D01*
X-1846659Y-723316D01*
X-1845294Y-724356D01*
X-1844709Y-725916D01*
Y-733456D01*
G01X-1830124D02*
X-1831294Y-733196D01*
X-1832464Y-732156D01*
X-1833244Y-730336D01*
X-1833634Y-728256D01*
X-1833244Y-726176D01*
X-1832464Y-724356D01*
X-1831294Y-723316D01*
X-1830124Y-723056D01*
X-1828954Y-723316D01*
X-1827784Y-724356D01*
X-1827004Y-726176D01*
X-1826809Y-728256D01*
X-1827004Y-730336D01*
X-1827784Y-732156D01*
X-1828954Y-733196D01*
X-1830124Y-733456D01*
G01X-1812224D02*
Y-717856D01*
G01X-1797249Y-726436D02*
X-1791009D01*
X-1791594Y-724616D01*
X-1792569Y-723576D01*
X-1793934Y-723056D01*
X-1795299Y-723316D01*
X-1796469Y-724096D01*
X-1797249Y-725916D01*
X-1797639Y-727476D01*
Y-729036D01*
X-1797249Y-730596D01*
X-1796274Y-732156D01*
X-1795104Y-733196D01*
X-1793739Y-733456D01*
X-1792374Y-732936D01*
X-1791009Y-731376D01*
G01X-1779349Y-731636D02*
X-1778374Y-732676D01*
X-1777009Y-733456D01*
X-1775839D01*
X-1774669Y-732936D01*
X-1773889Y-732156D01*
X-1773499Y-731116D01*
X-1773694Y-729556D01*
X-1774474Y-728776D01*
X-1777984Y-727216D01*
X-1778764Y-725396D01*
X-1778374Y-724096D01*
X-1777594Y-723316D01*
X-1776424Y-723056D01*
X-1775254Y-723316D01*
X-1774084Y-724096D01*
G01X-1740624Y-723056D02*
Y-733456D01*
G01Y-718896D02*
X-1741014Y-718636D01*
Y-718116D01*
X-1740624Y-717856D01*
X-1740234Y-718116D01*
Y-718636D01*
X-1740624Y-718896D01*
G01X-1726039Y-733456D02*
Y-723056D01*
G01Y-725656D02*
X-1725259Y-724356D01*
X-1724089Y-723316D01*
X-1722529Y-723056D01*
X-1721164Y-723316D01*
X-1719994Y-724356D01*
X-1719409Y-726176D01*
Y-733456D01*
G01X-1691214D02*
Y-717856D01*
X-1687314D01*
X-1685754Y-718636D01*
X-1684584Y-719676D01*
X-1683609Y-721236D01*
X-1682829Y-723056D01*
X-1682634Y-725656D01*
X-1682829Y-728256D01*
X-1683609Y-730076D01*
X-1684584Y-731636D01*
X-1685754Y-732676D01*
X-1687314Y-733456D01*
X-1691214D01*
G01X-1672729D02*
Y-717856D01*
X-1665319D01*
G01X-1668049Y-725396D02*
X-1672729D01*
G01X-1656194Y-733456D02*
Y-717856D01*
X-1651124Y-730856D01*
X-1646054Y-717856D01*
Y-733456D01*
G01X-1618054D02*
Y-723056D01*
G01Y-725136D02*
X-1617079Y-724096D01*
X-1616104Y-723316D01*
X-1614739Y-723056D01*
X-1613764Y-723316D01*
X-1612594Y-724096D01*
G01X-1600349Y-726436D02*
X-1594109D01*
X-1594694Y-724616D01*
X-1595669Y-723576D01*
X-1597034Y-723056D01*
X-1598399Y-723316D01*
X-1599569Y-724096D01*
X-1600349Y-725916D01*
X-1600739Y-727476D01*
Y-729036D01*
X-1600349Y-730596D01*
X-1599374Y-732156D01*
X-1598204Y-733196D01*
X-1596839Y-733456D01*
X-1595474Y-732936D01*
X-1594109Y-731376D01*
G01X-1583034Y-738656D02*
Y-723056D01*
G01Y-725396D02*
X-1582059Y-724096D01*
X-1581084Y-723316D01*
X-1579524Y-723056D01*
X-1578159Y-723316D01*
X-1576794Y-724616D01*
X-1576209Y-726436D01*
X-1576014Y-728256D01*
X-1576209Y-730076D01*
X-1576794Y-731896D01*
X-1577964Y-732936D01*
X-1579524Y-733456D01*
X-1580889Y-733196D01*
X-1582254Y-732416D01*
X-1583034Y-731376D01*
G01X-1561624Y-733456D02*
X-1562794Y-733196D01*
X-1563964Y-732156D01*
X-1564744Y-730336D01*
X-1565134Y-728256D01*
X-1564744Y-726176D01*
X-1563964Y-724356D01*
X-1562794Y-723316D01*
X-1561624Y-723056D01*
X-1560454Y-723316D01*
X-1559284Y-724356D01*
X-1558504Y-726176D01*
X-1558309Y-728256D01*
X-1558504Y-730336D01*
X-1559284Y-732156D01*
X-1560454Y-733196D01*
X-1561624Y-733456D01*
G01X-1546454D02*
Y-723056D01*
G01Y-725136D02*
X-1545479Y-724096D01*
X-1544504Y-723316D01*
X-1543139Y-723056D01*
X-1542164Y-723316D01*
X-1540994Y-724096D01*
G01X-1525824Y-717856D02*
Y-733456D01*
G01X-1528554Y-723056D02*
X-1523094D01*
G01X-1507924Y-733976D02*
X-1508314Y-733716D01*
Y-733196D01*
X-1507924Y-732936D01*
X-1507534Y-733196D01*
Y-733716D01*
X-1507924Y-733976D01*
G01X-2078604Y-612356D02*
X-2079969Y-611316D01*
X-2081139Y-611056D01*
X-2082699Y-611576D01*
X-2083869Y-612616D01*
X-2084649Y-614436D01*
X-2084844Y-616256D01*
X-2084649Y-618076D01*
X-2083869Y-619636D01*
X-2082699Y-620936D01*
X-2081139Y-621456D01*
X-2079774Y-620936D01*
X-2078604Y-619896D01*
G01X-2063824Y-621976D02*
X-2064214Y-621716D01*
Y-621196D01*
X-2063824Y-620936D01*
X-2063434Y-621196D01*
Y-621716D01*
X-2063824Y-621976D01*
G01X-2031924Y-621456D02*
Y-605856D01*
X-2027244D01*
X-2025684Y-606636D01*
X-2024514Y-608456D01*
X-2024124Y-610536D01*
X-2024514Y-612616D01*
X-2025489Y-614176D01*
X-2027244Y-614956D01*
X-2031924D01*
G01X-2010124Y-621456D02*
Y-605856D01*
G01X-1995149Y-614436D02*
X-1988909D01*
X-1989494Y-612616D01*
X-1990469Y-611576D01*
X-1991834Y-611056D01*
X-1993199Y-611316D01*
X-1994369Y-612096D01*
X-1995149Y-613916D01*
X-1995539Y-615476D01*
Y-617036D01*
X-1995149Y-618596D01*
X-1994174Y-620156D01*
X-1993004Y-621196D01*
X-1991639Y-621456D01*
X-1990274Y-620936D01*
X-1988909Y-619376D01*
G01X-1970814Y-621456D02*
Y-611056D01*
G01Y-612876D02*
X-1971594Y-611836D01*
X-1972764Y-611316D01*
X-1974129Y-611056D01*
X-1975494Y-611576D01*
X-1976664Y-612616D01*
X-1977444Y-614176D01*
X-1977834Y-616256D01*
X-1977444Y-618336D01*
X-1976664Y-619896D01*
X-1975494Y-620936D01*
X-1974129Y-621456D01*
X-1972764Y-621196D01*
X-1971594Y-620416D01*
X-1970814Y-619376D01*
G01X-1959349Y-619636D02*
X-1958374Y-620676D01*
X-1957009Y-621456D01*
X-1955839D01*
X-1954669Y-620936D01*
X-1953889Y-620156D01*
X-1953499Y-619116D01*
X-1953694Y-617556D01*
X-1954474Y-616776D01*
X-1957984Y-615216D01*
X-1958764Y-613396D01*
X-1958374Y-612096D01*
X-1957594Y-611316D01*
X-1956424Y-611056D01*
X-1955254Y-611316D01*
X-1954084Y-612096D01*
G01X-1941449Y-614436D02*
X-1935209D01*
X-1935794Y-612616D01*
X-1936769Y-611576D01*
X-1938134Y-611056D01*
X-1939499Y-611316D01*
X-1940669Y-612096D01*
X-1941449Y-613916D01*
X-1941839Y-615476D01*
Y-617036D01*
X-1941449Y-618596D01*
X-1940474Y-620156D01*
X-1939304Y-621196D01*
X-1937939Y-621456D01*
X-1936574Y-620936D01*
X-1935209Y-619376D01*
G01X-1905454Y-621456D02*
Y-611056D01*
G01Y-613136D02*
X-1904479Y-612096D01*
X-1903504Y-611316D01*
X-1902139Y-611056D01*
X-1901164Y-611316D01*
X-1899994Y-612096D01*
G01X-1887749Y-614436D02*
X-1881509D01*
X-1882094Y-612616D01*
X-1883069Y-611576D01*
X-1884434Y-611056D01*
X-1885799Y-611316D01*
X-1886969Y-612096D01*
X-1887749Y-613916D01*
X-1888139Y-615476D01*
Y-617036D01*
X-1887749Y-618596D01*
X-1886774Y-620156D01*
X-1885604Y-621196D01*
X-1884239Y-621456D01*
X-1882874Y-620936D01*
X-1881509Y-619376D01*
G01X-1872774Y-621456D02*
Y-611056D01*
G01Y-613916D02*
X-1872189Y-612616D01*
X-1871214Y-611576D01*
X-1869849Y-611056D01*
X-1868484Y-611576D01*
X-1867509Y-612616D01*
X-1866924Y-613916D01*
Y-621456D01*
G01Y-613916D02*
X-1866339Y-612616D01*
X-1865364Y-611576D01*
X-1863999Y-611056D01*
X-1862634Y-611576D01*
X-1861659Y-612616D01*
X-1861074Y-614176D01*
Y-621456D01*
G01X-1849024D02*
X-1850194Y-621196D01*
X-1851364Y-620156D01*
X-1852144Y-618336D01*
X-1852534Y-616256D01*
X-1852144Y-614176D01*
X-1851364Y-612356D01*
X-1850194Y-611316D01*
X-1849024Y-611056D01*
X-1847854Y-611316D01*
X-1846684Y-612356D01*
X-1845904Y-614176D01*
X-1845709Y-616256D01*
X-1845904Y-618336D01*
X-1846684Y-620156D01*
X-1847854Y-621196D01*
X-1849024Y-621456D01*
G01X-1834634Y-611056D02*
X-1831124Y-621456D01*
X-1827614Y-611056D01*
G01X-1816149Y-614436D02*
X-1809909D01*
X-1810494Y-612616D01*
X-1811469Y-611576D01*
X-1812834Y-611056D01*
X-1814199Y-611316D01*
X-1815369Y-612096D01*
X-1816149Y-613916D01*
X-1816539Y-615476D01*
Y-617036D01*
X-1816149Y-618596D01*
X-1815174Y-620156D01*
X-1814004Y-621196D01*
X-1812639Y-621456D01*
X-1811274Y-620936D01*
X-1809909Y-619376D01*
G01X-1773914Y-621456D02*
Y-611056D01*
G01Y-612876D02*
X-1774694Y-611836D01*
X-1775864Y-611316D01*
X-1777229Y-611056D01*
X-1778594Y-611576D01*
X-1779764Y-612616D01*
X-1780544Y-614176D01*
X-1780934Y-616256D01*
X-1780544Y-618336D01*
X-1779764Y-619896D01*
X-1778594Y-620936D01*
X-1777229Y-621456D01*
X-1775864Y-621196D01*
X-1774694Y-620416D01*
X-1773914Y-619376D01*
G01X-1759524Y-621456D02*
Y-605856D01*
G01X-1741624Y-621456D02*
Y-605856D01*
G01X-1705824D02*
Y-621456D01*
G01X-1708554Y-611056D02*
X-1703094D01*
G01X-1687924D02*
Y-621456D01*
G01Y-606896D02*
X-1688314Y-606636D01*
Y-606116D01*
X-1687924Y-605856D01*
X-1687534Y-606116D01*
Y-606636D01*
X-1687924Y-606896D01*
G01X-1672949Y-614436D02*
X-1666709D01*
X-1667294Y-612616D01*
X-1668269Y-611576D01*
X-1669634Y-611056D01*
X-1670999Y-611316D01*
X-1672169Y-612096D01*
X-1672949Y-613916D01*
X-1673339Y-615476D01*
Y-617036D01*
X-1672949Y-618596D01*
X-1671974Y-620156D01*
X-1670804Y-621196D01*
X-1669439Y-621456D01*
X-1668074Y-620936D01*
X-1666709Y-619376D01*
G01X-1654659Y-616256D02*
X-1649589D01*
G01X-1637734Y-621456D02*
Y-605856D01*
G01Y-613656D02*
X-1636759Y-612096D01*
X-1635589Y-611316D01*
X-1634419Y-611056D01*
X-1632664Y-611576D01*
X-1631494Y-612616D01*
X-1630714Y-614436D01*
Y-616516D01*
X-1631104Y-618596D01*
X-1631884Y-620156D01*
X-1633249Y-621196D01*
X-1634419Y-621456D01*
X-1635589Y-621196D01*
X-1636759Y-620416D01*
X-1637734Y-619116D01*
G01X-1612814Y-621456D02*
Y-611056D01*
G01Y-612876D02*
X-1613594Y-611836D01*
X-1614764Y-611316D01*
X-1616129Y-611056D01*
X-1617494Y-611576D01*
X-1618664Y-612616D01*
X-1619444Y-614176D01*
X-1619834Y-616256D01*
X-1619444Y-618336D01*
X-1618664Y-619896D01*
X-1617494Y-620936D01*
X-1616129Y-621456D01*
X-1614764Y-621196D01*
X-1613594Y-620416D01*
X-1612814Y-619376D01*
G01X-1601154Y-621456D02*
Y-611056D01*
G01Y-613136D02*
X-1600179Y-612096D01*
X-1599204Y-611316D01*
X-1597839Y-611056D01*
X-1596864Y-611316D01*
X-1595694Y-612096D01*
G01X-1565354Y-621456D02*
Y-611056D01*
G01Y-613136D02*
X-1564379Y-612096D01*
X-1563404Y-611316D01*
X-1562039Y-611056D01*
X-1561064Y-611316D01*
X-1559894Y-612096D01*
G01X-1547649Y-614436D02*
X-1541409D01*
X-1541994Y-612616D01*
X-1542969Y-611576D01*
X-1544334Y-611056D01*
X-1545699Y-611316D01*
X-1546869Y-612096D01*
X-1547649Y-613916D01*
X-1548039Y-615476D01*
Y-617036D01*
X-1547649Y-618596D01*
X-1546674Y-620156D01*
X-1545504Y-621196D01*
X-1544139Y-621456D01*
X-1542774Y-620936D01*
X-1541409Y-619376D01*
G01X-1532674Y-621456D02*
Y-611056D01*
G01Y-613916D02*
X-1532089Y-612616D01*
X-1531114Y-611576D01*
X-1529749Y-611056D01*
X-1528384Y-611576D01*
X-1527409Y-612616D01*
X-1526824Y-613916D01*
Y-621456D01*
G01Y-613916D02*
X-1526239Y-612616D01*
X-1525264Y-611576D01*
X-1523899Y-611056D01*
X-1522534Y-611576D01*
X-1521559Y-612616D01*
X-1520974Y-614176D01*
Y-621456D01*
G01X-1505414D02*
Y-611056D01*
G01Y-612876D02*
X-1506194Y-611836D01*
X-1507364Y-611316D01*
X-1508729Y-611056D01*
X-1510094Y-611576D01*
X-1511264Y-612616D01*
X-1512044Y-614176D01*
X-1512434Y-616256D01*
X-1512044Y-618336D01*
X-1511264Y-619896D01*
X-1510094Y-620936D01*
X-1508729Y-621456D01*
X-1507364Y-621196D01*
X-1506194Y-620416D01*
X-1505414Y-619376D01*
G01X-1491024Y-611056D02*
Y-621456D01*
G01Y-606896D02*
X-1491414Y-606636D01*
Y-606116D01*
X-1491024Y-605856D01*
X-1490634Y-606116D01*
Y-606636D01*
X-1491024Y-606896D01*
G01X-1476439Y-621456D02*
Y-611056D01*
G01Y-613656D02*
X-1475659Y-612356D01*
X-1474489Y-611316D01*
X-1472929Y-611056D01*
X-1471564Y-611316D01*
X-1470394Y-612356D01*
X-1469809Y-614176D01*
Y-621456D01*
G01X-1455224Y-611056D02*
Y-621456D01*
G01Y-606896D02*
X-1455614Y-606636D01*
Y-606116D01*
X-1455224Y-605856D01*
X-1454834Y-606116D01*
Y-606636D01*
X-1455224Y-606896D01*
G01X-1440639Y-621456D02*
Y-611056D01*
G01Y-613656D02*
X-1439859Y-612356D01*
X-1438689Y-611316D01*
X-1437129Y-611056D01*
X-1435764Y-611316D01*
X-1434594Y-612356D01*
X-1434009Y-614176D01*
Y-621456D01*
G01X-1422154Y-625356D02*
X-1420789Y-626396D01*
X-1419229Y-626656D01*
X-1417864Y-626396D01*
X-1416694Y-625096D01*
X-1415914Y-623276D01*
Y-611056D01*
G01Y-613136D02*
X-1416694Y-612096D01*
X-1417864Y-611316D01*
X-1419229Y-611056D01*
X-1420789Y-611576D01*
X-1421764Y-612616D01*
X-1422544Y-614436D01*
X-1422934Y-616256D01*
X-1422739Y-617816D01*
X-1421959Y-619636D01*
X-1420789Y-620936D01*
X-1419229Y-621456D01*
X-1418059Y-621196D01*
X-1416694Y-620156D01*
X-1415914Y-619116D01*
G01X-1383624Y-621456D02*
X-1384794Y-621196D01*
X-1385964Y-620156D01*
X-1386744Y-618336D01*
X-1387134Y-616256D01*
X-1386744Y-614176D01*
X-1385964Y-612356D01*
X-1384794Y-611316D01*
X-1383624Y-611056D01*
X-1382454Y-611316D01*
X-1381284Y-612356D01*
X-1380504Y-614176D01*
X-1380309Y-616256D01*
X-1380504Y-618336D01*
X-1381284Y-620156D01*
X-1382454Y-621196D01*
X-1383624Y-621456D01*
G01X-1369039D02*
Y-611056D01*
G01Y-613656D02*
X-1368259Y-612356D01*
X-1367089Y-611316D01*
X-1365529Y-611056D01*
X-1364164Y-611316D01*
X-1362994Y-612356D01*
X-1362409Y-614176D01*
Y-621456D01*
G01X-1329924D02*
X-1331094Y-621196D01*
X-1332264Y-620156D01*
X-1333044Y-618336D01*
X-1333434Y-616256D01*
X-1333044Y-614176D01*
X-1332264Y-612356D01*
X-1331094Y-611316D01*
X-1329924Y-611056D01*
X-1328754Y-611316D01*
X-1327584Y-612356D01*
X-1326804Y-614176D01*
X-1326609Y-616256D01*
X-1326804Y-618336D01*
X-1327584Y-620156D01*
X-1328754Y-621196D01*
X-1329924Y-621456D01*
G01X-1315339Y-611056D02*
Y-618336D01*
X-1314559Y-620156D01*
X-1313389Y-621196D01*
X-1312024Y-621456D01*
X-1310659Y-621196D01*
X-1309489Y-620156D01*
X-1308709Y-618336D01*
G01Y-621456D02*
Y-611056D01*
G01X-1294124Y-605856D02*
Y-621456D01*
G01X-1296854Y-611056D02*
X-1291394D01*
G01X-1279149Y-614436D02*
X-1272909D01*
X-1273494Y-612616D01*
X-1274469Y-611576D01*
X-1275834Y-611056D01*
X-1277199Y-611316D01*
X-1278369Y-612096D01*
X-1279149Y-613916D01*
X-1279539Y-615476D01*
Y-617036D01*
X-1279149Y-618596D01*
X-1278174Y-620156D01*
X-1277004Y-621196D01*
X-1275639Y-621456D01*
X-1274274Y-620936D01*
X-1272909Y-619376D01*
G01X-1261054Y-621456D02*
Y-611056D01*
G01Y-613136D02*
X-1260079Y-612096D01*
X-1259104Y-611316D01*
X-1257739Y-611056D01*
X-1256764Y-611316D01*
X-1255594Y-612096D01*
G01X-1222524Y-621456D02*
Y-605856D01*
G01X-1201114Y-621456D02*
Y-611056D01*
G01Y-612876D02*
X-1201894Y-611836D01*
X-1203064Y-611316D01*
X-1204429Y-611056D01*
X-1205794Y-611576D01*
X-1206964Y-612616D01*
X-1207744Y-614176D01*
X-1208134Y-616256D01*
X-1207744Y-618336D01*
X-1206964Y-619896D01*
X-1205794Y-620936D01*
X-1204429Y-621456D01*
X-1203064Y-621196D01*
X-1201894Y-620416D01*
X-1201114Y-619376D01*
G01X-1190819Y-626136D02*
X-1189649Y-626656D01*
X-1188089Y-626136D01*
X-1187114Y-625096D01*
X-1186334Y-623796D01*
X-1185164Y-619636D01*
X-1182629Y-611056D01*
G01X-1188869D02*
X-1185164Y-619636D01*
G01X-1171749Y-614436D02*
X-1165509D01*
X-1166094Y-612616D01*
X-1167069Y-611576D01*
X-1168434Y-611056D01*
X-1169799Y-611316D01*
X-1170969Y-612096D01*
X-1171749Y-613916D01*
X-1172139Y-615476D01*
Y-617036D01*
X-1171749Y-618596D01*
X-1170774Y-620156D01*
X-1169604Y-621196D01*
X-1168239Y-621456D01*
X-1166874Y-620936D01*
X-1165509Y-619376D01*
G01X-1153654Y-621456D02*
Y-611056D01*
G01Y-613136D02*
X-1152679Y-612096D01*
X-1151704Y-611316D01*
X-1150339Y-611056D01*
X-1149364Y-611316D01*
X-1148194Y-612096D01*
G01X-1135949Y-619636D02*
X-1134974Y-620676D01*
X-1133609Y-621456D01*
X-1132439D01*
X-1131269Y-620936D01*
X-1130489Y-620156D01*
X-1130099Y-619116D01*
X-1130294Y-617556D01*
X-1131074Y-616776D01*
X-1134584Y-615216D01*
X-1135364Y-613396D01*
X-1134974Y-612096D01*
X-1134194Y-611316D01*
X-1133024Y-611056D01*
X-1131854Y-611316D01*
X-1130684Y-612096D01*
G01X-1115124Y-621976D02*
X-1115514Y-621716D01*
Y-621196D01*
X-1115124Y-620936D01*
X-1114734Y-621196D01*
Y-621716D01*
X-1115124Y-621976D01*
G01X-2085234Y-587456D02*
Y-571856D01*
G01Y-579656D02*
X-2084259Y-578096D01*
X-2083089Y-577316D01*
X-2081919Y-577056D01*
X-2080164Y-577576D01*
X-2078994Y-578616D01*
X-2078214Y-580436D01*
Y-582516D01*
X-2078604Y-584596D01*
X-2079384Y-586156D01*
X-2080749Y-587196D01*
X-2081919Y-587456D01*
X-2083089Y-587196D01*
X-2084259Y-586416D01*
X-2085234Y-585116D01*
G01X-2063824Y-587976D02*
X-2064214Y-587716D01*
Y-587196D01*
X-2063824Y-586936D01*
X-2063434Y-587196D01*
Y-587716D01*
X-2063824Y-587976D01*
G01X-2032314Y-571856D02*
Y-583036D01*
X-2031534Y-585376D01*
X-2029974Y-586936D01*
X-2028024Y-587456D01*
X-2026074Y-586936D01*
X-2024514Y-585376D01*
X-2023734Y-583036D01*
Y-571856D01*
G01X-2013049Y-585636D02*
X-2012074Y-586676D01*
X-2010709Y-587456D01*
X-2009539D01*
X-2008369Y-586936D01*
X-2007589Y-586156D01*
X-2007199Y-585116D01*
X-2007394Y-583556D01*
X-2008174Y-582776D01*
X-2011684Y-581216D01*
X-2012464Y-579396D01*
X-2012074Y-578096D01*
X-2011294Y-577316D01*
X-2010124Y-577056D01*
X-2008954Y-577316D01*
X-2007784Y-578096D01*
G01X-1995149Y-580436D02*
X-1988909D01*
X-1989494Y-578616D01*
X-1990469Y-577576D01*
X-1991834Y-577056D01*
X-1993199Y-577316D01*
X-1994369Y-578096D01*
X-1995149Y-579916D01*
X-1995539Y-581476D01*
Y-583036D01*
X-1995149Y-584596D01*
X-1994174Y-586156D01*
X-1993004Y-587196D01*
X-1991639Y-587456D01*
X-1990274Y-586936D01*
X-1988909Y-585376D01*
G01X-1961299Y-587456D02*
X-1956424Y-571856D01*
X-1951549Y-587456D01*
G01X-1953304Y-581996D02*
X-1959544D01*
G01X-1926474Y-587456D02*
Y-577056D01*
G01Y-579916D02*
X-1925889Y-578616D01*
X-1924914Y-577576D01*
X-1923549Y-577056D01*
X-1922184Y-577576D01*
X-1921209Y-578616D01*
X-1920624Y-579916D01*
Y-587456D01*
G01Y-579916D02*
X-1920039Y-578616D01*
X-1919064Y-577576D01*
X-1917699Y-577056D01*
X-1916334Y-577576D01*
X-1915359Y-578616D01*
X-1914774Y-580176D01*
Y-587456D01*
G01X-1902724Y-577056D02*
Y-587456D01*
G01Y-572896D02*
X-1903114Y-572636D01*
Y-572116D01*
X-1902724Y-571856D01*
X-1902334Y-572116D01*
Y-572636D01*
X-1902724Y-572896D01*
G01X-1888139Y-587456D02*
Y-577056D01*
G01Y-579656D02*
X-1887359Y-578356D01*
X-1886189Y-577316D01*
X-1884629Y-577056D01*
X-1883264Y-577316D01*
X-1882094Y-578356D01*
X-1881509Y-580176D01*
Y-587456D01*
G01X-1866924Y-577056D02*
Y-587456D01*
G01Y-572896D02*
X-1867314Y-572636D01*
Y-572116D01*
X-1866924Y-571856D01*
X-1866534Y-572116D01*
Y-572636D01*
X-1866924Y-572896D01*
G01X-1854874Y-587456D02*
Y-577056D01*
G01Y-579916D02*
X-1854289Y-578616D01*
X-1853314Y-577576D01*
X-1851949Y-577056D01*
X-1850584Y-577576D01*
X-1849609Y-578616D01*
X-1849024Y-579916D01*
Y-587456D01*
G01Y-579916D02*
X-1848439Y-578616D01*
X-1847464Y-577576D01*
X-1846099Y-577056D01*
X-1844734Y-577576D01*
X-1843759Y-578616D01*
X-1843174Y-580176D01*
Y-587456D01*
G01X-1834439Y-577056D02*
Y-584336D01*
X-1833659Y-586156D01*
X-1832489Y-587196D01*
X-1831124Y-587456D01*
X-1829759Y-587196D01*
X-1828589Y-586156D01*
X-1827809Y-584336D01*
G01Y-587456D02*
Y-577056D01*
G01X-1819074Y-587456D02*
Y-577056D01*
G01Y-579916D02*
X-1818489Y-578616D01*
X-1817514Y-577576D01*
X-1816149Y-577056D01*
X-1814784Y-577576D01*
X-1813809Y-578616D01*
X-1813224Y-579916D01*
Y-587456D01*
G01Y-579916D02*
X-1812639Y-578616D01*
X-1811664Y-577576D01*
X-1810299Y-577056D01*
X-1808934Y-577576D01*
X-1807959Y-578616D01*
X-1807374Y-580176D01*
Y-587456D01*
G01X-1780349Y-585636D02*
X-1779374Y-586676D01*
X-1778009Y-587456D01*
X-1776839D01*
X-1775669Y-586936D01*
X-1774889Y-586156D01*
X-1774499Y-585116D01*
X-1774694Y-583556D01*
X-1775474Y-582776D01*
X-1778984Y-581216D01*
X-1779764Y-579396D01*
X-1779374Y-578096D01*
X-1778594Y-577316D01*
X-1777424Y-577056D01*
X-1776254Y-577316D01*
X-1775084Y-578096D01*
G01X-1763034Y-592656D02*
Y-577056D01*
G01Y-579396D02*
X-1762059Y-578096D01*
X-1761084Y-577316D01*
X-1759524Y-577056D01*
X-1758159Y-577316D01*
X-1756794Y-578616D01*
X-1756209Y-580436D01*
X-1756014Y-582256D01*
X-1756209Y-584076D01*
X-1756794Y-585896D01*
X-1757964Y-586936D01*
X-1759524Y-587456D01*
X-1760889Y-587196D01*
X-1762254Y-586416D01*
X-1763034Y-585376D01*
G01X-1744549Y-580436D02*
X-1738309D01*
X-1738894Y-578616D01*
X-1739869Y-577576D01*
X-1741234Y-577056D01*
X-1742599Y-577316D01*
X-1743769Y-578096D01*
X-1744549Y-579916D01*
X-1744939Y-581476D01*
Y-583036D01*
X-1744549Y-584596D01*
X-1743574Y-586156D01*
X-1742404Y-587196D01*
X-1741039Y-587456D01*
X-1739674Y-586936D01*
X-1738309Y-585376D01*
G01X-1720604Y-578356D02*
X-1721969Y-577316D01*
X-1723139Y-577056D01*
X-1724699Y-577576D01*
X-1725869Y-578616D01*
X-1726649Y-580436D01*
X-1726844Y-582256D01*
X-1726649Y-584076D01*
X-1725869Y-585636D01*
X-1724699Y-586936D01*
X-1723139Y-587456D01*
X-1721774Y-586936D01*
X-1720604Y-585896D01*
G01X-1705824Y-577056D02*
Y-587456D01*
G01Y-572896D02*
X-1706214Y-572636D01*
Y-572116D01*
X-1705824Y-571856D01*
X-1705434Y-572116D01*
Y-572636D01*
X-1705824Y-572896D01*
G01X-1689094Y-587456D02*
Y-574196D01*
X-1688704Y-572896D01*
X-1687924Y-572116D01*
X-1686754Y-571856D01*
X-1685584Y-572376D01*
X-1684999Y-573676D01*
G01X-1687339Y-578096D02*
X-1691239D01*
G01X-1670024Y-577056D02*
Y-587456D01*
G01Y-572896D02*
X-1670414Y-572636D01*
Y-572116D01*
X-1670024Y-571856D01*
X-1669634Y-572116D01*
Y-572636D01*
X-1670024Y-572896D01*
G01X-1655049Y-580436D02*
X-1648809D01*
X-1649394Y-578616D01*
X-1650369Y-577576D01*
X-1651734Y-577056D01*
X-1653099Y-577316D01*
X-1654269Y-578096D01*
X-1655049Y-579916D01*
X-1655439Y-581476D01*
Y-583036D01*
X-1655049Y-584596D01*
X-1654074Y-586156D01*
X-1652904Y-587196D01*
X-1651539Y-587456D01*
X-1650174Y-586936D01*
X-1648809Y-585376D01*
G01X-1630714Y-571856D02*
Y-587456D01*
G01Y-585116D02*
X-1631494Y-586416D01*
X-1632664Y-587196D01*
X-1634029Y-587456D01*
X-1635589Y-586936D01*
X-1636759Y-585636D01*
X-1637539Y-584076D01*
X-1637734Y-582256D01*
X-1637539Y-580436D01*
X-1636759Y-578876D01*
X-1635589Y-577576D01*
X-1634029Y-577056D01*
X-1632664Y-577316D01*
X-1631689Y-577836D01*
X-1630714Y-578876D01*
G01X-1601154Y-591356D02*
X-1599789Y-592396D01*
X-1598229Y-592656D01*
X-1596864Y-592396D01*
X-1595694Y-591096D01*
X-1594914Y-589276D01*
Y-577056D01*
G01Y-579136D02*
X-1595694Y-578096D01*
X-1596864Y-577316D01*
X-1598229Y-577056D01*
X-1599789Y-577576D01*
X-1600764Y-578616D01*
X-1601544Y-580436D01*
X-1601934Y-582256D01*
X-1601739Y-583816D01*
X-1600959Y-585636D01*
X-1599789Y-586936D01*
X-1598229Y-587456D01*
X-1597059Y-587196D01*
X-1595694Y-586156D01*
X-1594914Y-585116D01*
G01X-1580524Y-587456D02*
X-1581694Y-587196D01*
X-1582864Y-586156D01*
X-1583644Y-584336D01*
X-1584034Y-582256D01*
X-1583644Y-580176D01*
X-1582864Y-578356D01*
X-1581694Y-577316D01*
X-1580524Y-577056D01*
X-1579354Y-577316D01*
X-1578184Y-578356D01*
X-1577404Y-580176D01*
X-1577209Y-582256D01*
X-1577404Y-584336D01*
X-1578184Y-586156D01*
X-1579354Y-587196D01*
X-1580524Y-587456D01*
G01X-1562624D02*
Y-571856D01*
G01X-1541214D02*
Y-587456D01*
G01Y-585116D02*
X-1541994Y-586416D01*
X-1543164Y-587196D01*
X-1544529Y-587456D01*
X-1546089Y-586936D01*
X-1547259Y-585636D01*
X-1548039Y-584076D01*
X-1548234Y-582256D01*
X-1548039Y-580436D01*
X-1547259Y-578876D01*
X-1546089Y-577576D01*
X-1544529Y-577056D01*
X-1543164Y-577316D01*
X-1542189Y-577836D01*
X-1541214Y-578876D01*
G01X-1508924Y-571856D02*
Y-587456D01*
G01X-1511654Y-577056D02*
X-1506194D01*
G01X-1494339Y-587456D02*
Y-571856D01*
G01Y-579396D02*
X-1493364Y-578096D01*
X-1492389Y-577316D01*
X-1490829Y-577056D01*
X-1489659Y-577316D01*
X-1488294Y-578356D01*
X-1487709Y-579916D01*
Y-587456D01*
G01X-1473124Y-577056D02*
Y-587456D01*
G01Y-572896D02*
X-1473514Y-572636D01*
Y-572116D01*
X-1473124Y-571856D01*
X-1472734Y-572116D01*
Y-572636D01*
X-1473124Y-572896D01*
G01X-1458539Y-587456D02*
Y-577056D01*
G01Y-579656D02*
X-1457759Y-578356D01*
X-1456589Y-577316D01*
X-1455029Y-577056D01*
X-1453664Y-577316D01*
X-1452494Y-578356D01*
X-1451909Y-580176D01*
Y-587456D01*
G01X-1434204Y-578356D02*
X-1435569Y-577316D01*
X-1436739Y-577056D01*
X-1438299Y-577576D01*
X-1439469Y-578616D01*
X-1440249Y-580436D01*
X-1440444Y-582256D01*
X-1440249Y-584076D01*
X-1439469Y-585636D01*
X-1438299Y-586936D01*
X-1436739Y-587456D01*
X-1435374Y-586936D01*
X-1434204Y-585896D01*
G01X-1422739Y-587456D02*
Y-577056D01*
G01Y-579656D02*
X-1421959Y-578356D01*
X-1420789Y-577316D01*
X-1419229Y-577056D01*
X-1417864Y-577316D01*
X-1416694Y-578356D01*
X-1416109Y-580176D01*
Y-587456D01*
G01X-1404449Y-580436D02*
X-1398209D01*
X-1398794Y-578616D01*
X-1399769Y-577576D01*
X-1401134Y-577056D01*
X-1402499Y-577316D01*
X-1403669Y-578096D01*
X-1404449Y-579916D01*
X-1404839Y-581476D01*
Y-583036D01*
X-1404449Y-584596D01*
X-1403474Y-586156D01*
X-1402304Y-587196D01*
X-1400939Y-587456D01*
X-1399574Y-586936D01*
X-1398209Y-585376D01*
G01X-1386549Y-585636D02*
X-1385574Y-586676D01*
X-1384209Y-587456D01*
X-1383039D01*
X-1381869Y-586936D01*
X-1381089Y-586156D01*
X-1380699Y-585116D01*
X-1380894Y-583556D01*
X-1381674Y-582776D01*
X-1385184Y-581216D01*
X-1385964Y-579396D01*
X-1385574Y-578096D01*
X-1384794Y-577316D01*
X-1383624Y-577056D01*
X-1382454Y-577316D01*
X-1381284Y-578096D01*
G01X-1368649Y-585636D02*
X-1367674Y-586676D01*
X-1366309Y-587456D01*
X-1365139D01*
X-1363969Y-586936D01*
X-1363189Y-586156D01*
X-1362799Y-585116D01*
X-1362994Y-583556D01*
X-1363774Y-582776D01*
X-1367284Y-581216D01*
X-1368064Y-579396D01*
X-1367674Y-578096D01*
X-1366894Y-577316D01*
X-1365724Y-577056D01*
X-1364554Y-577316D01*
X-1363384Y-578096D01*
G01X-1329924Y-587456D02*
X-1331094Y-587196D01*
X-1332264Y-586156D01*
X-1333044Y-584336D01*
X-1333434Y-582256D01*
X-1333044Y-580176D01*
X-1332264Y-578356D01*
X-1331094Y-577316D01*
X-1329924Y-577056D01*
X-1328754Y-577316D01*
X-1327584Y-578356D01*
X-1326804Y-580176D01*
X-1326609Y-582256D01*
X-1326804Y-584336D01*
X-1327584Y-586156D01*
X-1328754Y-587196D01*
X-1329924Y-587456D01*
G01X-1315339D02*
Y-577056D01*
G01Y-579656D02*
X-1314559Y-578356D01*
X-1313389Y-577316D01*
X-1311829Y-577056D01*
X-1310464Y-577316D01*
X-1309294Y-578356D01*
X-1308709Y-580176D01*
Y-587456D01*
G01X-1278954Y-591356D02*
X-1277589Y-592396D01*
X-1276029Y-592656D01*
X-1274664Y-592396D01*
X-1273494Y-591096D01*
X-1272714Y-589276D01*
Y-577056D01*
G01Y-579136D02*
X-1273494Y-578096D01*
X-1274664Y-577316D01*
X-1276029Y-577056D01*
X-1277589Y-577576D01*
X-1278564Y-578616D01*
X-1279344Y-580436D01*
X-1279734Y-582256D01*
X-1279539Y-583816D01*
X-1278759Y-585636D01*
X-1277589Y-586936D01*
X-1276029Y-587456D01*
X-1274859Y-587196D01*
X-1273494Y-586156D01*
X-1272714Y-585116D01*
G01X-1258324Y-587456D02*
X-1259494Y-587196D01*
X-1260664Y-586156D01*
X-1261444Y-584336D01*
X-1261834Y-582256D01*
X-1261444Y-580176D01*
X-1260664Y-578356D01*
X-1259494Y-577316D01*
X-1258324Y-577056D01*
X-1257154Y-577316D01*
X-1255984Y-578356D01*
X-1255204Y-580176D01*
X-1255009Y-582256D01*
X-1255204Y-584336D01*
X-1255984Y-586156D01*
X-1257154Y-587196D01*
X-1258324Y-587456D01*
G01X-1240424D02*
Y-571856D01*
G01X-1219014D02*
Y-587456D01*
G01Y-585116D02*
X-1219794Y-586416D01*
X-1220964Y-587196D01*
X-1222329Y-587456D01*
X-1223889Y-586936D01*
X-1225059Y-585636D01*
X-1225839Y-584076D01*
X-1226034Y-582256D01*
X-1225839Y-580436D01*
X-1225059Y-578876D01*
X-1223889Y-577576D01*
X-1222329Y-577056D01*
X-1220964Y-577316D01*
X-1219989Y-577836D01*
X-1219014Y-578876D01*
G01X-1187894Y-587456D02*
Y-574196D01*
X-1187504Y-572896D01*
X-1186724Y-572116D01*
X-1185554Y-571856D01*
X-1184384Y-572376D01*
X-1183799Y-573676D01*
G01X-1186139Y-578096D02*
X-1190039D01*
G01X-1168824Y-577056D02*
Y-587456D01*
G01Y-572896D02*
X-1169214Y-572636D01*
Y-572116D01*
X-1168824Y-571856D01*
X-1168434Y-572116D01*
Y-572636D01*
X-1168824Y-572896D01*
G01X-1154239Y-587456D02*
Y-577056D01*
G01Y-579656D02*
X-1153459Y-578356D01*
X-1152289Y-577316D01*
X-1150729Y-577056D01*
X-1149364Y-577316D01*
X-1148194Y-578356D01*
X-1147609Y-580176D01*
Y-587456D01*
G01X-1135754Y-591356D02*
X-1134389Y-592396D01*
X-1132829Y-592656D01*
X-1131464Y-592396D01*
X-1130294Y-591096D01*
X-1129514Y-589276D01*
Y-577056D01*
G01Y-579136D02*
X-1130294Y-578096D01*
X-1131464Y-577316D01*
X-1132829Y-577056D01*
X-1134389Y-577576D01*
X-1135364Y-578616D01*
X-1136144Y-580436D01*
X-1136534Y-582256D01*
X-1136339Y-583816D01*
X-1135559Y-585636D01*
X-1134389Y-586936D01*
X-1132829Y-587456D01*
X-1131659Y-587196D01*
X-1130294Y-586156D01*
X-1129514Y-585116D01*
G01X-1118049Y-580436D02*
X-1111809D01*
X-1112394Y-578616D01*
X-1113369Y-577576D01*
X-1114734Y-577056D01*
X-1116099Y-577316D01*
X-1117269Y-578096D01*
X-1118049Y-579916D01*
X-1118439Y-581476D01*
Y-583036D01*
X-1118049Y-584596D01*
X-1117074Y-586156D01*
X-1115904Y-587196D01*
X-1114539Y-587456D01*
X-1113174Y-586936D01*
X-1111809Y-585376D01*
G01X-1099954Y-587456D02*
Y-577056D01*
G01Y-579136D02*
X-1098979Y-578096D01*
X-1098004Y-577316D01*
X-1096639Y-577056D01*
X-1095664Y-577316D01*
X-1094494Y-578096D01*
G01X-1061424Y-571856D02*
Y-587456D01*
G01X-1064154Y-577056D02*
X-1058694D01*
G01X-1040014Y-587456D02*
Y-577056D01*
G01Y-578876D02*
X-1040794Y-577836D01*
X-1041964Y-577316D01*
X-1043329Y-577056D01*
X-1044694Y-577576D01*
X-1045864Y-578616D01*
X-1046644Y-580176D01*
X-1047034Y-582256D01*
X-1046644Y-584336D01*
X-1045864Y-585896D01*
X-1044694Y-586936D01*
X-1043329Y-587456D01*
X-1041964Y-587196D01*
X-1040794Y-586416D01*
X-1040014Y-585376D01*
G01X-1029134Y-587456D02*
Y-571856D01*
G01Y-579656D02*
X-1028159Y-578096D01*
X-1026989Y-577316D01*
X-1025819Y-577056D01*
X-1024064Y-577576D01*
X-1022894Y-578616D01*
X-1022114Y-580436D01*
Y-582516D01*
X-1022504Y-584596D01*
X-1023284Y-586156D01*
X-1024649Y-587196D01*
X-1025819Y-587456D01*
X-1026989Y-587196D01*
X-1028159Y-586416D01*
X-1029134Y-585116D01*
G01X-1010649Y-585636D02*
X-1009674Y-586676D01*
X-1008309Y-587456D01*
X-1007139D01*
X-1005969Y-586936D01*
X-1005189Y-586156D01*
X-1004799Y-585116D01*
X-1004994Y-583556D01*
X-1005774Y-582776D01*
X-1009284Y-581216D01*
X-1010064Y-579396D01*
X-1009674Y-578096D01*
X-1008894Y-577316D01*
X-1007724Y-577056D01*
X-1006554Y-577316D01*
X-1005384Y-578096D01*
G01X-971924Y-587456D02*
X-973094Y-587196D01*
X-974264Y-586156D01*
X-975044Y-584336D01*
X-975434Y-582256D01*
X-975044Y-580176D01*
X-974264Y-578356D01*
X-973094Y-577316D01*
X-971924Y-577056D01*
X-970754Y-577316D01*
X-969584Y-578356D01*
X-968804Y-580176D01*
X-968609Y-582256D01*
X-968804Y-584336D01*
X-969584Y-586156D01*
X-970754Y-587196D01*
X-971924Y-587456D01*
G01X-955194D02*
Y-574196D01*
X-954804Y-572896D01*
X-954024Y-572116D01*
X-952854Y-571856D01*
X-951684Y-572376D01*
X-951099Y-573676D01*
G01X-953439Y-578096D02*
X-957339D01*
G01X-918224Y-571856D02*
X-919784Y-572376D01*
X-920954Y-573676D01*
X-921734Y-575236D01*
X-922319Y-577316D01*
X-922514Y-579656D01*
X-922319Y-581996D01*
X-921734Y-584076D01*
X-920954Y-585636D01*
X-919784Y-586936D01*
X-918224Y-587456D01*
X-916664Y-586936D01*
X-915494Y-585636D01*
X-914714Y-584076D01*
X-914129Y-581996D01*
X-913934Y-579656D01*
X-914129Y-577316D01*
X-914714Y-575236D01*
X-915494Y-573676D01*
X-916664Y-572376D01*
X-918224Y-571856D01*
G01X-900324Y-587976D02*
X-900714Y-587716D01*
Y-587196D01*
X-900324Y-586936D01*
X-899934Y-587196D01*
Y-587716D01*
X-900324Y-587976D01*
G01X-882814Y-587456D02*
X-882424Y-584076D01*
X-881839Y-581216D01*
X-881059Y-578616D01*
X-880084Y-575756D01*
X-878524Y-571856D01*
X-886324D01*
G01X-868229Y-580956D02*
X-866864Y-579136D01*
X-865694Y-578096D01*
X-864134Y-577576D01*
X-862769Y-578096D01*
X-861794Y-579136D01*
X-861014Y-580696D01*
X-860819Y-582516D01*
X-861014Y-584076D01*
X-861794Y-585636D01*
X-862964Y-586936D01*
X-864329Y-587456D01*
X-865889Y-586936D01*
X-867254Y-585376D01*
X-868034Y-583036D01*
X-868229Y-580436D01*
X-867839Y-577056D01*
X-867254Y-575236D01*
X-866279Y-573416D01*
X-864914Y-572116D01*
X-863549Y-571856D01*
X-862184Y-572376D01*
X-861209Y-573676D01*
G01X-849939Y-577056D02*
Y-584336D01*
X-849159Y-586156D01*
X-847989Y-587196D01*
X-846624Y-587456D01*
X-845259Y-587196D01*
X-844089Y-586156D01*
X-843309Y-584336D01*
G01Y-587456D02*
Y-577056D01*
G01X-834574Y-587456D02*
Y-577056D01*
G01Y-579916D02*
X-833989Y-578616D01*
X-833014Y-577576D01*
X-831649Y-577056D01*
X-830284Y-577576D01*
X-829309Y-578616D01*
X-828724Y-579916D01*
Y-587456D01*
G01Y-579916D02*
X-828139Y-578616D01*
X-827164Y-577576D01*
X-825799Y-577056D01*
X-824434Y-577576D01*
X-823459Y-578616D01*
X-822874Y-580176D01*
Y-587456D01*
G01X-793899Y-592656D02*
X-795849Y-590056D01*
X-796824Y-587456D01*
Y-577056D01*
X-795849Y-574456D01*
X-793899Y-571856D01*
G01X-779314Y-584336D02*
X-778144Y-586156D01*
X-776584Y-587196D01*
X-774829Y-587456D01*
X-773269Y-587196D01*
X-771709Y-585896D01*
X-770734Y-584336D01*
X-770539Y-582776D01*
X-770929Y-580956D01*
X-772294Y-579656D01*
X-773659Y-579136D01*
X-775414D01*
G01X-773659D02*
X-772489Y-578356D01*
X-771514Y-577056D01*
X-771124Y-575496D01*
X-771514Y-573936D01*
X-772489Y-572636D01*
X-774244Y-571856D01*
X-775999Y-572116D01*
X-777754Y-573156D01*
G01X-757124Y-571856D02*
X-758684Y-572376D01*
X-759854Y-573676D01*
X-760634Y-575236D01*
X-761219Y-577316D01*
X-761414Y-579656D01*
X-761219Y-581996D01*
X-760634Y-584076D01*
X-759854Y-585636D01*
X-758684Y-586936D01*
X-757124Y-587456D01*
X-755564Y-586936D01*
X-754394Y-585636D01*
X-753614Y-584076D01*
X-753029Y-581996D01*
X-752834Y-579656D01*
X-753029Y-577316D01*
X-753614Y-575236D01*
X-754394Y-573676D01*
X-755564Y-572376D01*
X-757124Y-571856D01*
G01X-727174Y-587456D02*
Y-577056D01*
G01Y-579916D02*
X-726589Y-578616D01*
X-725614Y-577576D01*
X-724249Y-577056D01*
X-722884Y-577576D01*
X-721909Y-578616D01*
X-721324Y-579916D01*
Y-587456D01*
G01Y-579916D02*
X-720739Y-578616D01*
X-719764Y-577576D01*
X-718399Y-577056D01*
X-717034Y-577576D01*
X-716059Y-578616D01*
X-715474Y-580176D01*
Y-587456D01*
G01X-703424Y-577056D02*
Y-587456D01*
G01Y-572896D02*
X-703814Y-572636D01*
Y-572116D01*
X-703424Y-571856D01*
X-703034Y-572116D01*
Y-572636D01*
X-703424Y-572896D01*
G01X-682404Y-578356D02*
X-683769Y-577316D01*
X-684939Y-577056D01*
X-686499Y-577576D01*
X-687669Y-578616D01*
X-688449Y-580436D01*
X-688644Y-582256D01*
X-688449Y-584076D01*
X-687669Y-585636D01*
X-686499Y-586936D01*
X-684939Y-587456D01*
X-683574Y-586936D01*
X-682404Y-585896D01*
G01X-670354Y-587456D02*
Y-577056D01*
G01Y-579136D02*
X-669379Y-578096D01*
X-668404Y-577316D01*
X-667039Y-577056D01*
X-666064Y-577316D01*
X-664894Y-578096D01*
G01X-649724Y-587456D02*
X-650894Y-587196D01*
X-652064Y-586156D01*
X-652844Y-584336D01*
X-653234Y-582256D01*
X-652844Y-580176D01*
X-652064Y-578356D01*
X-650894Y-577316D01*
X-649724Y-577056D01*
X-648554Y-577316D01*
X-647384Y-578356D01*
X-646604Y-580176D01*
X-646409Y-582256D01*
X-646604Y-584336D01*
X-647384Y-586156D01*
X-648554Y-587196D01*
X-649724Y-587456D01*
G01X-613924Y-577056D02*
Y-587456D01*
G01Y-572896D02*
X-614314Y-572636D01*
Y-572116D01*
X-613924Y-571856D01*
X-613534Y-572116D01*
Y-572636D01*
X-613924Y-572896D01*
G01X-599339Y-587456D02*
Y-577056D01*
G01Y-579656D02*
X-598559Y-578356D01*
X-597389Y-577316D01*
X-595829Y-577056D01*
X-594464Y-577316D01*
X-593294Y-578356D01*
X-592709Y-580176D01*
Y-587456D01*
G01X-575004Y-578356D02*
X-576369Y-577316D01*
X-577539Y-577056D01*
X-579099Y-577576D01*
X-580269Y-578616D01*
X-581049Y-580436D01*
X-581244Y-582256D01*
X-581049Y-584076D01*
X-580269Y-585636D01*
X-579099Y-586936D01*
X-577539Y-587456D01*
X-576174Y-586936D01*
X-575004Y-585896D01*
G01X-563539Y-587456D02*
Y-571856D01*
G01Y-579396D02*
X-562564Y-578096D01*
X-561589Y-577316D01*
X-560029Y-577056D01*
X-558859Y-577316D01*
X-557494Y-578356D01*
X-556909Y-579916D01*
Y-587456D01*
G01X-541349Y-592656D02*
X-539399Y-590056D01*
X-538424Y-587456D01*
Y-577056D01*
X-539399Y-574456D01*
X-541349Y-571856D01*
G01X-524424Y-587976D02*
X-524814Y-587716D01*
Y-587196D01*
X-524424Y-586936D01*
X-524034Y-587196D01*
Y-587716D01*
X-524424Y-587976D01*
G01X-2078214Y-553456D02*
Y-543056D01*
G01Y-544876D02*
X-2078994Y-543836D01*
X-2080164Y-543316D01*
X-2081529Y-543056D01*
X-2082894Y-543576D01*
X-2084064Y-544616D01*
X-2084844Y-546176D01*
X-2085234Y-548256D01*
X-2084844Y-550336D01*
X-2084064Y-551896D01*
X-2082894Y-552936D01*
X-2081529Y-553456D01*
X-2080164Y-553196D01*
X-2078994Y-552416D01*
X-2078214Y-551376D01*
G01X-2063824Y-553976D02*
X-2064214Y-553716D01*
Y-553196D01*
X-2063824Y-552936D01*
X-2063434Y-553196D01*
Y-553716D01*
X-2063824Y-553976D01*
G01X-2031924Y-553456D02*
Y-537856D01*
X-2027244D01*
X-2025684Y-538636D01*
X-2024514Y-540456D01*
X-2024124Y-542536D01*
X-2024514Y-544616D01*
X-2025489Y-546176D01*
X-2027244Y-546956D01*
X-2031924D01*
G01X-2010124Y-553456D02*
Y-537856D01*
G01X-1995149Y-546436D02*
X-1988909D01*
X-1989494Y-544616D01*
X-1990469Y-543576D01*
X-1991834Y-543056D01*
X-1993199Y-543316D01*
X-1994369Y-544096D01*
X-1995149Y-545916D01*
X-1995539Y-547476D01*
Y-549036D01*
X-1995149Y-550596D01*
X-1994174Y-552156D01*
X-1993004Y-553196D01*
X-1991639Y-553456D01*
X-1990274Y-552936D01*
X-1988909Y-551376D01*
G01X-1970814Y-553456D02*
Y-543056D01*
G01Y-544876D02*
X-1971594Y-543836D01*
X-1972764Y-543316D01*
X-1974129Y-543056D01*
X-1975494Y-543576D01*
X-1976664Y-544616D01*
X-1977444Y-546176D01*
X-1977834Y-548256D01*
X-1977444Y-550336D01*
X-1976664Y-551896D01*
X-1975494Y-552936D01*
X-1974129Y-553456D01*
X-1972764Y-553196D01*
X-1971594Y-552416D01*
X-1970814Y-551376D01*
G01X-1959349Y-551636D02*
X-1958374Y-552676D01*
X-1957009Y-553456D01*
X-1955839D01*
X-1954669Y-552936D01*
X-1953889Y-552156D01*
X-1953499Y-551116D01*
X-1953694Y-549556D01*
X-1954474Y-548776D01*
X-1957984Y-547216D01*
X-1958764Y-545396D01*
X-1958374Y-544096D01*
X-1957594Y-543316D01*
X-1956424Y-543056D01*
X-1955254Y-543316D01*
X-1954084Y-544096D01*
G01X-1941449Y-546436D02*
X-1935209D01*
X-1935794Y-544616D01*
X-1936769Y-543576D01*
X-1938134Y-543056D01*
X-1939499Y-543316D01*
X-1940669Y-544096D01*
X-1941449Y-545916D01*
X-1941839Y-547476D01*
Y-549036D01*
X-1941449Y-550596D01*
X-1940474Y-552156D01*
X-1939304Y-553196D01*
X-1937939Y-553456D01*
X-1936574Y-552936D01*
X-1935209Y-551376D01*
G01X-1899214Y-553456D02*
Y-543056D01*
G01Y-544876D02*
X-1899994Y-543836D01*
X-1901164Y-543316D01*
X-1902529Y-543056D01*
X-1903894Y-543576D01*
X-1905064Y-544616D01*
X-1905844Y-546176D01*
X-1906234Y-548256D01*
X-1905844Y-550336D01*
X-1905064Y-551896D01*
X-1903894Y-552936D01*
X-1902529Y-553456D01*
X-1901164Y-553196D01*
X-1899994Y-552416D01*
X-1899214Y-551376D01*
G01X-1881314Y-537856D02*
Y-553456D01*
G01Y-551116D02*
X-1882094Y-552416D01*
X-1883264Y-553196D01*
X-1884629Y-553456D01*
X-1886189Y-552936D01*
X-1887359Y-551636D01*
X-1888139Y-550076D01*
X-1888334Y-548256D01*
X-1888139Y-546436D01*
X-1887359Y-544876D01*
X-1886189Y-543576D01*
X-1884629Y-543056D01*
X-1883264Y-543316D01*
X-1882289Y-543836D01*
X-1881314Y-544876D01*
G01X-1863414Y-537856D02*
Y-553456D01*
G01Y-551116D02*
X-1864194Y-552416D01*
X-1865364Y-553196D01*
X-1866729Y-553456D01*
X-1868289Y-552936D01*
X-1869459Y-551636D01*
X-1870239Y-550076D01*
X-1870434Y-548256D01*
X-1870239Y-546436D01*
X-1869459Y-544876D01*
X-1868289Y-543576D01*
X-1866729Y-543056D01*
X-1865364Y-543316D01*
X-1864389Y-543836D01*
X-1863414Y-544876D01*
G01X-1828004Y-544356D02*
X-1829369Y-543316D01*
X-1830539Y-543056D01*
X-1832099Y-543576D01*
X-1833269Y-544616D01*
X-1834049Y-546436D01*
X-1834244Y-548256D01*
X-1834049Y-550076D01*
X-1833269Y-551636D01*
X-1832099Y-552936D01*
X-1830539Y-553456D01*
X-1829174Y-552936D01*
X-1828004Y-551896D01*
G01X-1816539Y-553456D02*
Y-537856D01*
G01Y-545396D02*
X-1815564Y-544096D01*
X-1814589Y-543316D01*
X-1813029Y-543056D01*
X-1811859Y-543316D01*
X-1810494Y-544356D01*
X-1809909Y-545916D01*
Y-553456D01*
G01X-1791814D02*
Y-543056D01*
G01Y-544876D02*
X-1792594Y-543836D01*
X-1793764Y-543316D01*
X-1795129Y-543056D01*
X-1796494Y-543576D01*
X-1797664Y-544616D01*
X-1798444Y-546176D01*
X-1798834Y-548256D01*
X-1798444Y-550336D01*
X-1797664Y-551896D01*
X-1796494Y-552936D01*
X-1795129Y-553456D01*
X-1793764Y-553196D01*
X-1792594Y-552416D01*
X-1791814Y-551376D01*
G01X-1783274Y-553456D02*
Y-543056D01*
G01Y-545916D02*
X-1782689Y-544616D01*
X-1781714Y-543576D01*
X-1780349Y-543056D01*
X-1778984Y-543576D01*
X-1778009Y-544616D01*
X-1777424Y-545916D01*
Y-553456D01*
G01Y-545916D02*
X-1776839Y-544616D01*
X-1775864Y-543576D01*
X-1774499Y-543056D01*
X-1773134Y-543576D01*
X-1772159Y-544616D01*
X-1771574Y-546176D01*
Y-553456D01*
G01X-1760694D02*
Y-540196D01*
X-1760304Y-538896D01*
X-1759524Y-538116D01*
X-1758354Y-537856D01*
X-1757184Y-538376D01*
X-1756599Y-539676D01*
G01X-1758939Y-544096D02*
X-1762839D01*
G01X-1744549Y-546436D02*
X-1738309D01*
X-1738894Y-544616D01*
X-1739869Y-543576D01*
X-1741234Y-543056D01*
X-1742599Y-543316D01*
X-1743769Y-544096D01*
X-1744549Y-545916D01*
X-1744939Y-547476D01*
Y-549036D01*
X-1744549Y-550596D01*
X-1743574Y-552156D01*
X-1742404Y-553196D01*
X-1741039Y-553456D01*
X-1739674Y-552936D01*
X-1738309Y-551376D01*
G01X-1726454Y-553456D02*
Y-543056D01*
G01Y-545136D02*
X-1725479Y-544096D01*
X-1724504Y-543316D01*
X-1723139Y-543056D01*
X-1722164Y-543316D01*
X-1720994Y-544096D01*
G01X-1687924Y-537856D02*
Y-553456D01*
G01X-1690654Y-543056D02*
X-1685194D01*
G01X-1670024Y-553456D02*
X-1671194Y-553196D01*
X-1672364Y-552156D01*
X-1673144Y-550336D01*
X-1673534Y-548256D01*
X-1673144Y-546176D01*
X-1672364Y-544356D01*
X-1671194Y-543316D01*
X-1670024Y-543056D01*
X-1668854Y-543316D01*
X-1667684Y-544356D01*
X-1666904Y-546176D01*
X-1666709Y-548256D01*
X-1666904Y-550336D01*
X-1667684Y-552156D01*
X-1668854Y-553196D01*
X-1670024Y-553456D01*
G01X-1637149Y-546436D02*
X-1630909D01*
X-1631494Y-544616D01*
X-1632469Y-543576D01*
X-1633834Y-543056D01*
X-1635199Y-543316D01*
X-1636369Y-544096D01*
X-1637149Y-545916D01*
X-1637539Y-547476D01*
Y-549036D01*
X-1637149Y-550596D01*
X-1636174Y-552156D01*
X-1635004Y-553196D01*
X-1633639Y-553456D01*
X-1632274Y-552936D01*
X-1630909Y-551376D01*
G01X-1612814Y-553456D02*
Y-543056D01*
G01Y-544876D02*
X-1613594Y-543836D01*
X-1614764Y-543316D01*
X-1616129Y-543056D01*
X-1617494Y-543576D01*
X-1618664Y-544616D01*
X-1619444Y-546176D01*
X-1619834Y-548256D01*
X-1619444Y-550336D01*
X-1618664Y-551896D01*
X-1617494Y-552936D01*
X-1616129Y-553456D01*
X-1614764Y-553196D01*
X-1613594Y-552416D01*
X-1612814Y-551376D01*
G01X-1595304Y-544356D02*
X-1596669Y-543316D01*
X-1597839Y-543056D01*
X-1599399Y-543576D01*
X-1600569Y-544616D01*
X-1601349Y-546436D01*
X-1601544Y-548256D01*
X-1601349Y-550076D01*
X-1600569Y-551636D01*
X-1599399Y-552936D01*
X-1597839Y-553456D01*
X-1596474Y-552936D01*
X-1595304Y-551896D01*
G01X-1583839Y-553456D02*
Y-537856D01*
G01Y-545396D02*
X-1582864Y-544096D01*
X-1581889Y-543316D01*
X-1580329Y-543056D01*
X-1579159Y-543316D01*
X-1577794Y-544356D01*
X-1577209Y-545916D01*
Y-553456D01*
G01X-1547649Y-551636D02*
X-1546674Y-552676D01*
X-1545309Y-553456D01*
X-1544139D01*
X-1542969Y-552936D01*
X-1542189Y-552156D01*
X-1541799Y-551116D01*
X-1541994Y-549556D01*
X-1542774Y-548776D01*
X-1546284Y-547216D01*
X-1547064Y-545396D01*
X-1546674Y-544096D01*
X-1545894Y-543316D01*
X-1544724Y-543056D01*
X-1543554Y-543316D01*
X-1542384Y-544096D01*
G01X-1526824Y-543056D02*
Y-553456D01*
G01Y-538896D02*
X-1527214Y-538636D01*
Y-538116D01*
X-1526824Y-537856D01*
X-1526434Y-538116D01*
Y-538636D01*
X-1526824Y-538896D01*
G01X-1505414Y-537856D02*
Y-553456D01*
G01Y-551116D02*
X-1506194Y-552416D01*
X-1507364Y-553196D01*
X-1508729Y-553456D01*
X-1510289Y-552936D01*
X-1511459Y-551636D01*
X-1512239Y-550076D01*
X-1512434Y-548256D01*
X-1512239Y-546436D01*
X-1511459Y-544876D01*
X-1510289Y-543576D01*
X-1508729Y-543056D01*
X-1507364Y-543316D01*
X-1506389Y-543836D01*
X-1505414Y-544876D01*
G01X-1493949Y-546436D02*
X-1487709D01*
X-1488294Y-544616D01*
X-1489269Y-543576D01*
X-1490634Y-543056D01*
X-1491999Y-543316D01*
X-1493169Y-544096D01*
X-1493949Y-545916D01*
X-1494339Y-547476D01*
Y-549036D01*
X-1493949Y-550596D01*
X-1492974Y-552156D01*
X-1491804Y-553196D01*
X-1490439Y-553456D01*
X-1489074Y-552936D01*
X-1487709Y-551376D01*
G01X-1455224Y-553456D02*
X-1456394Y-553196D01*
X-1457564Y-552156D01*
X-1458344Y-550336D01*
X-1458734Y-548256D01*
X-1458344Y-546176D01*
X-1457564Y-544356D01*
X-1456394Y-543316D01*
X-1455224Y-543056D01*
X-1454054Y-543316D01*
X-1452884Y-544356D01*
X-1452104Y-546176D01*
X-1451909Y-548256D01*
X-1452104Y-550336D01*
X-1452884Y-552156D01*
X-1454054Y-553196D01*
X-1455224Y-553456D01*
G01X-1438494D02*
Y-540196D01*
X-1438104Y-538896D01*
X-1437324Y-538116D01*
X-1436154Y-537856D01*
X-1434984Y-538376D01*
X-1434399Y-539676D01*
G01X-1436739Y-544096D02*
X-1440639D01*
G01X-1404254Y-557356D02*
X-1402889Y-558396D01*
X-1401329Y-558656D01*
X-1399964Y-558396D01*
X-1398794Y-557096D01*
X-1398014Y-555276D01*
Y-543056D01*
G01Y-545136D02*
X-1398794Y-544096D01*
X-1399964Y-543316D01*
X-1401329Y-543056D01*
X-1402889Y-543576D01*
X-1403864Y-544616D01*
X-1404644Y-546436D01*
X-1405034Y-548256D01*
X-1404839Y-549816D01*
X-1404059Y-551636D01*
X-1402889Y-552936D01*
X-1401329Y-553456D01*
X-1400159Y-553196D01*
X-1398794Y-552156D01*
X-1398014Y-551116D01*
G01X-1383624Y-553456D02*
X-1384794Y-553196D01*
X-1385964Y-552156D01*
X-1386744Y-550336D01*
X-1387134Y-548256D01*
X-1386744Y-546176D01*
X-1385964Y-544356D01*
X-1384794Y-543316D01*
X-1383624Y-543056D01*
X-1382454Y-543316D01*
X-1381284Y-544356D01*
X-1380504Y-546176D01*
X-1380309Y-548256D01*
X-1380504Y-550336D01*
X-1381284Y-552156D01*
X-1382454Y-553196D01*
X-1383624Y-553456D01*
G01X-1365724D02*
Y-537856D01*
G01X-1344314D02*
Y-553456D01*
G01Y-551116D02*
X-1345094Y-552416D01*
X-1346264Y-553196D01*
X-1347629Y-553456D01*
X-1349189Y-552936D01*
X-1350359Y-551636D01*
X-1351139Y-550076D01*
X-1351334Y-548256D01*
X-1351139Y-546436D01*
X-1350359Y-544876D01*
X-1349189Y-543576D01*
X-1347629Y-543056D01*
X-1346264Y-543316D01*
X-1345289Y-543836D01*
X-1344314Y-544876D01*
G01X-1313194Y-553456D02*
Y-540196D01*
X-1312804Y-538896D01*
X-1312024Y-538116D01*
X-1310854Y-537856D01*
X-1309684Y-538376D01*
X-1309099Y-539676D01*
G01X-1311439Y-544096D02*
X-1315339D01*
G01X-1294124Y-543056D02*
Y-553456D01*
G01Y-538896D02*
X-1294514Y-538636D01*
Y-538116D01*
X-1294124Y-537856D01*
X-1293734Y-538116D01*
Y-538636D01*
X-1294124Y-538896D01*
G01X-1279539Y-553456D02*
Y-543056D01*
G01Y-545656D02*
X-1278759Y-544356D01*
X-1277589Y-543316D01*
X-1276029Y-543056D01*
X-1274664Y-543316D01*
X-1273494Y-544356D01*
X-1272909Y-546176D01*
Y-553456D01*
G01X-1261054Y-557356D02*
X-1259689Y-558396D01*
X-1258129Y-558656D01*
X-1256764Y-558396D01*
X-1255594Y-557096D01*
X-1254814Y-555276D01*
Y-543056D01*
G01Y-545136D02*
X-1255594Y-544096D01*
X-1256764Y-543316D01*
X-1258129Y-543056D01*
X-1259689Y-543576D01*
X-1260664Y-544616D01*
X-1261444Y-546436D01*
X-1261834Y-548256D01*
X-1261639Y-549816D01*
X-1260859Y-551636D01*
X-1259689Y-552936D01*
X-1258129Y-553456D01*
X-1256959Y-553196D01*
X-1255594Y-552156D01*
X-1254814Y-551116D01*
G01X-1243349Y-546436D02*
X-1237109D01*
X-1237694Y-544616D01*
X-1238669Y-543576D01*
X-1240034Y-543056D01*
X-1241399Y-543316D01*
X-1242569Y-544096D01*
X-1243349Y-545916D01*
X-1243739Y-547476D01*
Y-549036D01*
X-1243349Y-550596D01*
X-1242374Y-552156D01*
X-1241204Y-553196D01*
X-1239839Y-553456D01*
X-1238474Y-552936D01*
X-1237109Y-551376D01*
G01X-1225254Y-553456D02*
Y-543056D01*
G01Y-545136D02*
X-1224279Y-544096D01*
X-1223304Y-543316D01*
X-1221939Y-543056D01*
X-1220964Y-543316D01*
X-1219794Y-544096D01*
G01X-1204624Y-553976D02*
X-1205014Y-553716D01*
Y-553196D01*
X-1204624Y-552936D01*
X-1204234Y-553196D01*
Y-553716D01*
X-1204624Y-553976D01*
G01X-1191599Y-553456D02*
X-1186724Y-537856D01*
X-1181849Y-553456D01*
G01X-1183604Y-547996D02*
X-1189844D01*
G01X-1165704Y-544356D02*
X-1167069Y-543316D01*
X-1168239Y-543056D01*
X-1169799Y-543576D01*
X-1170969Y-544616D01*
X-1171749Y-546436D01*
X-1171944Y-548256D01*
X-1171749Y-550076D01*
X-1170969Y-551636D01*
X-1169799Y-552936D01*
X-1168239Y-553456D01*
X-1166874Y-552936D01*
X-1165704Y-551896D01*
G01X-1147804Y-544356D02*
X-1149169Y-543316D01*
X-1150339Y-543056D01*
X-1151899Y-543576D01*
X-1153069Y-544616D01*
X-1153849Y-546436D01*
X-1154044Y-548256D01*
X-1153849Y-550076D01*
X-1153069Y-551636D01*
X-1151899Y-552936D01*
X-1150339Y-553456D01*
X-1148974Y-552936D01*
X-1147804Y-551896D01*
G01X-1133024Y-553456D02*
X-1134194Y-553196D01*
X-1135364Y-552156D01*
X-1136144Y-550336D01*
X-1136534Y-548256D01*
X-1136144Y-546176D01*
X-1135364Y-544356D01*
X-1134194Y-543316D01*
X-1133024Y-543056D01*
X-1131854Y-543316D01*
X-1130684Y-544356D01*
X-1129904Y-546176D01*
X-1129709Y-548256D01*
X-1129904Y-550336D01*
X-1130684Y-552156D01*
X-1131854Y-553196D01*
X-1133024Y-553456D01*
G01X-1117854D02*
Y-543056D01*
G01Y-545136D02*
X-1116879Y-544096D01*
X-1115904Y-543316D01*
X-1114539Y-543056D01*
X-1113564Y-543316D01*
X-1112394Y-544096D01*
G01X-1093714Y-537856D02*
Y-553456D01*
G01Y-551116D02*
X-1094494Y-552416D01*
X-1095664Y-553196D01*
X-1097029Y-553456D01*
X-1098589Y-552936D01*
X-1099759Y-551636D01*
X-1100539Y-550076D01*
X-1100734Y-548256D01*
X-1100539Y-546436D01*
X-1099759Y-544876D01*
X-1098589Y-543576D01*
X-1097029Y-543056D01*
X-1095664Y-543316D01*
X-1094689Y-543836D01*
X-1093714Y-544876D01*
G01X-1079324Y-543056D02*
Y-553456D01*
G01Y-538896D02*
X-1079714Y-538636D01*
Y-538116D01*
X-1079324Y-537856D01*
X-1078934Y-538116D01*
Y-538636D01*
X-1079324Y-538896D01*
G01X-1064739Y-553456D02*
Y-543056D01*
G01Y-545656D02*
X-1063959Y-544356D01*
X-1062789Y-543316D01*
X-1061229Y-543056D01*
X-1059864Y-543316D01*
X-1058694Y-544356D01*
X-1058109Y-546176D01*
Y-553456D01*
G01X-1046254Y-557356D02*
X-1044889Y-558396D01*
X-1043329Y-558656D01*
X-1041964Y-558396D01*
X-1040794Y-557096D01*
X-1040014Y-555276D01*
Y-543056D01*
G01Y-545136D02*
X-1040794Y-544096D01*
X-1041964Y-543316D01*
X-1043329Y-543056D01*
X-1044889Y-543576D01*
X-1045864Y-544616D01*
X-1046644Y-546436D01*
X-1047034Y-548256D01*
X-1046839Y-549816D01*
X-1046059Y-551636D01*
X-1044889Y-552936D01*
X-1043329Y-553456D01*
X-1042159Y-553196D01*
X-1040794Y-552156D01*
X-1040014Y-551116D01*
G01X-1007724Y-537856D02*
Y-553456D01*
G01X-1010454Y-543056D02*
X-1004994D01*
G01X-989824Y-553456D02*
X-990994Y-553196D01*
X-992164Y-552156D01*
X-992944Y-550336D01*
X-993334Y-548256D01*
X-992944Y-546176D01*
X-992164Y-544356D01*
X-990994Y-543316D01*
X-989824Y-543056D01*
X-988654Y-543316D01*
X-987484Y-544356D01*
X-986704Y-546176D01*
X-986509Y-548256D01*
X-986704Y-550336D01*
X-987484Y-552156D01*
X-988654Y-553196D01*
X-989824Y-553456D01*
G01X-950514Y-537856D02*
Y-553456D01*
G01Y-551116D02*
X-951294Y-552416D01*
X-952464Y-553196D01*
X-953829Y-553456D01*
X-955389Y-552936D01*
X-956559Y-551636D01*
X-957339Y-550076D01*
X-957534Y-548256D01*
X-957339Y-546436D01*
X-956559Y-544876D01*
X-955389Y-543576D01*
X-953829Y-543056D01*
X-952464Y-543316D01*
X-951489Y-543836D01*
X-950514Y-544876D01*
G01X-939049Y-546436D02*
X-932809D01*
X-933394Y-544616D01*
X-934369Y-543576D01*
X-935734Y-543056D01*
X-937099Y-543316D01*
X-938269Y-544096D01*
X-939049Y-545916D01*
X-939439Y-547476D01*
Y-549036D01*
X-939049Y-550596D01*
X-938074Y-552156D01*
X-936904Y-553196D01*
X-935539Y-553456D01*
X-934174Y-552936D01*
X-932809Y-551376D01*
G01X-918224Y-537856D02*
Y-553456D01*
G01X-920954Y-543056D02*
X-915494D01*
G01X-896814Y-553456D02*
Y-543056D01*
G01Y-544876D02*
X-897594Y-543836D01*
X-898764Y-543316D01*
X-900129Y-543056D01*
X-901494Y-543576D01*
X-902664Y-544616D01*
X-903444Y-546176D01*
X-903834Y-548256D01*
X-903444Y-550336D01*
X-902664Y-551896D01*
X-901494Y-552936D01*
X-900129Y-553456D01*
X-898764Y-553196D01*
X-897594Y-552416D01*
X-896814Y-551376D01*
G01X-882424Y-543056D02*
Y-553456D01*
G01Y-538896D02*
X-882814Y-538636D01*
Y-538116D01*
X-882424Y-537856D01*
X-882034Y-538116D01*
Y-538636D01*
X-882424Y-538896D01*
G01X-864524Y-553456D02*
Y-537856D01*
G01X-827164Y-545136D02*
X-826384Y-544356D01*
X-825799Y-543056D01*
X-825409Y-541236D01*
X-825799Y-539676D01*
X-826579Y-538636D01*
X-827944Y-537856D01*
X-833209D01*
Y-553456D01*
X-826774D01*
X-825409Y-552416D01*
X-824629Y-550856D01*
X-824239Y-549036D01*
X-824629Y-547216D01*
X-825799Y-545656D01*
X-827164Y-545136D01*
X-833209D01*
G01X-810824Y-553976D02*
X-811214Y-553716D01*
Y-553196D01*
X-810824Y-552936D01*
X-810434Y-553196D01*
Y-553716D01*
X-810824Y-553976D01*
G01X-2078224Y-459456D02*
Y-443856D01*
G01X-2056814Y-459456D02*
Y-449056D01*
G01Y-450876D02*
X-2057594Y-449836D01*
X-2058764Y-449316D01*
X-2060129Y-449056D01*
X-2061494Y-449576D01*
X-2062664Y-450616D01*
X-2063444Y-452176D01*
X-2063834Y-454256D01*
X-2063444Y-456336D01*
X-2062664Y-457896D01*
X-2061494Y-458936D01*
X-2060129Y-459456D01*
X-2058764Y-459196D01*
X-2057594Y-458416D01*
X-2056814Y-457376D01*
G01X-2046519Y-464136D02*
X-2045349Y-464656D01*
X-2043789Y-464136D01*
X-2042814Y-463096D01*
X-2042034Y-461796D01*
X-2040864Y-457636D01*
X-2038329Y-449056D01*
G01X-2044569D02*
X-2040864Y-457636D01*
G01X-2027449Y-452436D02*
X-2021209D01*
X-2021794Y-450616D01*
X-2022769Y-449576D01*
X-2024134Y-449056D01*
X-2025499Y-449316D01*
X-2026669Y-450096D01*
X-2027449Y-451916D01*
X-2027839Y-453476D01*
Y-455036D01*
X-2027449Y-456596D01*
X-2026474Y-458156D01*
X-2025304Y-459196D01*
X-2023939Y-459456D01*
X-2022574Y-458936D01*
X-2021209Y-457376D01*
G01X-2009354Y-459456D02*
Y-449056D01*
G01Y-451136D02*
X-2008379Y-450096D01*
X-2007404Y-449316D01*
X-2006039Y-449056D01*
X-2005064Y-449316D01*
X-2003894Y-450096D01*
G01X-1974139Y-449056D02*
Y-456336D01*
X-1973359Y-458156D01*
X-1972189Y-459196D01*
X-1970824Y-459456D01*
X-1969459Y-459196D01*
X-1968289Y-458156D01*
X-1967509Y-456336D01*
G01Y-459456D02*
Y-449056D01*
G01X-1956434Y-464656D02*
Y-449056D01*
G01Y-451396D02*
X-1955459Y-450096D01*
X-1954484Y-449316D01*
X-1952924Y-449056D01*
X-1951559Y-449316D01*
X-1950194Y-450616D01*
X-1949609Y-452436D01*
X-1949414Y-454256D01*
X-1949609Y-456076D01*
X-1950194Y-457896D01*
X-1951364Y-458936D01*
X-1952924Y-459456D01*
X-1954289Y-459196D01*
X-1955654Y-458416D01*
X-1956434Y-457376D01*
G01X-1920634Y-464656D02*
Y-449056D01*
G01Y-451396D02*
X-1919659Y-450096D01*
X-1918684Y-449316D01*
X-1917124Y-449056D01*
X-1915759Y-449316D01*
X-1914394Y-450616D01*
X-1913809Y-452436D01*
X-1913614Y-454256D01*
X-1913809Y-456076D01*
X-1914394Y-457896D01*
X-1915564Y-458936D01*
X-1917124Y-459456D01*
X-1918489Y-459196D01*
X-1919854Y-458416D01*
X-1920634Y-457376D01*
G01X-1899224Y-459456D02*
Y-443856D01*
G01X-1884639Y-449056D02*
Y-456336D01*
X-1883859Y-458156D01*
X-1882689Y-459196D01*
X-1881324Y-459456D01*
X-1879959Y-459196D01*
X-1878789Y-458156D01*
X-1878009Y-456336D01*
G01Y-459456D02*
Y-449056D01*
G01X-1866739Y-459456D02*
Y-449056D01*
G01Y-451656D02*
X-1865959Y-450356D01*
X-1864789Y-449316D01*
X-1863229Y-449056D01*
X-1861864Y-449316D01*
X-1860694Y-450356D01*
X-1860109Y-452176D01*
Y-459456D01*
G01X-1848254Y-463356D02*
X-1846889Y-464396D01*
X-1845329Y-464656D01*
X-1843964Y-464396D01*
X-1842794Y-463096D01*
X-1842014Y-461276D01*
Y-449056D01*
G01Y-451136D02*
X-1842794Y-450096D01*
X-1843964Y-449316D01*
X-1845329Y-449056D01*
X-1846889Y-449576D01*
X-1847864Y-450616D01*
X-1848644Y-452436D01*
X-1849034Y-454256D01*
X-1848839Y-455816D01*
X-1848059Y-457636D01*
X-1846889Y-458936D01*
X-1845329Y-459456D01*
X-1844159Y-459196D01*
X-1842794Y-458156D01*
X-1842014Y-457116D01*
G01X-1830549Y-452436D02*
X-1824309D01*
X-1824894Y-450616D01*
X-1825869Y-449576D01*
X-1827234Y-449056D01*
X-1828599Y-449316D01*
X-1829769Y-450096D01*
X-1830549Y-451916D01*
X-1830939Y-453476D01*
Y-455036D01*
X-1830549Y-456596D01*
X-1829574Y-458156D01*
X-1828404Y-459196D01*
X-1827039Y-459456D01*
X-1825674Y-458936D01*
X-1824309Y-457376D01*
G01X-1812649Y-457636D02*
X-1811674Y-458676D01*
X-1810309Y-459456D01*
X-1809139D01*
X-1807969Y-458936D01*
X-1807189Y-458156D01*
X-1806799Y-457116D01*
X-1806994Y-455556D01*
X-1807774Y-454776D01*
X-1811284Y-453216D01*
X-1812064Y-451396D01*
X-1811674Y-450096D01*
X-1810894Y-449316D01*
X-1809724Y-449056D01*
X-1808554Y-449316D01*
X-1807384Y-450096D01*
G01X-1770414Y-459456D02*
Y-449056D01*
G01Y-450876D02*
X-1771194Y-449836D01*
X-1772364Y-449316D01*
X-1773729Y-449056D01*
X-1775094Y-449576D01*
X-1776264Y-450616D01*
X-1777044Y-452176D01*
X-1777434Y-454256D01*
X-1777044Y-456336D01*
X-1776264Y-457896D01*
X-1775094Y-458936D01*
X-1773729Y-459456D01*
X-1772364Y-459196D01*
X-1771194Y-458416D01*
X-1770414Y-457376D01*
G01X-1759339Y-459456D02*
Y-449056D01*
G01Y-451656D02*
X-1758559Y-450356D01*
X-1757389Y-449316D01*
X-1755829Y-449056D01*
X-1754464Y-449316D01*
X-1753294Y-450356D01*
X-1752709Y-452176D01*
Y-459456D01*
G01X-1734614Y-443856D02*
Y-459456D01*
G01Y-457116D02*
X-1735394Y-458416D01*
X-1736564Y-459196D01*
X-1737929Y-459456D01*
X-1739489Y-458936D01*
X-1740659Y-457636D01*
X-1741439Y-456076D01*
X-1741634Y-454256D01*
X-1741439Y-452436D01*
X-1740659Y-450876D01*
X-1739489Y-449576D01*
X-1737929Y-449056D01*
X-1736564Y-449316D01*
X-1735589Y-449836D01*
X-1734614Y-450876D01*
G01X-1702324Y-459456D02*
Y-443856D01*
X-1704664Y-446976D01*
G01Y-459456D02*
X-1699984D01*
G01X-1670034D02*
Y-443856D01*
G01Y-451656D02*
X-1669059Y-450096D01*
X-1667889Y-449316D01*
X-1666719Y-449056D01*
X-1664964Y-449576D01*
X-1663794Y-450616D01*
X-1663014Y-452436D01*
Y-454516D01*
X-1663404Y-456596D01*
X-1664184Y-458156D01*
X-1665549Y-459196D01*
X-1666719Y-459456D01*
X-1667889Y-459196D01*
X-1669059Y-458416D01*
X-1670034Y-457116D01*
G01X-1645114Y-459456D02*
Y-449056D01*
G01Y-450876D02*
X-1645894Y-449836D01*
X-1647064Y-449316D01*
X-1648429Y-449056D01*
X-1649794Y-449576D01*
X-1650964Y-450616D01*
X-1651744Y-452176D01*
X-1652134Y-454256D01*
X-1651744Y-456336D01*
X-1650964Y-457896D01*
X-1649794Y-458936D01*
X-1648429Y-459456D01*
X-1647064Y-459196D01*
X-1645894Y-458416D01*
X-1645114Y-457376D01*
G01X-1627604Y-450356D02*
X-1628969Y-449316D01*
X-1630139Y-449056D01*
X-1631699Y-449576D01*
X-1632869Y-450616D01*
X-1633649Y-452436D01*
X-1633844Y-454256D01*
X-1633649Y-456076D01*
X-1632869Y-457636D01*
X-1631699Y-458936D01*
X-1630139Y-459456D01*
X-1628774Y-458936D01*
X-1627604Y-457896D01*
G01X-1616139Y-459456D02*
Y-443856D01*
G01X-1609899Y-449056D02*
X-1616139Y-455036D01*
G01X-1613604Y-452696D02*
X-1609509Y-459456D01*
G01X-1591414Y-443856D02*
Y-459456D01*
G01Y-457116D02*
X-1592194Y-458416D01*
X-1593364Y-459196D01*
X-1594729Y-459456D01*
X-1596289Y-458936D01*
X-1597459Y-457636D01*
X-1598239Y-456076D01*
X-1598434Y-454256D01*
X-1598239Y-452436D01*
X-1597459Y-450876D01*
X-1596289Y-449576D01*
X-1594729Y-449056D01*
X-1593364Y-449316D01*
X-1592389Y-449836D01*
X-1591414Y-450876D01*
G01X-1579754Y-459456D02*
Y-449056D01*
G01Y-451136D02*
X-1578779Y-450096D01*
X-1577804Y-449316D01*
X-1576439Y-449056D01*
X-1575464Y-449316D01*
X-1574294Y-450096D01*
G01X-1559124Y-449056D02*
Y-459456D01*
G01Y-444896D02*
X-1559514Y-444636D01*
Y-444116D01*
X-1559124Y-443856D01*
X-1558734Y-444116D01*
Y-444636D01*
X-1559124Y-444896D01*
G01X-1541224Y-459456D02*
Y-443856D01*
G01X-1523324Y-459456D02*
Y-443856D01*
G01X-1488694Y-459456D02*
Y-446196D01*
X-1488304Y-444896D01*
X-1487524Y-444116D01*
X-1486354Y-443856D01*
X-1485184Y-444376D01*
X-1484599Y-445676D01*
G01X-1486939Y-450096D02*
X-1490839D01*
G01X-1469624Y-449056D02*
Y-459456D01*
G01Y-444896D02*
X-1470014Y-444636D01*
Y-444116D01*
X-1469624Y-443856D01*
X-1469234Y-444116D01*
Y-444636D01*
X-1469624Y-444896D01*
G01X-1451724Y-459456D02*
Y-443856D01*
G01X-1436749Y-452436D02*
X-1430509D01*
X-1431094Y-450616D01*
X-1432069Y-449576D01*
X-1433434Y-449056D01*
X-1434799Y-449316D01*
X-1435969Y-450096D01*
X-1436749Y-451916D01*
X-1437139Y-453476D01*
Y-455036D01*
X-1436749Y-456596D01*
X-1435774Y-458156D01*
X-1434604Y-459196D01*
X-1433239Y-459456D01*
X-1431874Y-458936D01*
X-1430509Y-457376D01*
G01X-1418849Y-457636D02*
X-1417874Y-458676D01*
X-1416509Y-459456D01*
X-1415339D01*
X-1414169Y-458936D01*
X-1413389Y-458156D01*
X-1412999Y-457116D01*
X-1413194Y-455556D01*
X-1413974Y-454776D01*
X-1417484Y-453216D01*
X-1418264Y-451396D01*
X-1417874Y-450096D01*
X-1417094Y-449316D01*
X-1415924Y-449056D01*
X-1414754Y-449316D01*
X-1413584Y-450096D01*
G01X-1381294Y-459456D02*
Y-446196D01*
X-1380904Y-444896D01*
X-1380124Y-444116D01*
X-1378954Y-443856D01*
X-1377784Y-444376D01*
X-1377199Y-445676D01*
G01X-1379539Y-450096D02*
X-1383439D01*
G01X-1362224Y-459456D02*
X-1363394Y-459196D01*
X-1364564Y-458156D01*
X-1365344Y-456336D01*
X-1365734Y-454256D01*
X-1365344Y-452176D01*
X-1364564Y-450356D01*
X-1363394Y-449316D01*
X-1362224Y-449056D01*
X-1361054Y-449316D01*
X-1359884Y-450356D01*
X-1359104Y-452176D01*
X-1358909Y-454256D01*
X-1359104Y-456336D01*
X-1359884Y-458156D01*
X-1361054Y-459196D01*
X-1362224Y-459456D01*
G01X-1347054D02*
Y-449056D01*
G01Y-451136D02*
X-1346079Y-450096D01*
X-1345104Y-449316D01*
X-1343739Y-449056D01*
X-1342764Y-449316D01*
X-1341594Y-450096D01*
G01X-1308524Y-443856D02*
Y-459456D01*
G01X-1311254Y-449056D02*
X-1305794D01*
G01X-1290624Y-459456D02*
X-1291794Y-459196D01*
X-1292964Y-458156D01*
X-1293744Y-456336D01*
X-1294134Y-454256D01*
X-1293744Y-452176D01*
X-1292964Y-450356D01*
X-1291794Y-449316D01*
X-1290624Y-449056D01*
X-1289454Y-449316D01*
X-1288284Y-450356D01*
X-1287504Y-452176D01*
X-1287309Y-454256D01*
X-1287504Y-456336D01*
X-1288284Y-458156D01*
X-1289454Y-459196D01*
X-1290624Y-459456D01*
G01X-1276234Y-464656D02*
Y-449056D01*
G01Y-451396D02*
X-1275259Y-450096D01*
X-1274284Y-449316D01*
X-1272724Y-449056D01*
X-1271359Y-449316D01*
X-1269994Y-450616D01*
X-1269409Y-452436D01*
X-1269214Y-454256D01*
X-1269409Y-456076D01*
X-1269994Y-457896D01*
X-1271164Y-458936D01*
X-1272724Y-459456D01*
X-1274089Y-459196D01*
X-1275454Y-458416D01*
X-1276234Y-457376D01*
G01X-1236924Y-459456D02*
Y-443856D01*
G01X-1215514Y-459456D02*
Y-449056D01*
G01Y-450876D02*
X-1216294Y-449836D01*
X-1217464Y-449316D01*
X-1218829Y-449056D01*
X-1220194Y-449576D01*
X-1221364Y-450616D01*
X-1222144Y-452176D01*
X-1222534Y-454256D01*
X-1222144Y-456336D01*
X-1221364Y-457896D01*
X-1220194Y-458936D01*
X-1218829Y-459456D01*
X-1217464Y-459196D01*
X-1216294Y-458416D01*
X-1215514Y-457376D01*
G01X-1205219Y-464136D02*
X-1204049Y-464656D01*
X-1202489Y-464136D01*
X-1201514Y-463096D01*
X-1200734Y-461796D01*
X-1199564Y-457636D01*
X-1197029Y-449056D01*
G01X-1203269D02*
X-1199564Y-457636D01*
G01X-1186149Y-452436D02*
X-1179909D01*
X-1180494Y-450616D01*
X-1181469Y-449576D01*
X-1182834Y-449056D01*
X-1184199Y-449316D01*
X-1185369Y-450096D01*
X-1186149Y-451916D01*
X-1186539Y-453476D01*
Y-455036D01*
X-1186149Y-456596D01*
X-1185174Y-458156D01*
X-1184004Y-459196D01*
X-1182639Y-459456D01*
X-1181274Y-458936D01*
X-1179909Y-457376D01*
G01X-1168054Y-459456D02*
Y-449056D01*
G01Y-451136D02*
X-1167079Y-450096D01*
X-1166104Y-449316D01*
X-1164739Y-449056D01*
X-1163764Y-449316D01*
X-1162594Y-450096D01*
G01X-1126014Y-443856D02*
Y-459456D01*
G01Y-457116D02*
X-1126794Y-458416D01*
X-1127964Y-459196D01*
X-1129329Y-459456D01*
X-1130889Y-458936D01*
X-1132059Y-457636D01*
X-1132839Y-456076D01*
X-1133034Y-454256D01*
X-1132839Y-452436D01*
X-1132059Y-450876D01*
X-1130889Y-449576D01*
X-1129329Y-449056D01*
X-1127964Y-449316D01*
X-1126989Y-449836D01*
X-1126014Y-450876D01*
G01X-1111624Y-459456D02*
X-1112794Y-459196D01*
X-1113964Y-458156D01*
X-1114744Y-456336D01*
X-1115134Y-454256D01*
X-1114744Y-452176D01*
X-1113964Y-450356D01*
X-1112794Y-449316D01*
X-1111624Y-449056D01*
X-1110454Y-449316D01*
X-1109284Y-450356D01*
X-1108504Y-452176D01*
X-1108309Y-454256D01*
X-1108504Y-456336D01*
X-1109284Y-458156D01*
X-1110454Y-459196D01*
X-1111624Y-459456D01*
G01X-1098599Y-449056D02*
X-1096259Y-459456D01*
X-1093724Y-449056D01*
X-1091189Y-459456D01*
X-1088849Y-449056D01*
G01X-1079139Y-459456D02*
Y-449056D01*
G01Y-451656D02*
X-1078359Y-450356D01*
X-1077189Y-449316D01*
X-1075629Y-449056D01*
X-1074264Y-449316D01*
X-1073094Y-450356D01*
X-1072509Y-452176D01*
Y-459456D01*
G01X-1043534Y-464656D02*
Y-449056D01*
G01Y-451396D02*
X-1042559Y-450096D01*
X-1041584Y-449316D01*
X-1040024Y-449056D01*
X-1038659Y-449316D01*
X-1037294Y-450616D01*
X-1036709Y-452436D01*
X-1036514Y-454256D01*
X-1036709Y-456076D01*
X-1037294Y-457896D01*
X-1038464Y-458936D01*
X-1040024Y-459456D01*
X-1041389Y-459196D01*
X-1042754Y-458416D01*
X-1043534Y-457376D01*
G01X-1022124Y-459456D02*
Y-443856D01*
G01X-1007539Y-449056D02*
Y-456336D01*
X-1006759Y-458156D01*
X-1005589Y-459196D01*
X-1004224Y-459456D01*
X-1002859Y-459196D01*
X-1001689Y-458156D01*
X-1000909Y-456336D01*
G01Y-459456D02*
Y-449056D01*
G01X-989639Y-459456D02*
Y-449056D01*
G01Y-451656D02*
X-988859Y-450356D01*
X-987689Y-449316D01*
X-986129Y-449056D01*
X-984764Y-449316D01*
X-983594Y-450356D01*
X-983009Y-452176D01*
Y-459456D01*
G01X-971154Y-463356D02*
X-969789Y-464396D01*
X-968229Y-464656D01*
X-966864Y-464396D01*
X-965694Y-463096D01*
X-964914Y-461276D01*
Y-449056D01*
G01Y-451136D02*
X-965694Y-450096D01*
X-966864Y-449316D01*
X-968229Y-449056D01*
X-969789Y-449576D01*
X-970764Y-450616D01*
X-971544Y-452436D01*
X-971934Y-454256D01*
X-971739Y-455816D01*
X-970959Y-457636D01*
X-969789Y-458936D01*
X-968229Y-459456D01*
X-967059Y-459196D01*
X-965694Y-458156D01*
X-964914Y-457116D01*
G01X-953449Y-452436D02*
X-947209D01*
X-947794Y-450616D01*
X-948769Y-449576D01*
X-950134Y-449056D01*
X-951499Y-449316D01*
X-952669Y-450096D01*
X-953449Y-451916D01*
X-953839Y-453476D01*
Y-455036D01*
X-953449Y-456596D01*
X-952474Y-458156D01*
X-951304Y-459196D01*
X-949939Y-459456D01*
X-948574Y-458936D01*
X-947209Y-457376D01*
G01X-935549Y-457636D02*
X-934574Y-458676D01*
X-933209Y-459456D01*
X-932039D01*
X-930869Y-458936D01*
X-930089Y-458156D01*
X-929699Y-457116D01*
X-929894Y-455556D01*
X-930674Y-454776D01*
X-934184Y-453216D01*
X-934964Y-451396D01*
X-934574Y-450096D01*
X-933794Y-449316D01*
X-932624Y-449056D01*
X-931454Y-449316D01*
X-930284Y-450096D01*
G01X-914724Y-459976D02*
X-915114Y-459716D01*
Y-459196D01*
X-914724Y-458936D01*
X-914334Y-459196D01*
Y-459716D01*
X-914724Y-459976D01*
G01X-2078224Y-425456D02*
X-2079784Y-425196D01*
X-2081149Y-424156D01*
X-2082319Y-422596D01*
X-2083099Y-420776D01*
X-2083489Y-418696D01*
Y-416616D01*
X-2083099Y-414536D01*
X-2082319Y-412716D01*
X-2081149Y-411156D01*
X-2079784Y-410116D01*
X-2078224Y-409856D01*
X-2076664Y-410116D01*
X-2075299Y-411156D01*
X-2074129Y-412716D01*
X-2073349Y-414536D01*
X-2072959Y-416616D01*
Y-418696D01*
X-2073349Y-420776D01*
X-2074129Y-422596D01*
X-2075299Y-424156D01*
X-2076664Y-425196D01*
X-2078224Y-425456D01*
G01X-2063639Y-415056D02*
Y-422336D01*
X-2062859Y-424156D01*
X-2061689Y-425196D01*
X-2060324Y-425456D01*
X-2058959Y-425196D01*
X-2057789Y-424156D01*
X-2057009Y-422336D01*
G01Y-425456D02*
Y-415056D01*
G01X-2045154Y-425456D02*
Y-415056D01*
G01Y-417136D02*
X-2044179Y-416096D01*
X-2043204Y-415316D01*
X-2041839Y-415056D01*
X-2040864Y-415316D01*
X-2039694Y-416096D01*
G01X-2011109Y-425456D02*
Y-409856D01*
X-2002139Y-425456D01*
Y-409856D01*
G01X-1984434Y-411156D02*
X-1985604Y-410376D01*
X-1986969Y-409856D01*
X-1988529D01*
X-1990284Y-410636D01*
X-1991649Y-411936D01*
X-1992624Y-413496D01*
X-1993404Y-416096D01*
X-1993599Y-418436D01*
X-1993209Y-420776D01*
X-1992624Y-422336D01*
X-1991454Y-423896D01*
X-1990089Y-424936D01*
X-1988724Y-425456D01*
X-1987359D01*
X-1985994Y-424936D01*
X-1984824Y-424156D01*
X-1983849Y-423116D01*
G01X-1949414Y-409856D02*
Y-425456D01*
G01Y-423116D02*
X-1950194Y-424416D01*
X-1951364Y-425196D01*
X-1952729Y-425456D01*
X-1954289Y-424936D01*
X-1955459Y-423636D01*
X-1956239Y-422076D01*
X-1956434Y-420256D01*
X-1956239Y-418436D01*
X-1955459Y-416876D01*
X-1954289Y-415576D01*
X-1952729Y-415056D01*
X-1951364Y-415316D01*
X-1950389Y-415836D01*
X-1949414Y-416876D01*
G01X-1937754Y-425456D02*
Y-415056D01*
G01Y-417136D02*
X-1936779Y-416096D01*
X-1935804Y-415316D01*
X-1934439Y-415056D01*
X-1933464Y-415316D01*
X-1932294Y-416096D01*
G01X-1917124Y-415056D02*
Y-425456D01*
G01Y-410896D02*
X-1917514Y-410636D01*
Y-410116D01*
X-1917124Y-409856D01*
X-1916734Y-410116D01*
Y-410636D01*
X-1917124Y-410896D01*
G01X-1899224Y-425456D02*
Y-409856D01*
G01X-1881324Y-425456D02*
Y-409856D01*
G01X-1842014D02*
Y-425456D01*
G01Y-423116D02*
X-1842794Y-424416D01*
X-1843964Y-425196D01*
X-1845329Y-425456D01*
X-1846889Y-424936D01*
X-1848059Y-423636D01*
X-1848839Y-422076D01*
X-1849034Y-420256D01*
X-1848839Y-418436D01*
X-1848059Y-416876D01*
X-1846889Y-415576D01*
X-1845329Y-415056D01*
X-1843964Y-415316D01*
X-1842989Y-415836D01*
X-1842014Y-416876D01*
G01X-1827624Y-425456D02*
X-1828794Y-425196D01*
X-1829964Y-424156D01*
X-1830744Y-422336D01*
X-1831134Y-420256D01*
X-1830744Y-418176D01*
X-1829964Y-416356D01*
X-1828794Y-415316D01*
X-1827624Y-415056D01*
X-1826454Y-415316D01*
X-1825284Y-416356D01*
X-1824504Y-418176D01*
X-1824309Y-420256D01*
X-1824504Y-422336D01*
X-1825284Y-424156D01*
X-1826454Y-425196D01*
X-1827624Y-425456D01*
G01X-1806604Y-416356D02*
X-1807969Y-415316D01*
X-1809139Y-415056D01*
X-1810699Y-415576D01*
X-1811869Y-416616D01*
X-1812649Y-418436D01*
X-1812844Y-420256D01*
X-1812649Y-422076D01*
X-1811869Y-423636D01*
X-1810699Y-424936D01*
X-1809139Y-425456D01*
X-1807774Y-424936D01*
X-1806604Y-423896D01*
G01X-1795139Y-415056D02*
Y-422336D01*
X-1794359Y-424156D01*
X-1793189Y-425196D01*
X-1791824Y-425456D01*
X-1790459Y-425196D01*
X-1789289Y-424156D01*
X-1788509Y-422336D01*
G01Y-425456D02*
Y-415056D01*
G01X-1779774Y-425456D02*
Y-415056D01*
G01Y-417916D02*
X-1779189Y-416616D01*
X-1778214Y-415576D01*
X-1776849Y-415056D01*
X-1775484Y-415576D01*
X-1774509Y-416616D01*
X-1773924Y-417916D01*
Y-425456D01*
G01Y-417916D02*
X-1773339Y-416616D01*
X-1772364Y-415576D01*
X-1770999Y-415056D01*
X-1769634Y-415576D01*
X-1768659Y-416616D01*
X-1768074Y-418176D01*
Y-425456D01*
G01X-1758949Y-418436D02*
X-1752709D01*
X-1753294Y-416616D01*
X-1754269Y-415576D01*
X-1755634Y-415056D01*
X-1756999Y-415316D01*
X-1758169Y-416096D01*
X-1758949Y-417916D01*
X-1759339Y-419476D01*
Y-421036D01*
X-1758949Y-422596D01*
X-1757974Y-424156D01*
X-1756804Y-425196D01*
X-1755439Y-425456D01*
X-1754074Y-424936D01*
X-1752709Y-423376D01*
G01X-1741439Y-425456D02*
Y-415056D01*
G01Y-417656D02*
X-1740659Y-416356D01*
X-1739489Y-415316D01*
X-1737929Y-415056D01*
X-1736564Y-415316D01*
X-1735394Y-416356D01*
X-1734809Y-418176D01*
Y-425456D01*
G01X-1720224Y-409856D02*
Y-425456D01*
G01X-1722954Y-415056D02*
X-1717494D01*
G01X-1698814Y-425456D02*
Y-415056D01*
G01Y-416876D02*
X-1699594Y-415836D01*
X-1700764Y-415316D01*
X-1702129Y-415056D01*
X-1703494Y-415576D01*
X-1704664Y-416616D01*
X-1705444Y-418176D01*
X-1705834Y-420256D01*
X-1705444Y-422336D01*
X-1704664Y-423896D01*
X-1703494Y-424936D01*
X-1702129Y-425456D01*
X-1700764Y-425196D01*
X-1699594Y-424416D01*
X-1698814Y-423376D01*
G01X-1684424Y-409856D02*
Y-425456D01*
G01X-1687154Y-415056D02*
X-1681694D01*
G01X-1666524D02*
Y-425456D01*
G01Y-410896D02*
X-1666914Y-410636D01*
Y-410116D01*
X-1666524Y-409856D01*
X-1666134Y-410116D01*
Y-410636D01*
X-1666524Y-410896D01*
G01X-1648624Y-425456D02*
X-1649794Y-425196D01*
X-1650964Y-424156D01*
X-1651744Y-422336D01*
X-1652134Y-420256D01*
X-1651744Y-418176D01*
X-1650964Y-416356D01*
X-1649794Y-415316D01*
X-1648624Y-415056D01*
X-1647454Y-415316D01*
X-1646284Y-416356D01*
X-1645504Y-418176D01*
X-1645309Y-420256D01*
X-1645504Y-422336D01*
X-1646284Y-424156D01*
X-1647454Y-425196D01*
X-1648624Y-425456D01*
G01X-1634039D02*
Y-415056D01*
G01Y-417656D02*
X-1633259Y-416356D01*
X-1632089Y-415316D01*
X-1630529Y-415056D01*
X-1629164Y-415316D01*
X-1627994Y-416356D01*
X-1627409Y-418176D01*
Y-425456D01*
G01X-1599799Y-415056D02*
X-1597459Y-425456D01*
X-1594924Y-415056D01*
X-1592389Y-425456D01*
X-1590049Y-415056D01*
G01X-1577024D02*
Y-425456D01*
G01Y-410896D02*
X-1577414Y-410636D01*
Y-410116D01*
X-1577024Y-409856D01*
X-1576634Y-410116D01*
Y-410636D01*
X-1577024Y-410896D01*
G01X-1559124Y-425456D02*
Y-409856D01*
G01X-1541224Y-425456D02*
Y-409856D01*
G01X-1505424Y-415056D02*
Y-425456D01*
G01Y-410896D02*
X-1505814Y-410636D01*
Y-410116D01*
X-1505424Y-409856D01*
X-1505034Y-410116D01*
Y-410636D01*
X-1505424Y-410896D01*
G01X-1490839Y-425456D02*
Y-415056D01*
G01Y-417656D02*
X-1490059Y-416356D01*
X-1488889Y-415316D01*
X-1487329Y-415056D01*
X-1485964Y-415316D01*
X-1484794Y-416356D01*
X-1484209Y-418176D01*
Y-425456D01*
G01X-1466504Y-416356D02*
X-1467869Y-415316D01*
X-1469039Y-415056D01*
X-1470599Y-415576D01*
X-1471769Y-416616D01*
X-1472549Y-418436D01*
X-1472744Y-420256D01*
X-1472549Y-422076D01*
X-1471769Y-423636D01*
X-1470599Y-424936D01*
X-1469039Y-425456D01*
X-1467674Y-424936D01*
X-1466504Y-423896D01*
G01X-1451724Y-425456D02*
Y-409856D01*
G01X-1437139Y-415056D02*
Y-422336D01*
X-1436359Y-424156D01*
X-1435189Y-425196D01*
X-1433824Y-425456D01*
X-1432459Y-425196D01*
X-1431289Y-424156D01*
X-1430509Y-422336D01*
G01Y-425456D02*
Y-415056D01*
G01X-1412414Y-409856D02*
Y-425456D01*
G01Y-423116D02*
X-1413194Y-424416D01*
X-1414364Y-425196D01*
X-1415729Y-425456D01*
X-1417289Y-424936D01*
X-1418459Y-423636D01*
X-1419239Y-422076D01*
X-1419434Y-420256D01*
X-1419239Y-418436D01*
X-1418459Y-416876D01*
X-1417289Y-415576D01*
X-1415729Y-415056D01*
X-1414364Y-415316D01*
X-1413389Y-415836D01*
X-1412414Y-416876D01*
G01X-1400949Y-418436D02*
X-1394709D01*
X-1395294Y-416616D01*
X-1396269Y-415576D01*
X-1397634Y-415056D01*
X-1398999Y-415316D01*
X-1400169Y-416096D01*
X-1400949Y-417916D01*
X-1401339Y-419476D01*
Y-421036D01*
X-1400949Y-422596D01*
X-1399974Y-424156D01*
X-1398804Y-425196D01*
X-1397439Y-425456D01*
X-1396074Y-424936D01*
X-1394709Y-423376D01*
G01X-1362224Y-425456D02*
Y-409856D01*
X-1364564Y-412976D01*
G01Y-425456D02*
X-1359884D01*
G01X-1329934D02*
Y-409856D01*
G01Y-417656D02*
X-1328959Y-416096D01*
X-1327789Y-415316D01*
X-1326619Y-415056D01*
X-1324864Y-415576D01*
X-1323694Y-416616D01*
X-1322914Y-418436D01*
Y-420516D01*
X-1323304Y-422596D01*
X-1324084Y-424156D01*
X-1325449Y-425196D01*
X-1326619Y-425456D01*
X-1327789Y-425196D01*
X-1328959Y-424416D01*
X-1329934Y-423116D01*
G01X-1305014Y-425456D02*
Y-415056D01*
G01Y-416876D02*
X-1305794Y-415836D01*
X-1306964Y-415316D01*
X-1308329Y-415056D01*
X-1309694Y-415576D01*
X-1310864Y-416616D01*
X-1311644Y-418176D01*
X-1312034Y-420256D01*
X-1311644Y-422336D01*
X-1310864Y-423896D01*
X-1309694Y-424936D01*
X-1308329Y-425456D01*
X-1306964Y-425196D01*
X-1305794Y-424416D01*
X-1305014Y-423376D01*
G01X-1287504Y-416356D02*
X-1288869Y-415316D01*
X-1290039Y-415056D01*
X-1291599Y-415576D01*
X-1292769Y-416616D01*
X-1293549Y-418436D01*
X-1293744Y-420256D01*
X-1293549Y-422076D01*
X-1292769Y-423636D01*
X-1291599Y-424936D01*
X-1290039Y-425456D01*
X-1288674Y-424936D01*
X-1287504Y-423896D01*
G01X-1276039Y-425456D02*
Y-409856D01*
G01X-1269799Y-415056D02*
X-1276039Y-421036D01*
G01X-1273504Y-418696D02*
X-1269409Y-425456D01*
G01X-1251314Y-409856D02*
Y-425456D01*
G01Y-423116D02*
X-1252094Y-424416D01*
X-1253264Y-425196D01*
X-1254629Y-425456D01*
X-1256189Y-424936D01*
X-1257359Y-423636D01*
X-1258139Y-422076D01*
X-1258334Y-420256D01*
X-1258139Y-418436D01*
X-1257359Y-416876D01*
X-1256189Y-415576D01*
X-1254629Y-415056D01*
X-1253264Y-415316D01*
X-1252289Y-415836D01*
X-1251314Y-416876D01*
G01X-1239654Y-425456D02*
Y-415056D01*
G01Y-417136D02*
X-1238679Y-416096D01*
X-1237704Y-415316D01*
X-1236339Y-415056D01*
X-1235364Y-415316D01*
X-1234194Y-416096D01*
G01X-1219024Y-415056D02*
Y-425456D01*
G01Y-410896D02*
X-1219414Y-410636D01*
Y-410116D01*
X-1219024Y-409856D01*
X-1218634Y-410116D01*
Y-410636D01*
X-1219024Y-410896D01*
G01X-1201124Y-425456D02*
Y-409856D01*
G01X-1183224Y-425456D02*
Y-409856D01*
G01X-1148594Y-425456D02*
Y-412196D01*
X-1148204Y-410896D01*
X-1147424Y-410116D01*
X-1146254Y-409856D01*
X-1145084Y-410376D01*
X-1144499Y-411676D01*
G01X-1146839Y-416096D02*
X-1150739D01*
G01X-1129524Y-415056D02*
Y-425456D01*
G01Y-410896D02*
X-1129914Y-410636D01*
Y-410116D01*
X-1129524Y-409856D01*
X-1129134Y-410116D01*
Y-410636D01*
X-1129524Y-410896D01*
G01X-1111624Y-425456D02*
Y-409856D01*
G01X-1096649Y-418436D02*
X-1090409D01*
X-1090994Y-416616D01*
X-1091969Y-415576D01*
X-1093334Y-415056D01*
X-1094699Y-415316D01*
X-1095869Y-416096D01*
X-1096649Y-417916D01*
X-1097039Y-419476D01*
Y-421036D01*
X-1096649Y-422596D01*
X-1095674Y-424156D01*
X-1094504Y-425196D01*
X-1093139Y-425456D01*
X-1091774Y-424936D01*
X-1090409Y-423376D01*
G01X-1078749Y-423636D02*
X-1077774Y-424676D01*
X-1076409Y-425456D01*
X-1075239D01*
X-1074069Y-424936D01*
X-1073289Y-424156D01*
X-1072899Y-423116D01*
X-1073094Y-421556D01*
X-1073874Y-420776D01*
X-1077384Y-419216D01*
X-1078164Y-417396D01*
X-1077774Y-416096D01*
X-1076994Y-415316D01*
X-1075824Y-415056D01*
X-1074654Y-415316D01*
X-1073484Y-416096D01*
G01X-1041194Y-425456D02*
Y-412196D01*
X-1040804Y-410896D01*
X-1040024Y-410116D01*
X-1038854Y-409856D01*
X-1037684Y-410376D01*
X-1037099Y-411676D01*
G01X-1039439Y-416096D02*
X-1043339D01*
G01X-1022124Y-425456D02*
X-1023294Y-425196D01*
X-1024464Y-424156D01*
X-1025244Y-422336D01*
X-1025634Y-420256D01*
X-1025244Y-418176D01*
X-1024464Y-416356D01*
X-1023294Y-415316D01*
X-1022124Y-415056D01*
X-1020954Y-415316D01*
X-1019784Y-416356D01*
X-1019004Y-418176D01*
X-1018809Y-420256D01*
X-1019004Y-422336D01*
X-1019784Y-424156D01*
X-1020954Y-425196D01*
X-1022124Y-425456D01*
G01X-1006954D02*
Y-415056D01*
G01Y-417136D02*
X-1005979Y-416096D01*
X-1005004Y-415316D01*
X-1003639Y-415056D01*
X-1002664Y-415316D01*
X-1001494Y-416096D01*
G01X-971934Y-425456D02*
Y-409856D01*
G01Y-417656D02*
X-970959Y-416096D01*
X-969789Y-415316D01*
X-968619Y-415056D01*
X-966864Y-415576D01*
X-965694Y-416616D01*
X-964914Y-418436D01*
Y-420516D01*
X-965304Y-422596D01*
X-966084Y-424156D01*
X-967449Y-425196D01*
X-968619Y-425456D01*
X-969789Y-425196D01*
X-970959Y-424416D01*
X-971934Y-423116D01*
G01X-950524Y-425456D02*
X-951694Y-425196D01*
X-952864Y-424156D01*
X-953644Y-422336D01*
X-954034Y-420256D01*
X-953644Y-418176D01*
X-952864Y-416356D01*
X-951694Y-415316D01*
X-950524Y-415056D01*
X-949354Y-415316D01*
X-948184Y-416356D01*
X-947404Y-418176D01*
X-947209Y-420256D01*
X-947404Y-422336D01*
X-948184Y-424156D01*
X-949354Y-425196D01*
X-950524Y-425456D01*
G01X-932624Y-409856D02*
Y-425456D01*
G01X-935354Y-415056D02*
X-929894D01*
G01X-914724Y-409856D02*
Y-425456D01*
G01X-917454Y-415056D02*
X-911994D01*
G01X-896824Y-425456D02*
X-897994Y-425196D01*
X-899164Y-424156D01*
X-899944Y-422336D01*
X-900334Y-420256D01*
X-899944Y-418176D01*
X-899164Y-416356D01*
X-897994Y-415316D01*
X-896824Y-415056D01*
X-895654Y-415316D01*
X-894484Y-416356D01*
X-893704Y-418176D01*
X-893509Y-420256D01*
X-893704Y-422336D01*
X-894484Y-424156D01*
X-895654Y-425196D01*
X-896824Y-425456D01*
G01X-884774D02*
Y-415056D01*
G01Y-417916D02*
X-884189Y-416616D01*
X-883214Y-415576D01*
X-881849Y-415056D01*
X-880484Y-415576D01*
X-879509Y-416616D01*
X-878924Y-417916D01*
Y-425456D01*
G01Y-417916D02*
X-878339Y-416616D01*
X-877364Y-415576D01*
X-875999Y-415056D01*
X-874634Y-415576D01*
X-873659Y-416616D01*
X-873074Y-418176D01*
Y-425456D01*
G01X-2078224Y-375856D02*
Y-391456D01*
G01X-2082709Y-375856D02*
X-2073739D01*
G01X-2063639Y-391456D02*
Y-375856D01*
G01Y-383396D02*
X-2062664Y-382096D01*
X-2061689Y-381316D01*
X-2060129Y-381056D01*
X-2058959Y-381316D01*
X-2057594Y-382356D01*
X-2057009Y-383916D01*
Y-391456D01*
G01X-2045349Y-384436D02*
X-2039109D01*
X-2039694Y-382616D01*
X-2040669Y-381576D01*
X-2042034Y-381056D01*
X-2043399Y-381316D01*
X-2044569Y-382096D01*
X-2045349Y-383916D01*
X-2045739Y-385476D01*
Y-387036D01*
X-2045349Y-388596D01*
X-2044374Y-390156D01*
X-2043204Y-391196D01*
X-2041839Y-391456D01*
X-2040474Y-390936D01*
X-2039109Y-389376D01*
G01X-2010134Y-381056D02*
X-2006624Y-391456D01*
X-2003114Y-381056D01*
G01X-1991649Y-384436D02*
X-1985409D01*
X-1985994Y-382616D01*
X-1986969Y-381576D01*
X-1988334Y-381056D01*
X-1989699Y-381316D01*
X-1990869Y-382096D01*
X-1991649Y-383916D01*
X-1992039Y-385476D01*
Y-387036D01*
X-1991649Y-388596D01*
X-1990674Y-390156D01*
X-1989504Y-391196D01*
X-1988139Y-391456D01*
X-1986774Y-390936D01*
X-1985409Y-389376D01*
G01X-1974139Y-391456D02*
Y-381056D01*
G01Y-383656D02*
X-1973359Y-382356D01*
X-1972189Y-381316D01*
X-1970629Y-381056D01*
X-1969264Y-381316D01*
X-1968094Y-382356D01*
X-1967509Y-384176D01*
Y-391456D01*
G01X-1949414Y-375856D02*
Y-391456D01*
G01Y-389116D02*
X-1950194Y-390416D01*
X-1951364Y-391196D01*
X-1952729Y-391456D01*
X-1954289Y-390936D01*
X-1955459Y-389636D01*
X-1956239Y-388076D01*
X-1956434Y-386256D01*
X-1956239Y-384436D01*
X-1955459Y-382876D01*
X-1954289Y-381576D01*
X-1952729Y-381056D01*
X-1951364Y-381316D01*
X-1950389Y-381836D01*
X-1949414Y-382876D01*
G01X-1935024Y-391456D02*
X-1936194Y-391196D01*
X-1937364Y-390156D01*
X-1938144Y-388336D01*
X-1938534Y-386256D01*
X-1938144Y-384176D01*
X-1937364Y-382356D01*
X-1936194Y-381316D01*
X-1935024Y-381056D01*
X-1933854Y-381316D01*
X-1932684Y-382356D01*
X-1931904Y-384176D01*
X-1931709Y-386256D01*
X-1931904Y-388336D01*
X-1932684Y-390156D01*
X-1933854Y-391196D01*
X-1935024Y-391456D01*
G01X-1919854D02*
Y-381056D01*
G01Y-383136D02*
X-1918879Y-382096D01*
X-1917904Y-381316D01*
X-1916539Y-381056D01*
X-1915564Y-381316D01*
X-1914394Y-382096D01*
G01X-1881324Y-381056D02*
Y-391456D01*
G01Y-376896D02*
X-1881714Y-376636D01*
Y-376116D01*
X-1881324Y-375856D01*
X-1880934Y-376116D01*
Y-376636D01*
X-1881324Y-376896D01*
G01X-1866349Y-389636D02*
X-1865374Y-390676D01*
X-1864009Y-391456D01*
X-1862839D01*
X-1861669Y-390936D01*
X-1860889Y-390156D01*
X-1860499Y-389116D01*
X-1860694Y-387556D01*
X-1861474Y-386776D01*
X-1864984Y-385216D01*
X-1865764Y-383396D01*
X-1865374Y-382096D01*
X-1864594Y-381316D01*
X-1863424Y-381056D01*
X-1862254Y-381316D01*
X-1861084Y-382096D01*
G01X-1830354Y-391456D02*
Y-381056D01*
G01Y-383136D02*
X-1829379Y-382096D01*
X-1828404Y-381316D01*
X-1827039Y-381056D01*
X-1826064Y-381316D01*
X-1824894Y-382096D01*
G01X-1812649Y-384436D02*
X-1806409D01*
X-1806994Y-382616D01*
X-1807969Y-381576D01*
X-1809334Y-381056D01*
X-1810699Y-381316D01*
X-1811869Y-382096D01*
X-1812649Y-383916D01*
X-1813039Y-385476D01*
Y-387036D01*
X-1812649Y-388596D01*
X-1811674Y-390156D01*
X-1810504Y-391196D01*
X-1809139Y-391456D01*
X-1807774Y-390936D01*
X-1806409Y-389376D01*
G01X-1788314Y-396656D02*
Y-381056D01*
G01Y-383396D02*
X-1789289Y-382096D01*
X-1790459Y-381316D01*
X-1791824Y-381056D01*
X-1792994Y-381316D01*
X-1794359Y-382616D01*
X-1795139Y-384436D01*
X-1795334Y-386256D01*
X-1795139Y-388076D01*
X-1794359Y-389896D01*
X-1792994Y-391196D01*
X-1791824Y-391456D01*
X-1790459Y-391196D01*
X-1789289Y-390416D01*
X-1788314Y-389116D01*
G01X-1777239Y-381056D02*
Y-388336D01*
X-1776459Y-390156D01*
X-1775289Y-391196D01*
X-1773924Y-391456D01*
X-1772559Y-391196D01*
X-1771389Y-390156D01*
X-1770609Y-388336D01*
G01Y-391456D02*
Y-381056D01*
G01X-1758949Y-384436D02*
X-1752709D01*
X-1753294Y-382616D01*
X-1754269Y-381576D01*
X-1755634Y-381056D01*
X-1756999Y-381316D01*
X-1758169Y-382096D01*
X-1758949Y-383916D01*
X-1759339Y-385476D01*
Y-387036D01*
X-1758949Y-388596D01*
X-1757974Y-390156D01*
X-1756804Y-391196D01*
X-1755439Y-391456D01*
X-1754074Y-390936D01*
X-1752709Y-389376D01*
G01X-1741049Y-389636D02*
X-1740074Y-390676D01*
X-1738709Y-391456D01*
X-1737539D01*
X-1736369Y-390936D01*
X-1735589Y-390156D01*
X-1735199Y-389116D01*
X-1735394Y-387556D01*
X-1736174Y-386776D01*
X-1739684Y-385216D01*
X-1740464Y-383396D01*
X-1740074Y-382096D01*
X-1739294Y-381316D01*
X-1738124Y-381056D01*
X-1736954Y-381316D01*
X-1735784Y-382096D01*
G01X-1720224Y-375856D02*
Y-391456D01*
G01X-1722954Y-381056D02*
X-1717494D01*
G01X-1705249Y-384436D02*
X-1699009D01*
X-1699594Y-382616D01*
X-1700569Y-381576D01*
X-1701934Y-381056D01*
X-1703299Y-381316D01*
X-1704469Y-382096D01*
X-1705249Y-383916D01*
X-1705639Y-385476D01*
Y-387036D01*
X-1705249Y-388596D01*
X-1704274Y-390156D01*
X-1703104Y-391196D01*
X-1701739Y-391456D01*
X-1700374Y-390936D01*
X-1699009Y-389376D01*
G01X-1680914Y-375856D02*
Y-391456D01*
G01Y-389116D02*
X-1681694Y-390416D01*
X-1682864Y-391196D01*
X-1684229Y-391456D01*
X-1685789Y-390936D01*
X-1686959Y-389636D01*
X-1687739Y-388076D01*
X-1687934Y-386256D01*
X-1687739Y-384436D01*
X-1686959Y-382876D01*
X-1685789Y-381576D01*
X-1684229Y-381056D01*
X-1682864Y-381316D01*
X-1681889Y-381836D01*
X-1680914Y-382876D01*
G01X-1648624Y-375856D02*
Y-391456D01*
G01X-1651354Y-381056D02*
X-1645894D01*
G01X-1630724Y-391456D02*
X-1631894Y-391196D01*
X-1633064Y-390156D01*
X-1633844Y-388336D01*
X-1634234Y-386256D01*
X-1633844Y-384176D01*
X-1633064Y-382356D01*
X-1631894Y-381316D01*
X-1630724Y-381056D01*
X-1629554Y-381316D01*
X-1628384Y-382356D01*
X-1627604Y-384176D01*
X-1627409Y-386256D01*
X-1627604Y-388336D01*
X-1628384Y-390156D01*
X-1629554Y-391196D01*
X-1630724Y-391456D01*
G01X-1591414D02*
Y-381056D01*
G01Y-382876D02*
X-1592194Y-381836D01*
X-1593364Y-381316D01*
X-1594729Y-381056D01*
X-1596094Y-381576D01*
X-1597264Y-382616D01*
X-1598044Y-384176D01*
X-1598434Y-386256D01*
X-1598044Y-388336D01*
X-1597264Y-389896D01*
X-1596094Y-390936D01*
X-1594729Y-391456D01*
X-1593364Y-391196D01*
X-1592194Y-390416D01*
X-1591414Y-389376D01*
G01X-1573514Y-375856D02*
Y-391456D01*
G01Y-389116D02*
X-1574294Y-390416D01*
X-1575464Y-391196D01*
X-1576829Y-391456D01*
X-1578389Y-390936D01*
X-1579559Y-389636D01*
X-1580339Y-388076D01*
X-1580534Y-386256D01*
X-1580339Y-384436D01*
X-1579559Y-382876D01*
X-1578389Y-381576D01*
X-1576829Y-381056D01*
X-1575464Y-381316D01*
X-1574489Y-381836D01*
X-1573514Y-382876D01*
G01X-1562244Y-395356D02*
X-1560879Y-396396D01*
X-1559709Y-396656D01*
X-1558149Y-396136D01*
X-1556979Y-394836D01*
X-1556394Y-392496D01*
Y-381056D01*
G01Y-376896D02*
X-1556784Y-376636D01*
Y-376116D01*
X-1556394Y-375856D01*
X-1556004Y-376116D01*
Y-376636D01*
X-1556394Y-376896D01*
G01X-1544539Y-381056D02*
Y-388336D01*
X-1543759Y-390156D01*
X-1542589Y-391196D01*
X-1541224Y-391456D01*
X-1539859Y-391196D01*
X-1538689Y-390156D01*
X-1537909Y-388336D01*
G01Y-391456D02*
Y-381056D01*
G01X-1526249Y-389636D02*
X-1525274Y-390676D01*
X-1523909Y-391456D01*
X-1522739D01*
X-1521569Y-390936D01*
X-1520789Y-390156D01*
X-1520399Y-389116D01*
X-1520594Y-387556D01*
X-1521374Y-386776D01*
X-1524884Y-385216D01*
X-1525664Y-383396D01*
X-1525274Y-382096D01*
X-1524494Y-381316D01*
X-1523324Y-381056D01*
X-1522154Y-381316D01*
X-1520984Y-382096D01*
G01X-1505424Y-375856D02*
Y-391456D01*
G01X-1508154Y-381056D02*
X-1502694D01*
G01X-1473134Y-391456D02*
Y-375856D01*
G01Y-383656D02*
X-1472159Y-382096D01*
X-1470989Y-381316D01*
X-1469819Y-381056D01*
X-1468064Y-381576D01*
X-1466894Y-382616D01*
X-1466114Y-384436D01*
Y-386516D01*
X-1466504Y-388596D01*
X-1467284Y-390156D01*
X-1468649Y-391196D01*
X-1469819Y-391456D01*
X-1470989Y-391196D01*
X-1472159Y-390416D01*
X-1473134Y-389116D01*
G01X-1448214Y-391456D02*
Y-381056D01*
G01Y-382876D02*
X-1448994Y-381836D01*
X-1450164Y-381316D01*
X-1451529Y-381056D01*
X-1452894Y-381576D01*
X-1454064Y-382616D01*
X-1454844Y-384176D01*
X-1455234Y-386256D01*
X-1454844Y-388336D01*
X-1454064Y-389896D01*
X-1452894Y-390936D01*
X-1451529Y-391456D01*
X-1450164Y-391196D01*
X-1448994Y-390416D01*
X-1448214Y-389376D01*
G01X-1430704Y-382356D02*
X-1432069Y-381316D01*
X-1433239Y-381056D01*
X-1434799Y-381576D01*
X-1435969Y-382616D01*
X-1436749Y-384436D01*
X-1436944Y-386256D01*
X-1436749Y-388076D01*
X-1435969Y-389636D01*
X-1434799Y-390936D01*
X-1433239Y-391456D01*
X-1431874Y-390936D01*
X-1430704Y-389896D01*
G01X-1419239Y-391456D02*
Y-375856D01*
G01X-1412999Y-381056D02*
X-1419239Y-387036D01*
G01X-1416704Y-384696D02*
X-1412609Y-391456D01*
G01X-1394514Y-375856D02*
Y-391456D01*
G01Y-389116D02*
X-1395294Y-390416D01*
X-1396464Y-391196D01*
X-1397829Y-391456D01*
X-1399389Y-390936D01*
X-1400559Y-389636D01*
X-1401339Y-388076D01*
X-1401534Y-386256D01*
X-1401339Y-384436D01*
X-1400559Y-382876D01*
X-1399389Y-381576D01*
X-1397829Y-381056D01*
X-1396464Y-381316D01*
X-1395489Y-381836D01*
X-1394514Y-382876D01*
G01X-1382854Y-391456D02*
Y-381056D01*
G01Y-383136D02*
X-1381879Y-382096D01*
X-1380904Y-381316D01*
X-1379539Y-381056D01*
X-1378564Y-381316D01*
X-1377394Y-382096D01*
G01X-1362224Y-381056D02*
Y-391456D01*
G01Y-376896D02*
X-1362614Y-376636D01*
Y-376116D01*
X-1362224Y-375856D01*
X-1361834Y-376116D01*
Y-376636D01*
X-1362224Y-376896D01*
G01X-1344324Y-391456D02*
Y-375856D01*
G01X-1326424Y-391456D02*
Y-375856D01*
G01X-1294134Y-396656D02*
Y-381056D01*
G01Y-383396D02*
X-1293159Y-382096D01*
X-1292184Y-381316D01*
X-1290624Y-381056D01*
X-1289259Y-381316D01*
X-1287894Y-382616D01*
X-1287309Y-384436D01*
X-1287114Y-386256D01*
X-1287309Y-388076D01*
X-1287894Y-389896D01*
X-1289064Y-390936D01*
X-1290624Y-391456D01*
X-1291989Y-391196D01*
X-1293354Y-390416D01*
X-1294134Y-389376D01*
G01X-1272724Y-391456D02*
Y-375856D01*
G01X-1258139Y-381056D02*
Y-388336D01*
X-1257359Y-390156D01*
X-1256189Y-391196D01*
X-1254824Y-391456D01*
X-1253459Y-391196D01*
X-1252289Y-390156D01*
X-1251509Y-388336D01*
G01Y-391456D02*
Y-381056D01*
G01X-1240239Y-391456D02*
Y-381056D01*
G01Y-383656D02*
X-1239459Y-382356D01*
X-1238289Y-381316D01*
X-1236729Y-381056D01*
X-1235364Y-381316D01*
X-1234194Y-382356D01*
X-1233609Y-384176D01*
Y-391456D01*
G01X-1221754Y-395356D02*
X-1220389Y-396396D01*
X-1218829Y-396656D01*
X-1217464Y-396396D01*
X-1216294Y-395096D01*
X-1215514Y-393276D01*
Y-381056D01*
G01Y-383136D02*
X-1216294Y-382096D01*
X-1217464Y-381316D01*
X-1218829Y-381056D01*
X-1220389Y-381576D01*
X-1221364Y-382616D01*
X-1222144Y-384436D01*
X-1222534Y-386256D01*
X-1222339Y-387816D01*
X-1221559Y-389636D01*
X-1220389Y-390936D01*
X-1218829Y-391456D01*
X-1217659Y-391196D01*
X-1216294Y-390156D01*
X-1215514Y-389116D01*
G01X-1204049Y-384436D02*
X-1197809D01*
X-1198394Y-382616D01*
X-1199369Y-381576D01*
X-1200734Y-381056D01*
X-1202099Y-381316D01*
X-1203269Y-382096D01*
X-1204049Y-383916D01*
X-1204439Y-385476D01*
Y-387036D01*
X-1204049Y-388596D01*
X-1203074Y-390156D01*
X-1201904Y-391196D01*
X-1200539Y-391456D01*
X-1199174Y-390936D01*
X-1197809Y-389376D01*
G01X-1161814Y-375856D02*
Y-391456D01*
G01Y-389116D02*
X-1162594Y-390416D01*
X-1163764Y-391196D01*
X-1165129Y-391456D01*
X-1166689Y-390936D01*
X-1167859Y-389636D01*
X-1168639Y-388076D01*
X-1168834Y-386256D01*
X-1168639Y-384436D01*
X-1167859Y-382876D01*
X-1166689Y-381576D01*
X-1165129Y-381056D01*
X-1163764Y-381316D01*
X-1162789Y-381836D01*
X-1161814Y-382876D01*
G01X-1150349Y-384436D02*
X-1144109D01*
X-1144694Y-382616D01*
X-1145669Y-381576D01*
X-1147034Y-381056D01*
X-1148399Y-381316D01*
X-1149569Y-382096D01*
X-1150349Y-383916D01*
X-1150739Y-385476D01*
Y-387036D01*
X-1150349Y-388596D01*
X-1149374Y-390156D01*
X-1148204Y-391196D01*
X-1146839Y-391456D01*
X-1145474Y-390936D01*
X-1144109Y-389376D01*
G01X-1133034Y-396656D02*
Y-381056D01*
G01Y-383396D02*
X-1132059Y-382096D01*
X-1131084Y-381316D01*
X-1129524Y-381056D01*
X-1128159Y-381316D01*
X-1126794Y-382616D01*
X-1126209Y-384436D01*
X-1126014Y-386256D01*
X-1126209Y-388076D01*
X-1126794Y-389896D01*
X-1127964Y-390936D01*
X-1129524Y-391456D01*
X-1130889Y-391196D01*
X-1132254Y-390416D01*
X-1133034Y-389376D01*
G01X-1111624Y-375856D02*
Y-391456D01*
G01X-1114354Y-381056D02*
X-1108894D01*
G01X-1097039Y-391456D02*
Y-375856D01*
G01Y-383396D02*
X-1096064Y-382096D01*
X-1095089Y-381316D01*
X-1093529Y-381056D01*
X-1092359Y-381316D01*
X-1090994Y-382356D01*
X-1090409Y-383916D01*
Y-391456D01*
G01X-1078749Y-389636D02*
X-1077774Y-390676D01*
X-1076409Y-391456D01*
X-1075239D01*
X-1074069Y-390936D01*
X-1073289Y-390156D01*
X-1072899Y-389116D01*
X-1073094Y-387556D01*
X-1073874Y-386776D01*
X-1077384Y-385216D01*
X-1078164Y-383396D01*
X-1077774Y-382096D01*
X-1076994Y-381316D01*
X-1075824Y-381056D01*
X-1074654Y-381316D01*
X-1073484Y-382096D01*
G01X-1036514Y-391456D02*
Y-381056D01*
G01Y-382876D02*
X-1037294Y-381836D01*
X-1038464Y-381316D01*
X-1039829Y-381056D01*
X-1041194Y-381576D01*
X-1042364Y-382616D01*
X-1043144Y-384176D01*
X-1043534Y-386256D01*
X-1043144Y-388336D01*
X-1042364Y-389896D01*
X-1041194Y-390936D01*
X-1039829Y-391456D01*
X-1038464Y-391196D01*
X-1037294Y-390416D01*
X-1036514Y-389376D01*
G01X-1019004Y-382356D02*
X-1020369Y-381316D01*
X-1021539Y-381056D01*
X-1023099Y-381576D01*
X-1024269Y-382616D01*
X-1025049Y-384436D01*
X-1025244Y-386256D01*
X-1025049Y-388076D01*
X-1024269Y-389636D01*
X-1023099Y-390936D01*
X-1021539Y-391456D01*
X-1020174Y-390936D01*
X-1019004Y-389896D01*
G01X-1001104Y-382356D02*
X-1002469Y-381316D01*
X-1003639Y-381056D01*
X-1005199Y-381576D01*
X-1006369Y-382616D01*
X-1007149Y-384436D01*
X-1007344Y-386256D01*
X-1007149Y-388076D01*
X-1006369Y-389636D01*
X-1005199Y-390936D01*
X-1003639Y-391456D01*
X-1002274Y-390936D01*
X-1001104Y-389896D01*
G01X-986324Y-391456D02*
X-987494Y-391196D01*
X-988664Y-390156D01*
X-989444Y-388336D01*
X-989834Y-386256D01*
X-989444Y-384176D01*
X-988664Y-382356D01*
X-987494Y-381316D01*
X-986324Y-381056D01*
X-985154Y-381316D01*
X-983984Y-382356D01*
X-983204Y-384176D01*
X-983009Y-386256D01*
X-983204Y-388336D01*
X-983984Y-390156D01*
X-985154Y-391196D01*
X-986324Y-391456D01*
G01X-971154D02*
Y-381056D01*
G01Y-383136D02*
X-970179Y-382096D01*
X-969204Y-381316D01*
X-967839Y-381056D01*
X-966864Y-381316D01*
X-965694Y-382096D01*
G01X-947014Y-375856D02*
Y-391456D01*
G01Y-389116D02*
X-947794Y-390416D01*
X-948964Y-391196D01*
X-950329Y-391456D01*
X-951889Y-390936D01*
X-953059Y-389636D01*
X-953839Y-388076D01*
X-954034Y-386256D01*
X-953839Y-384436D01*
X-953059Y-382876D01*
X-951889Y-381576D01*
X-950329Y-381056D01*
X-948964Y-381316D01*
X-947989Y-381836D01*
X-947014Y-382876D01*
G01X-932624Y-381056D02*
Y-391456D01*
G01Y-376896D02*
X-933014Y-376636D01*
Y-376116D01*
X-932624Y-375856D01*
X-932234Y-376116D01*
Y-376636D01*
X-932624Y-376896D01*
G01X-918039Y-391456D02*
Y-381056D01*
G01Y-383656D02*
X-917259Y-382356D01*
X-916089Y-381316D01*
X-914529Y-381056D01*
X-913164Y-381316D01*
X-911994Y-382356D01*
X-911409Y-384176D01*
Y-391456D01*
G01X-899554Y-395356D02*
X-898189Y-396396D01*
X-896629Y-396656D01*
X-895264Y-396396D01*
X-894094Y-395096D01*
X-893314Y-393276D01*
Y-381056D01*
G01Y-383136D02*
X-894094Y-382096D01*
X-895264Y-381316D01*
X-896629Y-381056D01*
X-898189Y-381576D01*
X-899164Y-382616D01*
X-899944Y-384436D01*
X-900334Y-386256D01*
X-900139Y-387816D01*
X-899359Y-389636D01*
X-898189Y-390936D01*
X-896629Y-391456D01*
X-895459Y-391196D01*
X-894094Y-390156D01*
X-893314Y-389116D01*
G01X-878924Y-391456D02*
Y-375856D01*
G01X-865119Y-396136D02*
X-863949Y-396656D01*
X-862389Y-396136D01*
X-861414Y-395096D01*
X-860634Y-393796D01*
X-859464Y-389636D01*
X-856929Y-381056D01*
G01X-863169D02*
X-859464Y-389636D01*
G01X-843124Y-391976D02*
X-843514Y-391716D01*
Y-391196D01*
X-843124Y-390936D01*
X-842734Y-391196D01*
Y-391716D01*
X-843124Y-391976D01*
G01X-2078224Y-341856D02*
Y-357456D01*
G01X-2082709Y-341856D02*
X-2073739D01*
G01X-2063639Y-357456D02*
Y-341856D01*
G01Y-349396D02*
X-2062664Y-348096D01*
X-2061689Y-347316D01*
X-2060129Y-347056D01*
X-2058959Y-347316D01*
X-2057594Y-348356D01*
X-2057009Y-349916D01*
Y-357456D01*
G01X-2045349Y-350436D02*
X-2039109D01*
X-2039694Y-348616D01*
X-2040669Y-347576D01*
X-2042034Y-347056D01*
X-2043399Y-347316D01*
X-2044569Y-348096D01*
X-2045349Y-349916D01*
X-2045739Y-351476D01*
Y-353036D01*
X-2045349Y-354596D01*
X-2044374Y-356156D01*
X-2043204Y-357196D01*
X-2041839Y-357456D01*
X-2040474Y-356936D01*
X-2039109Y-355376D01*
G01X-2006624Y-347056D02*
Y-357456D01*
G01Y-342896D02*
X-2007014Y-342636D01*
Y-342116D01*
X-2006624Y-341856D01*
X-2006234Y-342116D01*
Y-342636D01*
X-2006624Y-342896D01*
G01X-1992039Y-357456D02*
Y-347056D01*
G01Y-349656D02*
X-1991259Y-348356D01*
X-1990089Y-347316D01*
X-1988529Y-347056D01*
X-1987164Y-347316D01*
X-1985994Y-348356D01*
X-1985409Y-350176D01*
Y-357456D01*
G01X-1970824Y-341856D02*
Y-357456D01*
G01X-1973554Y-347056D02*
X-1968094D01*
G01X-1955849Y-350436D02*
X-1949609D01*
X-1950194Y-348616D01*
X-1951169Y-347576D01*
X-1952534Y-347056D01*
X-1953899Y-347316D01*
X-1955069Y-348096D01*
X-1955849Y-349916D01*
X-1956239Y-351476D01*
Y-353036D01*
X-1955849Y-354596D01*
X-1954874Y-356156D01*
X-1953704Y-357196D01*
X-1952339Y-357456D01*
X-1950974Y-356936D01*
X-1949609Y-355376D01*
G01X-1937754Y-357456D02*
Y-347056D01*
G01Y-349136D02*
X-1936779Y-348096D01*
X-1935804Y-347316D01*
X-1934439Y-347056D01*
X-1933464Y-347316D01*
X-1932294Y-348096D01*
G01X-1919854Y-361356D02*
X-1918489Y-362396D01*
X-1916929Y-362656D01*
X-1915564Y-362396D01*
X-1914394Y-361096D01*
X-1913614Y-359276D01*
Y-347056D01*
G01Y-349136D02*
X-1914394Y-348096D01*
X-1915564Y-347316D01*
X-1916929Y-347056D01*
X-1918489Y-347576D01*
X-1919464Y-348616D01*
X-1920244Y-350436D01*
X-1920634Y-352256D01*
X-1920439Y-353816D01*
X-1919659Y-355636D01*
X-1918489Y-356936D01*
X-1916929Y-357456D01*
X-1915759Y-357196D01*
X-1914394Y-356156D01*
X-1913614Y-355116D01*
G01X-1901954Y-357456D02*
Y-347056D01*
G01Y-349136D02*
X-1900979Y-348096D01*
X-1900004Y-347316D01*
X-1898639Y-347056D01*
X-1897664Y-347316D01*
X-1896494Y-348096D01*
G01X-1881324Y-347056D02*
Y-357456D01*
G01Y-342896D02*
X-1881714Y-342636D01*
Y-342116D01*
X-1881324Y-341856D01*
X-1880934Y-342116D01*
Y-342636D01*
X-1881324Y-342896D01*
G01X-1863424Y-341856D02*
Y-357456D01*
G01X-1866154Y-347056D02*
X-1860694D01*
G01X-1849619Y-362136D02*
X-1848449Y-362656D01*
X-1846889Y-362136D01*
X-1845914Y-361096D01*
X-1845134Y-359796D01*
X-1843964Y-355636D01*
X-1841429Y-347056D01*
G01X-1847669D02*
X-1843964Y-355636D01*
G01X-1809724Y-357456D02*
X-1810894Y-357196D01*
X-1812064Y-356156D01*
X-1812844Y-354336D01*
X-1813234Y-352256D01*
X-1812844Y-350176D01*
X-1812064Y-348356D01*
X-1810894Y-347316D01*
X-1809724Y-347056D01*
X-1808554Y-347316D01*
X-1807384Y-348356D01*
X-1806604Y-350176D01*
X-1806409Y-352256D01*
X-1806604Y-354336D01*
X-1807384Y-356156D01*
X-1808554Y-357196D01*
X-1809724Y-357456D01*
G01X-1792994D02*
Y-344196D01*
X-1792604Y-342896D01*
X-1791824Y-342116D01*
X-1790654Y-341856D01*
X-1789484Y-342376D01*
X-1788899Y-343676D01*
G01X-1791239Y-348096D02*
X-1795139D01*
G01X-1752904Y-348356D02*
X-1754269Y-347316D01*
X-1755439Y-347056D01*
X-1756999Y-347576D01*
X-1758169Y-348616D01*
X-1758949Y-350436D01*
X-1759144Y-352256D01*
X-1758949Y-354076D01*
X-1758169Y-355636D01*
X-1756999Y-356936D01*
X-1755439Y-357456D01*
X-1754074Y-356936D01*
X-1752904Y-355896D01*
G01X-1738124Y-357456D02*
X-1739294Y-357196D01*
X-1740464Y-356156D01*
X-1741244Y-354336D01*
X-1741634Y-352256D01*
X-1741244Y-350176D01*
X-1740464Y-348356D01*
X-1739294Y-347316D01*
X-1738124Y-347056D01*
X-1736954Y-347316D01*
X-1735784Y-348356D01*
X-1735004Y-350176D01*
X-1734809Y-352256D01*
X-1735004Y-354336D01*
X-1735784Y-356156D01*
X-1736954Y-357196D01*
X-1738124Y-357456D01*
G01X-1723539D02*
Y-347056D01*
G01Y-349656D02*
X-1722759Y-348356D01*
X-1721589Y-347316D01*
X-1720029Y-347056D01*
X-1718664Y-347316D01*
X-1717494Y-348356D01*
X-1716909Y-350176D01*
Y-357456D01*
G01X-1705639D02*
Y-347056D01*
G01Y-349656D02*
X-1704859Y-348356D01*
X-1703689Y-347316D01*
X-1702129Y-347056D01*
X-1700764Y-347316D01*
X-1699594Y-348356D01*
X-1699009Y-350176D01*
Y-357456D01*
G01X-1687349Y-350436D02*
X-1681109D01*
X-1681694Y-348616D01*
X-1682669Y-347576D01*
X-1684034Y-347056D01*
X-1685399Y-347316D01*
X-1686569Y-348096D01*
X-1687349Y-349916D01*
X-1687739Y-351476D01*
Y-353036D01*
X-1687349Y-354596D01*
X-1686374Y-356156D01*
X-1685204Y-357196D01*
X-1683839Y-357456D01*
X-1682474Y-356936D01*
X-1681109Y-355376D01*
G01X-1663404Y-348356D02*
X-1664769Y-347316D01*
X-1665939Y-347056D01*
X-1667499Y-347576D01*
X-1668669Y-348616D01*
X-1669449Y-350436D01*
X-1669644Y-352256D01*
X-1669449Y-354076D01*
X-1668669Y-355636D01*
X-1667499Y-356936D01*
X-1665939Y-357456D01*
X-1664574Y-356936D01*
X-1663404Y-355896D01*
G01X-1648624Y-341856D02*
Y-357456D01*
G01X-1651354Y-347056D02*
X-1645894D01*
G01X-1630724D02*
Y-357456D01*
G01Y-342896D02*
X-1631114Y-342636D01*
Y-342116D01*
X-1630724Y-341856D01*
X-1630334Y-342116D01*
Y-342636D01*
X-1630724Y-342896D01*
G01X-1612824Y-357456D02*
X-1613994Y-357196D01*
X-1615164Y-356156D01*
X-1615944Y-354336D01*
X-1616334Y-352256D01*
X-1615944Y-350176D01*
X-1615164Y-348356D01*
X-1613994Y-347316D01*
X-1612824Y-347056D01*
X-1611654Y-347316D01*
X-1610484Y-348356D01*
X-1609704Y-350176D01*
X-1609509Y-352256D01*
X-1609704Y-354336D01*
X-1610484Y-356156D01*
X-1611654Y-357196D01*
X-1612824Y-357456D01*
G01X-1598239D02*
Y-347056D01*
G01Y-349656D02*
X-1597459Y-348356D01*
X-1596289Y-347316D01*
X-1594729Y-347056D01*
X-1593364Y-347316D01*
X-1592194Y-348356D01*
X-1591609Y-350176D01*
Y-357456D01*
G01X-1559124Y-341856D02*
Y-357456D01*
G01X-1561854Y-347056D02*
X-1556394D01*
G01X-1541224Y-357456D02*
X-1542394Y-357196D01*
X-1543564Y-356156D01*
X-1544344Y-354336D01*
X-1544734Y-352256D01*
X-1544344Y-350176D01*
X-1543564Y-348356D01*
X-1542394Y-347316D01*
X-1541224Y-347056D01*
X-1540054Y-347316D01*
X-1538884Y-348356D01*
X-1538104Y-350176D01*
X-1537909Y-352256D01*
X-1538104Y-354336D01*
X-1538884Y-356156D01*
X-1540054Y-357196D01*
X-1541224Y-357456D01*
G01X-1511274D02*
Y-347056D01*
G01Y-349916D02*
X-1510689Y-348616D01*
X-1509714Y-347576D01*
X-1508349Y-347056D01*
X-1506984Y-347576D01*
X-1506009Y-348616D01*
X-1505424Y-349916D01*
Y-357456D01*
G01Y-349916D02*
X-1504839Y-348616D01*
X-1503864Y-347576D01*
X-1502499Y-347056D01*
X-1501134Y-347576D01*
X-1500159Y-348616D01*
X-1499574Y-350176D01*
Y-357456D01*
G01X-1490839Y-347056D02*
Y-354336D01*
X-1490059Y-356156D01*
X-1488889Y-357196D01*
X-1487524Y-357456D01*
X-1486159Y-357196D01*
X-1484989Y-356156D01*
X-1484209Y-354336D01*
G01Y-357456D02*
Y-347056D01*
G01X-1472549Y-355636D02*
X-1471574Y-356676D01*
X-1470209Y-357456D01*
X-1469039D01*
X-1467869Y-356936D01*
X-1467089Y-356156D01*
X-1466699Y-355116D01*
X-1466894Y-353556D01*
X-1467674Y-352776D01*
X-1471184Y-351216D01*
X-1471964Y-349396D01*
X-1471574Y-348096D01*
X-1470794Y-347316D01*
X-1469624Y-347056D01*
X-1468454Y-347316D01*
X-1467284Y-348096D01*
G01X-1451724Y-341856D02*
Y-357456D01*
G01X-1454454Y-347056D02*
X-1448994D01*
G01X-1419239Y-357456D02*
Y-347056D01*
G01Y-349656D02*
X-1418459Y-348356D01*
X-1417289Y-347316D01*
X-1415729Y-347056D01*
X-1414364Y-347316D01*
X-1413194Y-348356D01*
X-1412609Y-350176D01*
Y-357456D01*
G01X-1398024D02*
X-1399194Y-357196D01*
X-1400364Y-356156D01*
X-1401144Y-354336D01*
X-1401534Y-352256D01*
X-1401144Y-350176D01*
X-1400364Y-348356D01*
X-1399194Y-347316D01*
X-1398024Y-347056D01*
X-1396854Y-347316D01*
X-1395684Y-348356D01*
X-1394904Y-350176D01*
X-1394709Y-352256D01*
X-1394904Y-354336D01*
X-1395684Y-356156D01*
X-1396854Y-357196D01*
X-1398024Y-357456D01*
G01X-1380124Y-341856D02*
Y-357456D01*
G01X-1382854Y-347056D02*
X-1377394D01*
G01X-1341204Y-348356D02*
X-1342569Y-347316D01*
X-1343739Y-347056D01*
X-1345299Y-347576D01*
X-1346469Y-348616D01*
X-1347249Y-350436D01*
X-1347444Y-352256D01*
X-1347249Y-354076D01*
X-1346469Y-355636D01*
X-1345299Y-356936D01*
X-1343739Y-357456D01*
X-1342374Y-356936D01*
X-1341204Y-355896D01*
G01X-1329739Y-347056D02*
Y-354336D01*
X-1328959Y-356156D01*
X-1327789Y-357196D01*
X-1326424Y-357456D01*
X-1325059Y-357196D01*
X-1323889Y-356156D01*
X-1323109Y-354336D01*
G01Y-357456D02*
Y-347056D01*
G01X-1308524Y-341856D02*
Y-357456D01*
G01X-1311254Y-347056D02*
X-1305794D01*
G01X-1272724Y-357456D02*
Y-341856D01*
G01X-1251314Y-357456D02*
Y-347056D01*
G01Y-348876D02*
X-1252094Y-347836D01*
X-1253264Y-347316D01*
X-1254629Y-347056D01*
X-1255994Y-347576D01*
X-1257164Y-348616D01*
X-1257944Y-350176D01*
X-1258334Y-352256D01*
X-1257944Y-354336D01*
X-1257164Y-355896D01*
X-1255994Y-356936D01*
X-1254629Y-357456D01*
X-1253264Y-357196D01*
X-1252094Y-356416D01*
X-1251314Y-355376D01*
G01X-1241019Y-362136D02*
X-1239849Y-362656D01*
X-1238289Y-362136D01*
X-1237314Y-361096D01*
X-1236534Y-359796D01*
X-1235364Y-355636D01*
X-1232829Y-347056D01*
G01X-1239069D02*
X-1235364Y-355636D01*
G01X-1221949Y-350436D02*
X-1215709D01*
X-1216294Y-348616D01*
X-1217269Y-347576D01*
X-1218634Y-347056D01*
X-1219999Y-347316D01*
X-1221169Y-348096D01*
X-1221949Y-349916D01*
X-1222339Y-351476D01*
Y-353036D01*
X-1221949Y-354596D01*
X-1220974Y-356156D01*
X-1219804Y-357196D01*
X-1218439Y-357456D01*
X-1217074Y-356936D01*
X-1215709Y-355376D01*
G01X-1203854Y-357456D02*
Y-347056D01*
G01Y-349136D02*
X-1202879Y-348096D01*
X-1201904Y-347316D01*
X-1200539Y-347056D01*
X-1199564Y-347316D01*
X-1198394Y-348096D01*
G01X-1186149Y-355636D02*
X-1185174Y-356676D01*
X-1183809Y-357456D01*
X-1182639D01*
X-1181469Y-356936D01*
X-1180689Y-356156D01*
X-1180299Y-355116D01*
X-1180494Y-353556D01*
X-1181274Y-352776D01*
X-1184784Y-351216D01*
X-1185564Y-349396D01*
X-1185174Y-348096D01*
X-1184394Y-347316D01*
X-1183224Y-347056D01*
X-1182054Y-347316D01*
X-1180884Y-348096D01*
G01X-1153274Y-357456D02*
Y-347056D01*
G01Y-349916D02*
X-1152689Y-348616D01*
X-1151714Y-347576D01*
X-1150349Y-347056D01*
X-1148984Y-347576D01*
X-1148009Y-348616D01*
X-1147424Y-349916D01*
Y-357456D01*
G01Y-349916D02*
X-1146839Y-348616D01*
X-1145864Y-347576D01*
X-1144499Y-347056D01*
X-1143134Y-347576D01*
X-1142159Y-348616D01*
X-1141574Y-350176D01*
Y-357456D01*
G01X-1132839Y-347056D02*
Y-354336D01*
X-1132059Y-356156D01*
X-1130889Y-357196D01*
X-1129524Y-357456D01*
X-1128159Y-357196D01*
X-1126989Y-356156D01*
X-1126209Y-354336D01*
G01Y-357456D02*
Y-347056D01*
G01X-1114549Y-355636D02*
X-1113574Y-356676D01*
X-1112209Y-357456D01*
X-1111039D01*
X-1109869Y-356936D01*
X-1109089Y-356156D01*
X-1108699Y-355116D01*
X-1108894Y-353556D01*
X-1109674Y-352776D01*
X-1113184Y-351216D01*
X-1113964Y-349396D01*
X-1113574Y-348096D01*
X-1112794Y-347316D01*
X-1111624Y-347056D01*
X-1110454Y-347316D01*
X-1109284Y-348096D01*
G01X-1093724Y-341856D02*
Y-357456D01*
G01X-1096454Y-347056D02*
X-1090994D01*
G01X-1061434Y-357456D02*
Y-341856D01*
G01Y-349656D02*
X-1060459Y-348096D01*
X-1059289Y-347316D01*
X-1058119Y-347056D01*
X-1056364Y-347576D01*
X-1055194Y-348616D01*
X-1054414Y-350436D01*
Y-352516D01*
X-1054804Y-354596D01*
X-1055584Y-356156D01*
X-1056949Y-357196D01*
X-1058119Y-357456D01*
X-1059289Y-357196D01*
X-1060459Y-356416D01*
X-1061434Y-355116D01*
G01X-1042949Y-350436D02*
X-1036709D01*
X-1037294Y-348616D01*
X-1038269Y-347576D01*
X-1039634Y-347056D01*
X-1040999Y-347316D01*
X-1042169Y-348096D01*
X-1042949Y-349916D01*
X-1043339Y-351476D01*
Y-353036D01*
X-1042949Y-354596D01*
X-1041974Y-356156D01*
X-1040804Y-357196D01*
X-1039439Y-357456D01*
X-1038074Y-356936D01*
X-1036709Y-355376D01*
G01X-1010074Y-357456D02*
Y-347056D01*
G01Y-349916D02*
X-1009489Y-348616D01*
X-1008514Y-347576D01*
X-1007149Y-347056D01*
X-1005784Y-347576D01*
X-1004809Y-348616D01*
X-1004224Y-349916D01*
Y-357456D01*
G01Y-349916D02*
X-1003639Y-348616D01*
X-1002664Y-347576D01*
X-1001299Y-347056D01*
X-999934Y-347576D01*
X-998959Y-348616D01*
X-998374Y-350176D01*
Y-357456D01*
G01X-982814D02*
Y-347056D01*
G01Y-348876D02*
X-983594Y-347836D01*
X-984764Y-347316D01*
X-986129Y-347056D01*
X-987494Y-347576D01*
X-988664Y-348616D01*
X-989444Y-350176D01*
X-989834Y-352256D01*
X-989444Y-354336D01*
X-988664Y-355896D01*
X-987494Y-356936D01*
X-986129Y-357456D01*
X-984764Y-357196D01*
X-983594Y-356416D01*
X-982814Y-355376D01*
G01X-968424Y-347056D02*
Y-357456D01*
G01Y-342896D02*
X-968814Y-342636D01*
Y-342116D01*
X-968424Y-341856D01*
X-968034Y-342116D01*
Y-342636D01*
X-968424Y-342896D01*
G01X-953839Y-357456D02*
Y-347056D01*
G01Y-349656D02*
X-953059Y-348356D01*
X-951889Y-347316D01*
X-950329Y-347056D01*
X-948964Y-347316D01*
X-947794Y-348356D01*
X-947209Y-350176D01*
Y-357456D01*
G01X-932624Y-341856D02*
Y-357456D01*
G01X-935354Y-347056D02*
X-929894D01*
G01X-911214Y-357456D02*
Y-347056D01*
G01Y-348876D02*
X-911994Y-347836D01*
X-913164Y-347316D01*
X-914529Y-347056D01*
X-915894Y-347576D01*
X-917064Y-348616D01*
X-917844Y-350176D01*
X-918234Y-352256D01*
X-917844Y-354336D01*
X-917064Y-355896D01*
X-915894Y-356936D01*
X-914529Y-357456D01*
X-913164Y-357196D01*
X-911994Y-356416D01*
X-911214Y-355376D01*
G01X-896824Y-347056D02*
Y-357456D01*
G01Y-342896D02*
X-897214Y-342636D01*
Y-342116D01*
X-896824Y-341856D01*
X-896434Y-342116D01*
Y-342636D01*
X-896824Y-342896D01*
G01X-882239Y-357456D02*
Y-347056D01*
G01Y-349656D02*
X-881459Y-348356D01*
X-880289Y-347316D01*
X-878729Y-347056D01*
X-877364Y-347316D01*
X-876194Y-348356D01*
X-875609Y-350176D01*
Y-357456D01*
G01X-863949Y-350436D02*
X-857709D01*
X-858294Y-348616D01*
X-859269Y-347576D01*
X-860634Y-347056D01*
X-861999Y-347316D01*
X-863169Y-348096D01*
X-863949Y-349916D01*
X-864339Y-351476D01*
Y-353036D01*
X-863949Y-354596D01*
X-862974Y-356156D01*
X-861804Y-357196D01*
X-860439Y-357456D01*
X-859074Y-356936D01*
X-857709Y-355376D01*
G01X-839614Y-341856D02*
Y-357456D01*
G01Y-355116D02*
X-840394Y-356416D01*
X-841564Y-357196D01*
X-842929Y-357456D01*
X-844489Y-356936D01*
X-845659Y-355636D01*
X-846439Y-354076D01*
X-846634Y-352256D01*
X-846439Y-350436D01*
X-845659Y-348876D01*
X-844489Y-347576D01*
X-842929Y-347056D01*
X-841564Y-347316D01*
X-840589Y-347836D01*
X-839614Y-348876D01*
G01X-825224Y-357976D02*
X-825614Y-357716D01*
Y-357196D01*
X-825224Y-356936D01*
X-824834Y-357196D01*
Y-357716D01*
X-825224Y-357976D01*
G01X-2082514Y-323976D02*
X-2073934Y-312536D01*
G01X-2078224Y-310456D02*
Y-326056D01*
G01X-2073934Y-323976D02*
X-2082514Y-312536D01*
G01X-2084074Y-318256D02*
X-2072374D01*
G01X-2064614Y-323976D02*
X-2056034Y-312536D01*
G01X-2060324Y-310456D02*
Y-326056D01*
G01X-2056034Y-323976D02*
X-2064614Y-312536D01*
G01X-2066174Y-318256D02*
X-2054474D01*
G01X-2046909Y-323456D02*
Y-307856D01*
X-2037939Y-323456D01*
Y-307856D01*
G01X-2024524Y-323456D02*
X-2025694Y-323196D01*
X-2026864Y-322156D01*
X-2027644Y-320336D01*
X-2028034Y-318256D01*
X-2027644Y-316176D01*
X-2026864Y-314356D01*
X-2025694Y-313316D01*
X-2024524Y-313056D01*
X-2023354Y-313316D01*
X-2022184Y-314356D01*
X-2021404Y-316176D01*
X-2021209Y-318256D01*
X-2021404Y-320336D01*
X-2022184Y-322156D01*
X-2023354Y-323196D01*
X-2024524Y-323456D01*
G01X-2006624Y-307856D02*
Y-323456D01*
G01X-2009354Y-313056D02*
X-2003894D01*
G01X-1991649Y-316436D02*
X-1985409D01*
X-1985994Y-314616D01*
X-1986969Y-313576D01*
X-1988334Y-313056D01*
X-1989699Y-313316D01*
X-1990869Y-314096D01*
X-1991649Y-315916D01*
X-1992039Y-317476D01*
Y-319036D01*
X-1991649Y-320596D01*
X-1990674Y-322156D01*
X-1989504Y-323196D01*
X-1988139Y-323456D01*
X-1986774Y-322936D01*
X-1985409Y-321376D01*
G01X-1975114Y-323976D02*
X-1966534Y-312536D01*
G01X-1970824Y-310456D02*
Y-326056D01*
G01X-1966534Y-323976D02*
X-1975114Y-312536D01*
G01X-1976674Y-318256D02*
X-1964974D01*
G01X-1933464Y-315136D02*
X-1932684Y-314356D01*
X-1932099Y-313056D01*
X-1931709Y-311236D01*
X-1932099Y-309676D01*
X-1932879Y-308636D01*
X-1934244Y-307856D01*
X-1939509D01*
Y-323456D01*
X-1933074D01*
X-1931709Y-322416D01*
X-1930929Y-320856D01*
X-1930539Y-319036D01*
X-1930929Y-317216D01*
X-1932099Y-315656D01*
X-1933464Y-315136D01*
X-1939509D01*
G01X-1913614Y-323456D02*
Y-313056D01*
G01Y-314876D02*
X-1914394Y-313836D01*
X-1915564Y-313316D01*
X-1916929Y-313056D01*
X-1918294Y-313576D01*
X-1919464Y-314616D01*
X-1920244Y-316176D01*
X-1920634Y-318256D01*
X-1920244Y-320336D01*
X-1919464Y-321896D01*
X-1918294Y-322936D01*
X-1916929Y-323456D01*
X-1915564Y-323196D01*
X-1914394Y-322416D01*
X-1913614Y-321376D01*
G01X-1896104Y-314356D02*
X-1897469Y-313316D01*
X-1898639Y-313056D01*
X-1900199Y-313576D01*
X-1901369Y-314616D01*
X-1902149Y-316436D01*
X-1902344Y-318256D01*
X-1902149Y-320076D01*
X-1901369Y-321636D01*
X-1900199Y-322936D01*
X-1898639Y-323456D01*
X-1897274Y-322936D01*
X-1896104Y-321896D01*
G01X-1884639Y-323456D02*
Y-307856D01*
G01X-1878399Y-313056D02*
X-1884639Y-319036D01*
G01X-1882104Y-316696D02*
X-1878009Y-323456D01*
G01X-1859914Y-307856D02*
Y-323456D01*
G01Y-321116D02*
X-1860694Y-322416D01*
X-1861864Y-323196D01*
X-1863229Y-323456D01*
X-1864789Y-322936D01*
X-1865959Y-321636D01*
X-1866739Y-320076D01*
X-1866934Y-318256D01*
X-1866739Y-316436D01*
X-1865959Y-314876D01*
X-1864789Y-313576D01*
X-1863229Y-313056D01*
X-1861864Y-313316D01*
X-1860889Y-313836D01*
X-1859914Y-314876D01*
G01X-1848254Y-323456D02*
Y-313056D01*
G01Y-315136D02*
X-1847279Y-314096D01*
X-1846304Y-313316D01*
X-1844939Y-313056D01*
X-1843964Y-313316D01*
X-1842794Y-314096D01*
G01X-1827624Y-313056D02*
Y-323456D01*
G01Y-308896D02*
X-1828014Y-308636D01*
Y-308116D01*
X-1827624Y-307856D01*
X-1827234Y-308116D01*
Y-308636D01*
X-1827624Y-308896D01*
G01X-1809724Y-323456D02*
Y-307856D01*
G01X-1791824Y-323456D02*
Y-307856D01*
G01X-1759924D02*
Y-323456D01*
X-1752124D01*
G01X-1741049Y-316436D02*
X-1734809D01*
X-1735394Y-314616D01*
X-1736369Y-313576D01*
X-1737734Y-313056D01*
X-1739099Y-313316D01*
X-1740269Y-314096D01*
X-1741049Y-315916D01*
X-1741439Y-317476D01*
Y-319036D01*
X-1741049Y-320596D01*
X-1740074Y-322156D01*
X-1738904Y-323196D01*
X-1737539Y-323456D01*
X-1736174Y-322936D01*
X-1734809Y-321376D01*
G01X-1722954Y-327356D02*
X-1721589Y-328396D01*
X-1720029Y-328656D01*
X-1718664Y-328396D01*
X-1717494Y-327096D01*
X-1716714Y-325276D01*
Y-313056D01*
G01Y-315136D02*
X-1717494Y-314096D01*
X-1718664Y-313316D01*
X-1720029Y-313056D01*
X-1721589Y-313576D01*
X-1722564Y-314616D01*
X-1723344Y-316436D01*
X-1723734Y-318256D01*
X-1723539Y-319816D01*
X-1722759Y-321636D01*
X-1721589Y-322936D01*
X-1720029Y-323456D01*
X-1718859Y-323196D01*
X-1717494Y-322156D01*
X-1716714Y-321116D01*
G01X-1705249Y-316436D02*
X-1699009D01*
X-1699594Y-314616D01*
X-1700569Y-313576D01*
X-1701934Y-313056D01*
X-1703299Y-313316D01*
X-1704469Y-314096D01*
X-1705249Y-315916D01*
X-1705639Y-317476D01*
Y-319036D01*
X-1705249Y-320596D01*
X-1704274Y-322156D01*
X-1703104Y-323196D01*
X-1701739Y-323456D01*
X-1700374Y-322936D01*
X-1699009Y-321376D01*
G01X-1687739Y-323456D02*
Y-313056D01*
G01Y-315656D02*
X-1686959Y-314356D01*
X-1685789Y-313316D01*
X-1684229Y-313056D01*
X-1682864Y-313316D01*
X-1681694Y-314356D01*
X-1681109Y-316176D01*
Y-323456D01*
G01X-1663014Y-307856D02*
Y-323456D01*
G01Y-321116D02*
X-1663794Y-322416D01*
X-1664964Y-323196D01*
X-1666329Y-323456D01*
X-1667889Y-322936D01*
X-1669059Y-321636D01*
X-1669839Y-320076D01*
X-1670034Y-318256D01*
X-1669839Y-316436D01*
X-1669059Y-314876D01*
X-1667889Y-313576D01*
X-1666329Y-313056D01*
X-1664964Y-313316D01*
X-1663989Y-313836D01*
X-1663014Y-314876D01*
G01X-1630724Y-313056D02*
Y-323456D01*
G01Y-308896D02*
X-1631114Y-308636D01*
Y-308116D01*
X-1630724Y-307856D01*
X-1630334Y-308116D01*
Y-308636D01*
X-1630724Y-308896D01*
G01X-1615749Y-321636D02*
X-1614774Y-322676D01*
X-1613409Y-323456D01*
X-1612239D01*
X-1611069Y-322936D01*
X-1610289Y-322156D01*
X-1609899Y-321116D01*
X-1610094Y-319556D01*
X-1610874Y-318776D01*
X-1614384Y-317216D01*
X-1615164Y-315396D01*
X-1614774Y-314096D01*
X-1613994Y-313316D01*
X-1612824Y-313056D01*
X-1611654Y-313316D01*
X-1610484Y-314096D01*
G01X-1579949Y-321636D02*
X-1578974Y-322676D01*
X-1577609Y-323456D01*
X-1576439D01*
X-1575269Y-322936D01*
X-1574489Y-322156D01*
X-1574099Y-321116D01*
X-1574294Y-319556D01*
X-1575074Y-318776D01*
X-1578584Y-317216D01*
X-1579364Y-315396D01*
X-1578974Y-314096D01*
X-1578194Y-313316D01*
X-1577024Y-313056D01*
X-1575854Y-313316D01*
X-1574684Y-314096D01*
G01X-1563219Y-328136D02*
X-1562049Y-328656D01*
X-1560489Y-328136D01*
X-1559514Y-327096D01*
X-1558734Y-325796D01*
X-1557564Y-321636D01*
X-1555029Y-313056D01*
G01X-1561269D02*
X-1557564Y-321636D01*
G01X-1544149D02*
X-1543174Y-322676D01*
X-1541809Y-323456D01*
X-1540639D01*
X-1539469Y-322936D01*
X-1538689Y-322156D01*
X-1538299Y-321116D01*
X-1538494Y-319556D01*
X-1539274Y-318776D01*
X-1542784Y-317216D01*
X-1543564Y-315396D01*
X-1543174Y-314096D01*
X-1542394Y-313316D01*
X-1541224Y-313056D01*
X-1540054Y-313316D01*
X-1538884Y-314096D01*
G01X-1523324Y-307856D02*
Y-323456D01*
G01X-1526054Y-313056D02*
X-1520594D01*
G01X-1508349Y-316436D02*
X-1502109D01*
X-1502694Y-314616D01*
X-1503669Y-313576D01*
X-1505034Y-313056D01*
X-1506399Y-313316D01*
X-1507569Y-314096D01*
X-1508349Y-315916D01*
X-1508739Y-317476D01*
Y-319036D01*
X-1508349Y-320596D01*
X-1507374Y-322156D01*
X-1506204Y-323196D01*
X-1504839Y-323456D01*
X-1503474Y-322936D01*
X-1502109Y-321376D01*
G01X-1493374Y-323456D02*
Y-313056D01*
G01Y-315916D02*
X-1492789Y-314616D01*
X-1491814Y-313576D01*
X-1490449Y-313056D01*
X-1489084Y-313576D01*
X-1488109Y-314616D01*
X-1487524Y-315916D01*
Y-323456D01*
G01Y-315916D02*
X-1486939Y-314616D01*
X-1485964Y-313576D01*
X-1484599Y-313056D01*
X-1483234Y-313576D01*
X-1482259Y-314616D01*
X-1481674Y-316176D01*
Y-323456D01*
G01X-1454454Y-327356D02*
X-1453089Y-328396D01*
X-1451529Y-328656D01*
X-1450164Y-328396D01*
X-1448994Y-327096D01*
X-1448214Y-325276D01*
Y-313056D01*
G01Y-315136D02*
X-1448994Y-314096D01*
X-1450164Y-313316D01*
X-1451529Y-313056D01*
X-1453089Y-313576D01*
X-1454064Y-314616D01*
X-1454844Y-316436D01*
X-1455234Y-318256D01*
X-1455039Y-319816D01*
X-1454259Y-321636D01*
X-1453089Y-322936D01*
X-1451529Y-323456D01*
X-1450359Y-323196D01*
X-1448994Y-322156D01*
X-1448214Y-321116D01*
G01X-1436749Y-316436D02*
X-1430509D01*
X-1431094Y-314616D01*
X-1432069Y-313576D01*
X-1433434Y-313056D01*
X-1434799Y-313316D01*
X-1435969Y-314096D01*
X-1436749Y-315916D01*
X-1437139Y-317476D01*
Y-319036D01*
X-1436749Y-320596D01*
X-1435774Y-322156D01*
X-1434604Y-323196D01*
X-1433239Y-323456D01*
X-1431874Y-322936D01*
X-1430509Y-321376D01*
G01X-1419239Y-323456D02*
Y-313056D01*
G01Y-315656D02*
X-1418459Y-314356D01*
X-1417289Y-313316D01*
X-1415729Y-313056D01*
X-1414364Y-313316D01*
X-1413194Y-314356D01*
X-1412609Y-316176D01*
Y-323456D01*
G01X-1400949Y-316436D02*
X-1394709D01*
X-1395294Y-314616D01*
X-1396269Y-313576D01*
X-1397634Y-313056D01*
X-1398999Y-313316D01*
X-1400169Y-314096D01*
X-1400949Y-315916D01*
X-1401339Y-317476D01*
Y-319036D01*
X-1400949Y-320596D01*
X-1399974Y-322156D01*
X-1398804Y-323196D01*
X-1397439Y-323456D01*
X-1396074Y-322936D01*
X-1394709Y-321376D01*
G01X-1382854Y-323456D02*
Y-313056D01*
G01Y-315136D02*
X-1381879Y-314096D01*
X-1380904Y-313316D01*
X-1379539Y-313056D01*
X-1378564Y-313316D01*
X-1377394Y-314096D01*
G01X-1358714Y-323456D02*
Y-313056D01*
G01Y-314876D02*
X-1359494Y-313836D01*
X-1360664Y-313316D01*
X-1362029Y-313056D01*
X-1363394Y-313576D01*
X-1364564Y-314616D01*
X-1365344Y-316176D01*
X-1365734Y-318256D01*
X-1365344Y-320336D01*
X-1364564Y-321896D01*
X-1363394Y-322936D01*
X-1362029Y-323456D01*
X-1360664Y-323196D01*
X-1359494Y-322416D01*
X-1358714Y-321376D01*
G01X-1344324Y-307856D02*
Y-323456D01*
G01X-1347054Y-313056D02*
X-1341594D01*
G01X-1329349Y-316436D02*
X-1323109D01*
X-1323694Y-314616D01*
X-1324669Y-313576D01*
X-1326034Y-313056D01*
X-1327399Y-313316D01*
X-1328569Y-314096D01*
X-1329349Y-315916D01*
X-1329739Y-317476D01*
Y-319036D01*
X-1329349Y-320596D01*
X-1328374Y-322156D01*
X-1327204Y-323196D01*
X-1325839Y-323456D01*
X-1324474Y-322936D01*
X-1323109Y-321376D01*
G01X-1305014Y-307856D02*
Y-323456D01*
G01Y-321116D02*
X-1305794Y-322416D01*
X-1306964Y-323196D01*
X-1308329Y-323456D01*
X-1309889Y-322936D01*
X-1311059Y-321636D01*
X-1311839Y-320076D01*
X-1312034Y-318256D01*
X-1311839Y-316436D01*
X-1311059Y-314876D01*
X-1309889Y-313576D01*
X-1308329Y-313056D01*
X-1306964Y-313316D01*
X-1305989Y-313836D01*
X-1305014Y-314876D01*
G01X-1273894Y-323456D02*
Y-310196D01*
X-1273504Y-308896D01*
X-1272724Y-308116D01*
X-1271554Y-307856D01*
X-1270384Y-308376D01*
X-1269799Y-309676D01*
G01X-1272139Y-314096D02*
X-1276039D01*
G01X-1257554Y-323456D02*
Y-313056D01*
G01Y-315136D02*
X-1256579Y-314096D01*
X-1255604Y-313316D01*
X-1254239Y-313056D01*
X-1253264Y-313316D01*
X-1252094Y-314096D01*
G01X-1236924Y-323456D02*
X-1238094Y-323196D01*
X-1239264Y-322156D01*
X-1240044Y-320336D01*
X-1240434Y-318256D01*
X-1240044Y-316176D01*
X-1239264Y-314356D01*
X-1238094Y-313316D01*
X-1236924Y-313056D01*
X-1235754Y-313316D01*
X-1234584Y-314356D01*
X-1233804Y-316176D01*
X-1233609Y-318256D01*
X-1233804Y-320336D01*
X-1234584Y-322156D01*
X-1235754Y-323196D01*
X-1236924Y-323456D01*
G01X-1224874D02*
Y-313056D01*
G01Y-315916D02*
X-1224289Y-314616D01*
X-1223314Y-313576D01*
X-1221949Y-313056D01*
X-1220584Y-313576D01*
X-1219609Y-314616D01*
X-1219024Y-315916D01*
Y-323456D01*
G01Y-315916D02*
X-1218439Y-314616D01*
X-1217464Y-313576D01*
X-1216099Y-313056D01*
X-1214734Y-313576D01*
X-1213759Y-314616D01*
X-1213174Y-316176D01*
Y-323456D01*
G01X-1178934Y-309156D02*
X-1180104Y-308376D01*
X-1181469Y-307856D01*
X-1183029D01*
X-1184784Y-308636D01*
X-1186149Y-309936D01*
X-1187124Y-311496D01*
X-1187904Y-314096D01*
X-1188099Y-316436D01*
X-1187709Y-318776D01*
X-1187124Y-320336D01*
X-1185954Y-321896D01*
X-1184589Y-322936D01*
X-1183224Y-323456D01*
X-1181859D01*
X-1180494Y-322936D01*
X-1179324Y-322156D01*
X-1178349Y-321116D01*
G01X-1161814Y-323456D02*
Y-313056D01*
G01Y-314876D02*
X-1162594Y-313836D01*
X-1163764Y-313316D01*
X-1165129Y-313056D01*
X-1166494Y-313576D01*
X-1167664Y-314616D01*
X-1168444Y-316176D01*
X-1168834Y-318256D01*
X-1168444Y-320336D01*
X-1167664Y-321896D01*
X-1166494Y-322936D01*
X-1165129Y-323456D01*
X-1163764Y-323196D01*
X-1162594Y-322416D01*
X-1161814Y-321376D01*
G01X-1143914Y-307856D02*
Y-323456D01*
G01Y-321116D02*
X-1144694Y-322416D01*
X-1145864Y-323196D01*
X-1147229Y-323456D01*
X-1148789Y-322936D01*
X-1149959Y-321636D01*
X-1150739Y-320076D01*
X-1150934Y-318256D01*
X-1150739Y-316436D01*
X-1149959Y-314876D01*
X-1148789Y-313576D01*
X-1147229Y-313056D01*
X-1145864Y-313316D01*
X-1144889Y-313836D01*
X-1143914Y-314876D01*
G01X-1132449Y-316436D02*
X-1126209D01*
X-1126794Y-314616D01*
X-1127769Y-313576D01*
X-1129134Y-313056D01*
X-1130499Y-313316D01*
X-1131669Y-314096D01*
X-1132449Y-315916D01*
X-1132839Y-317476D01*
Y-319036D01*
X-1132449Y-320596D01*
X-1131474Y-322156D01*
X-1130304Y-323196D01*
X-1128939Y-323456D01*
X-1127574Y-322936D01*
X-1126209Y-321376D01*
G01X-1114939Y-323456D02*
Y-313056D01*
G01Y-315656D02*
X-1114159Y-314356D01*
X-1112989Y-313316D01*
X-1111429Y-313056D01*
X-1110064Y-313316D01*
X-1108894Y-314356D01*
X-1108309Y-316176D01*
Y-323456D01*
G01X-1090604Y-314356D02*
X-1091969Y-313316D01*
X-1093139Y-313056D01*
X-1094699Y-313576D01*
X-1095869Y-314616D01*
X-1096649Y-316436D01*
X-1096844Y-318256D01*
X-1096649Y-320076D01*
X-1095869Y-321636D01*
X-1094699Y-322936D01*
X-1093139Y-323456D01*
X-1091774Y-322936D01*
X-1090604Y-321896D01*
G01X-1078749Y-316436D02*
X-1072509D01*
X-1073094Y-314616D01*
X-1074069Y-313576D01*
X-1075434Y-313056D01*
X-1076799Y-313316D01*
X-1077969Y-314096D01*
X-1078749Y-315916D01*
X-1079139Y-317476D01*
Y-319036D01*
X-1078749Y-320596D01*
X-1077774Y-322156D01*
X-1076604Y-323196D01*
X-1075239Y-323456D01*
X-1073874Y-322936D01*
X-1072509Y-321376D01*
G01X-1040024Y-323456D02*
Y-307856D01*
G01X-1018614Y-323456D02*
Y-313056D01*
G01Y-314876D02*
X-1019394Y-313836D01*
X-1020564Y-313316D01*
X-1021929Y-313056D01*
X-1023294Y-313576D01*
X-1024464Y-314616D01*
X-1025244Y-316176D01*
X-1025634Y-318256D01*
X-1025244Y-320336D01*
X-1024464Y-321896D01*
X-1023294Y-322936D01*
X-1021929Y-323456D01*
X-1020564Y-323196D01*
X-1019394Y-322416D01*
X-1018614Y-321376D01*
G01X-1008319Y-328136D02*
X-1007149Y-328656D01*
X-1005589Y-328136D01*
X-1004614Y-327096D01*
X-1003834Y-325796D01*
X-1002664Y-321636D01*
X-1000129Y-313056D01*
G01X-1006369D02*
X-1002664Y-321636D01*
G01X-986324Y-323456D02*
X-987494Y-323196D01*
X-988664Y-322156D01*
X-989444Y-320336D01*
X-989834Y-318256D01*
X-989444Y-316176D01*
X-988664Y-314356D01*
X-987494Y-313316D01*
X-986324Y-313056D01*
X-985154Y-313316D01*
X-983984Y-314356D01*
X-983204Y-316176D01*
X-983009Y-318256D01*
X-983204Y-320336D01*
X-983984Y-322156D01*
X-985154Y-323196D01*
X-986324Y-323456D01*
G01X-971739Y-313056D02*
Y-320336D01*
X-970959Y-322156D01*
X-969789Y-323196D01*
X-968424Y-323456D01*
X-967059Y-323196D01*
X-965889Y-322156D01*
X-965109Y-320336D01*
G01Y-323456D02*
Y-313056D01*
G01X-950524Y-307856D02*
Y-323456D01*
G01X-953254Y-313056D02*
X-947794D01*
G01X-914724Y-307856D02*
Y-323456D01*
G01X-917454Y-313056D02*
X-911994D01*
G01X-896824Y-323456D02*
X-897994Y-323196D01*
X-899164Y-322156D01*
X-899944Y-320336D01*
X-900334Y-318256D01*
X-899944Y-316176D01*
X-899164Y-314356D01*
X-897994Y-313316D01*
X-896824Y-313056D01*
X-895654Y-313316D01*
X-894484Y-314356D01*
X-893704Y-316176D01*
X-893509Y-318256D01*
X-893704Y-320336D01*
X-894484Y-322156D01*
X-895654Y-323196D01*
X-896824Y-323456D01*
G01X-878924D02*
X-880094Y-323196D01*
X-881264Y-322156D01*
X-882044Y-320336D01*
X-882434Y-318256D01*
X-882044Y-316176D01*
X-881264Y-314356D01*
X-880094Y-313316D01*
X-878924Y-313056D01*
X-877754Y-313316D01*
X-876584Y-314356D01*
X-875804Y-316176D01*
X-875609Y-318256D01*
X-875804Y-320336D01*
X-876584Y-322156D01*
X-877754Y-323196D01*
X-878924Y-323456D01*
G01X-861024D02*
Y-307856D01*
G01X-843124Y-323976D02*
X-843514Y-323716D01*
Y-323196D01*
X-843124Y-322936D01*
X-842734Y-323196D01*
Y-323716D01*
X-843124Y-323976D01*
G01X-2076164Y-222636D02*
X-2075384Y-221856D01*
X-2074799Y-220556D01*
X-2074409Y-218736D01*
X-2074799Y-217176D01*
X-2075579Y-216136D01*
X-2076944Y-215356D01*
X-2082209D01*
Y-230956D01*
X-2075774D01*
X-2074409Y-229916D01*
X-2073629Y-228356D01*
X-2073239Y-226536D01*
X-2073629Y-224716D01*
X-2074799Y-223156D01*
X-2076164Y-222636D01*
X-2082209D01*
G01X-2059824Y-230956D02*
X-2061384Y-230696D01*
X-2062749Y-229656D01*
X-2063919Y-228096D01*
X-2064699Y-226276D01*
X-2065089Y-224196D01*
Y-222116D01*
X-2064699Y-220036D01*
X-2063919Y-218216D01*
X-2062749Y-216656D01*
X-2061384Y-215616D01*
X-2059824Y-215356D01*
X-2058264Y-215616D01*
X-2056899Y-216656D01*
X-2055729Y-218216D01*
X-2054949Y-220036D01*
X-2054559Y-222116D01*
Y-224196D01*
X-2054949Y-226276D01*
X-2055729Y-228096D01*
X-2056899Y-229656D01*
X-2058264Y-230696D01*
X-2059824Y-230956D01*
G01X-2041924Y-215356D02*
Y-230956D01*
G01X-2046409Y-215356D02*
X-2037439D01*
G01X-2010219Y-228876D02*
X-2008659Y-230176D01*
X-2006904Y-230956D01*
X-2005344D01*
X-2003784Y-230176D01*
X-2002614Y-228876D01*
X-2002029Y-227056D01*
X-2002419Y-225236D01*
X-2003394Y-223676D01*
X-2005149Y-222636D01*
X-2007489Y-222116D01*
X-2008854Y-221076D01*
X-2009439Y-219256D01*
X-2009049Y-217436D01*
X-2008074Y-216136D01*
X-2006709Y-215356D01*
X-2005344D01*
X-2003979Y-215876D01*
X-2002809Y-217176D01*
G01X-1990564Y-215356D02*
X-1985884D01*
G01X-1988224D02*
Y-230956D01*
G01X-1990564D02*
X-1985884D01*
G01X-1974614D02*
Y-215356D01*
X-1970714D01*
X-1969154Y-216136D01*
X-1967984Y-217176D01*
X-1967009Y-218736D01*
X-1966229Y-220556D01*
X-1966034Y-223156D01*
X-1966229Y-225756D01*
X-1967009Y-227576D01*
X-1967984Y-229136D01*
X-1969154Y-230176D01*
X-1970714Y-230956D01*
X-1974614D01*
G01X-1948524D02*
X-1956324D01*
Y-215356D01*
X-1948524D01*
G01X-1951644Y-222896D02*
X-1956324D01*
G01X-1934524Y-231476D02*
X-1934914Y-231216D01*
Y-230696D01*
X-1934524Y-230436D01*
X-1934134Y-230696D01*
Y-231216D01*
X-1934524Y-231476D01*
G01Y-224456D02*
X-1934914Y-224196D01*
Y-223676D01*
X-1934524Y-223416D01*
X-1934134Y-223676D01*
Y-224196D01*
X-1934524Y-224456D01*
G01X-1902234Y-230956D02*
Y-215356D01*
G01Y-223156D02*
X-1901259Y-221596D01*
X-1900089Y-220816D01*
X-1898919Y-220556D01*
X-1897164Y-221076D01*
X-1895994Y-222116D01*
X-1895214Y-223936D01*
Y-226016D01*
X-1895604Y-228096D01*
X-1896384Y-229656D01*
X-1897749Y-230696D01*
X-1898919Y-230956D01*
X-1900089Y-230696D01*
X-1901259Y-229916D01*
X-1902234Y-228616D01*
G01X-1877314Y-215356D02*
Y-230956D01*
G01Y-228616D02*
X-1878094Y-229916D01*
X-1879264Y-230696D01*
X-1880629Y-230956D01*
X-1882189Y-230436D01*
X-1883359Y-229136D01*
X-1884139Y-227576D01*
X-1884334Y-225756D01*
X-1884139Y-223936D01*
X-1883359Y-222376D01*
X-1882189Y-221076D01*
X-1880629Y-220556D01*
X-1879264Y-220816D01*
X-1878289Y-221336D01*
X-1877314Y-222376D01*
G01X-1868774Y-236156D02*
X-1857074D01*
G01X-1845024Y-230956D02*
Y-215356D01*
X-1847364Y-218476D01*
G01Y-230956D02*
X-1842684D01*
G01X-1827124Y-215356D02*
X-1828684Y-215876D01*
X-1829854Y-217176D01*
X-1830634Y-218736D01*
X-1831219Y-220816D01*
X-1831414Y-223156D01*
X-1831219Y-225496D01*
X-1830634Y-227576D01*
X-1829854Y-229136D01*
X-1828684Y-230436D01*
X-1827124Y-230956D01*
X-1825564Y-230436D01*
X-1824394Y-229136D01*
X-1823614Y-227576D01*
X-1823029Y-225496D01*
X-1822834Y-223156D01*
X-1823029Y-220816D01*
X-1823614Y-218736D01*
X-1824394Y-217176D01*
X-1825564Y-215876D01*
X-1827124Y-215356D01*
G01X-1811759Y-225756D02*
X-1806689D01*
G01X-1794639Y-229136D02*
X-1793274Y-230436D01*
X-1791714Y-230956D01*
X-1790154Y-230436D01*
X-1788789Y-228876D01*
X-1787814Y-226536D01*
X-1787424Y-224196D01*
Y-221336D01*
X-1787814Y-218996D01*
X-1788789Y-216916D01*
X-1789959Y-215876D01*
X-1791324Y-215356D01*
X-1792884Y-215876D01*
X-1794054Y-216916D01*
X-1794834Y-218476D01*
X-1795224Y-220556D01*
X-1794834Y-222376D01*
X-1793859Y-224196D01*
X-1792689Y-225236D01*
X-1791324Y-225496D01*
X-1789764Y-224976D01*
X-1788594Y-223676D01*
X-1787424Y-221336D01*
G01X-1773814Y-233816D02*
X-1773034Y-230436D01*
G01X-1742694Y-230956D02*
Y-215356D01*
X-1737624Y-228356D01*
X-1732554Y-215356D01*
Y-230956D01*
G01X-1723039Y-220556D02*
Y-227836D01*
X-1722259Y-229656D01*
X-1721089Y-230696D01*
X-1719724Y-230956D01*
X-1718359Y-230696D01*
X-1717189Y-229656D01*
X-1716409Y-227836D01*
G01Y-230956D02*
Y-220556D01*
G01X-1704749Y-229136D02*
X-1703774Y-230176D01*
X-1702409Y-230956D01*
X-1701239D01*
X-1700069Y-230436D01*
X-1699289Y-229656D01*
X-1698899Y-228616D01*
X-1699094Y-227056D01*
X-1699874Y-226276D01*
X-1703384Y-224716D01*
X-1704164Y-222896D01*
X-1703774Y-221596D01*
X-1702994Y-220816D01*
X-1701824Y-220556D01*
X-1700654Y-220816D01*
X-1699484Y-221596D01*
G01X-1683924Y-215356D02*
Y-230956D01*
G01X-1686654Y-220556D02*
X-1681194D01*
G01X-1651439Y-230956D02*
Y-220556D01*
G01Y-223156D02*
X-1650659Y-221856D01*
X-1649489Y-220816D01*
X-1647929Y-220556D01*
X-1646564Y-220816D01*
X-1645394Y-221856D01*
X-1644809Y-223676D01*
Y-230956D01*
G01X-1630224D02*
X-1631394Y-230696D01*
X-1632564Y-229656D01*
X-1633344Y-227836D01*
X-1633734Y-225756D01*
X-1633344Y-223676D01*
X-1632564Y-221856D01*
X-1631394Y-220816D01*
X-1630224Y-220556D01*
X-1629054Y-220816D01*
X-1627884Y-221856D01*
X-1627104Y-223676D01*
X-1626909Y-225756D01*
X-1627104Y-227836D01*
X-1627884Y-229656D01*
X-1629054Y-230696D01*
X-1630224Y-230956D01*
G01X-1612324Y-215356D02*
Y-230956D01*
G01X-1615054Y-220556D02*
X-1609594D01*
G01X-1573404Y-221856D02*
X-1574769Y-220816D01*
X-1575939Y-220556D01*
X-1577499Y-221076D01*
X-1578669Y-222116D01*
X-1579449Y-223936D01*
X-1579644Y-225756D01*
X-1579449Y-227576D01*
X-1578669Y-229136D01*
X-1577499Y-230436D01*
X-1575939Y-230956D01*
X-1574574Y-230436D01*
X-1573404Y-229396D01*
G01X-1561939Y-220556D02*
Y-227836D01*
X-1561159Y-229656D01*
X-1559989Y-230696D01*
X-1558624Y-230956D01*
X-1557259Y-230696D01*
X-1556089Y-229656D01*
X-1555309Y-227836D01*
G01Y-230956D02*
Y-220556D01*
G01X-1540724Y-215356D02*
Y-230956D01*
G01X-1543454Y-220556D02*
X-1537994D01*
G01X-1504924Y-230956D02*
Y-215356D01*
G01X-1483514Y-230956D02*
Y-220556D01*
G01Y-222376D02*
X-1484294Y-221336D01*
X-1485464Y-220816D01*
X-1486829Y-220556D01*
X-1488194Y-221076D01*
X-1489364Y-222116D01*
X-1490144Y-223676D01*
X-1490534Y-225756D01*
X-1490144Y-227836D01*
X-1489364Y-229396D01*
X-1488194Y-230436D01*
X-1486829Y-230956D01*
X-1485464Y-230696D01*
X-1484294Y-229916D01*
X-1483514Y-228876D01*
G01X-1473219Y-235636D02*
X-1472049Y-236156D01*
X-1470489Y-235636D01*
X-1469514Y-234596D01*
X-1468734Y-233296D01*
X-1467564Y-229136D01*
X-1465029Y-220556D01*
G01X-1471269D02*
X-1467564Y-229136D01*
G01X-1454149Y-223936D02*
X-1447909D01*
X-1448494Y-222116D01*
X-1449469Y-221076D01*
X-1450834Y-220556D01*
X-1452199Y-220816D01*
X-1453369Y-221596D01*
X-1454149Y-223416D01*
X-1454539Y-224976D01*
Y-226536D01*
X-1454149Y-228096D01*
X-1453174Y-229656D01*
X-1452004Y-230696D01*
X-1450639Y-230956D01*
X-1449274Y-230436D01*
X-1447909Y-228876D01*
G01X-1436054Y-230956D02*
Y-220556D01*
G01Y-222636D02*
X-1435079Y-221596D01*
X-1434104Y-220816D01*
X-1432739Y-220556D01*
X-1431764Y-220816D01*
X-1430594Y-221596D01*
G01X-1401424Y-215356D02*
Y-230956D01*
X-1393624D01*
G01X-1379624Y-215356D02*
X-1381184Y-215876D01*
X-1382354Y-217176D01*
X-1383134Y-218736D01*
X-1383719Y-220816D01*
X-1383914Y-223156D01*
X-1383719Y-225496D01*
X-1383134Y-227576D01*
X-1382354Y-229136D01*
X-1381184Y-230436D01*
X-1379624Y-230956D01*
X-1378064Y-230436D01*
X-1376894Y-229136D01*
X-1376114Y-227576D01*
X-1375529Y-225496D01*
X-1375334Y-223156D01*
X-1375529Y-220816D01*
X-1376114Y-218736D01*
X-1376894Y-217176D01*
X-1378064Y-215876D01*
X-1379624Y-215356D01*
G01X-1361724Y-230956D02*
X-1360359Y-230696D01*
X-1358799Y-229916D01*
X-1357824Y-228616D01*
X-1357434Y-226796D01*
X-1357824Y-224976D01*
X-1358994Y-223416D01*
X-1360749Y-222636D01*
X-1362699D01*
X-1363869Y-222116D01*
X-1364844Y-220816D01*
X-1365234Y-218996D01*
X-1364649Y-217176D01*
X-1363284Y-215876D01*
X-1361724Y-215356D01*
X-1360164Y-215876D01*
X-1358799Y-217176D01*
X-1358214Y-218996D01*
X-1358604Y-220816D01*
X-1359579Y-222116D01*
X-1360749Y-222636D01*
X-1362699D01*
X-1364454Y-223416D01*
X-1365624Y-224976D01*
X-1366014Y-226796D01*
X-1365624Y-228616D01*
X-1364649Y-229916D01*
X-1363089Y-230696D01*
X-1361724Y-230956D01*
G01X-1326899Y-236156D02*
X-1328849Y-233556D01*
X-1329824Y-230956D01*
Y-220556D01*
X-1328849Y-217956D01*
X-1326899Y-215356D01*
G01X-1312119Y-228876D02*
X-1310559Y-230176D01*
X-1308804Y-230956D01*
X-1307244D01*
X-1305684Y-230176D01*
X-1304514Y-228876D01*
X-1303929Y-227056D01*
X-1304319Y-225236D01*
X-1305294Y-223676D01*
X-1307049Y-222636D01*
X-1309389Y-222116D01*
X-1310754Y-221076D01*
X-1311339Y-219256D01*
X-1310949Y-217436D01*
X-1309974Y-216136D01*
X-1308609Y-215356D01*
X-1307244D01*
X-1305879Y-215876D01*
X-1304709Y-217176D01*
G01X-1290124Y-215356D02*
Y-230956D01*
G01X-1292854Y-220556D02*
X-1287394D01*
G01X-1275539D02*
Y-227836D01*
X-1274759Y-229656D01*
X-1273589Y-230696D01*
X-1272224Y-230956D01*
X-1270859Y-230696D01*
X-1269689Y-229656D01*
X-1268909Y-227836D01*
G01Y-230956D02*
Y-220556D01*
G01X-1257834Y-230956D02*
Y-215356D01*
G01Y-223156D02*
X-1256859Y-221596D01*
X-1255689Y-220816D01*
X-1254519Y-220556D01*
X-1252764Y-221076D01*
X-1251594Y-222116D01*
X-1250814Y-223936D01*
Y-226016D01*
X-1251204Y-228096D01*
X-1251984Y-229656D01*
X-1253349Y-230696D01*
X-1254519Y-230956D01*
X-1255689Y-230696D01*
X-1256859Y-229916D01*
X-1257834Y-228616D01*
G01X-1218524Y-230956D02*
Y-215356D01*
G01X-1203549Y-223936D02*
X-1197309D01*
X-1197894Y-222116D01*
X-1198869Y-221076D01*
X-1200234Y-220556D01*
X-1201599Y-220816D01*
X-1202769Y-221596D01*
X-1203549Y-223416D01*
X-1203939Y-224976D01*
Y-226536D01*
X-1203549Y-228096D01*
X-1202574Y-229656D01*
X-1201404Y-230696D01*
X-1200039Y-230956D01*
X-1198674Y-230436D01*
X-1197309Y-228876D01*
G01X-1186039Y-230956D02*
Y-220556D01*
G01Y-223156D02*
X-1185259Y-221856D01*
X-1184089Y-220816D01*
X-1182529Y-220556D01*
X-1181164Y-220816D01*
X-1179994Y-221856D01*
X-1179409Y-223676D01*
Y-230956D01*
G01X-1167554Y-234856D02*
X-1166189Y-235896D01*
X-1164629Y-236156D01*
X-1163264Y-235896D01*
X-1162094Y-234596D01*
X-1161314Y-232776D01*
Y-220556D01*
G01Y-222636D02*
X-1162094Y-221596D01*
X-1163264Y-220816D01*
X-1164629Y-220556D01*
X-1166189Y-221076D01*
X-1167164Y-222116D01*
X-1167944Y-223936D01*
X-1168334Y-225756D01*
X-1168139Y-227316D01*
X-1167359Y-229136D01*
X-1166189Y-230436D01*
X-1164629Y-230956D01*
X-1163459Y-230696D01*
X-1162094Y-229656D01*
X-1161314Y-228616D01*
G01X-1146924Y-215356D02*
Y-230956D01*
G01X-1149654Y-220556D02*
X-1144194D01*
G01X-1132339Y-230956D02*
Y-215356D01*
G01Y-222896D02*
X-1131364Y-221596D01*
X-1130389Y-220816D01*
X-1128829Y-220556D01*
X-1127659Y-220816D01*
X-1126294Y-221856D01*
X-1125709Y-223416D01*
Y-230956D01*
G01X-1096929Y-224456D02*
X-1095564Y-222636D01*
X-1094394Y-221596D01*
X-1092834Y-221076D01*
X-1091469Y-221596D01*
X-1090494Y-222636D01*
X-1089714Y-224196D01*
X-1089519Y-226016D01*
X-1089714Y-227576D01*
X-1090494Y-229136D01*
X-1091664Y-230436D01*
X-1093029Y-230956D01*
X-1094589Y-230436D01*
X-1095954Y-228876D01*
X-1096734Y-226536D01*
X-1096929Y-223936D01*
X-1096539Y-220556D01*
X-1095954Y-218736D01*
X-1094979Y-216916D01*
X-1093614Y-215616D01*
X-1092249Y-215356D01*
X-1090884Y-215876D01*
X-1089909Y-217176D01*
G01X-1077469Y-225756D02*
X-1072789D01*
G01X-1075324Y-222376D02*
Y-229136D01*
G01X-1060934Y-231476D02*
X-1053914Y-215356D01*
G01X-1042059Y-225756D02*
X-1036989D01*
G01X-1019284Y-230956D02*
Y-215356D01*
X-1026499Y-226536D01*
X-1016749D01*
G01X-991674Y-230956D02*
Y-220556D01*
G01Y-223416D02*
X-991089Y-222116D01*
X-990114Y-221076D01*
X-988749Y-220556D01*
X-987384Y-221076D01*
X-986409Y-222116D01*
X-985824Y-223416D01*
Y-230956D01*
G01Y-223416D02*
X-985239Y-222116D01*
X-984264Y-221076D01*
X-982899Y-220556D01*
X-981534Y-221076D01*
X-980559Y-222116D01*
X-979974Y-223676D01*
Y-230956D01*
G01X-967924Y-220556D02*
Y-230956D01*
G01Y-216396D02*
X-968314Y-216136D01*
Y-215616D01*
X-967924Y-215356D01*
X-967534Y-215616D01*
Y-216136D01*
X-967924Y-216396D01*
G01X-950024Y-230956D02*
Y-215356D01*
G01X-914224D02*
Y-230956D01*
G01X-916954Y-220556D02*
X-911494D01*
G01X-896324Y-230956D02*
X-897494Y-230696D01*
X-898664Y-229656D01*
X-899444Y-227836D01*
X-899834Y-225756D01*
X-899444Y-223676D01*
X-898664Y-221856D01*
X-897494Y-220816D01*
X-896324Y-220556D01*
X-895154Y-220816D01*
X-893984Y-221856D01*
X-893204Y-223676D01*
X-893009Y-225756D01*
X-893204Y-227836D01*
X-893984Y-229656D01*
X-895154Y-230696D01*
X-896324Y-230956D01*
G01X-878424D02*
Y-215356D01*
G01X-863449Y-223936D02*
X-857209D01*
X-857794Y-222116D01*
X-858769Y-221076D01*
X-860134Y-220556D01*
X-861499Y-220816D01*
X-862669Y-221596D01*
X-863449Y-223416D01*
X-863839Y-224976D01*
Y-226536D01*
X-863449Y-228096D01*
X-862474Y-229656D01*
X-861304Y-230696D01*
X-859939Y-230956D01*
X-858574Y-230436D01*
X-857209Y-228876D01*
G01X-845354Y-230956D02*
Y-220556D01*
G01Y-222636D02*
X-844379Y-221596D01*
X-843404Y-220816D01*
X-842039Y-220556D01*
X-841064Y-220816D01*
X-839894Y-221596D01*
G01X-821214Y-230956D02*
Y-220556D01*
G01Y-222376D02*
X-821994Y-221336D01*
X-823164Y-220816D01*
X-824529Y-220556D01*
X-825894Y-221076D01*
X-827064Y-222116D01*
X-827844Y-223676D01*
X-828234Y-225756D01*
X-827844Y-227836D01*
X-827064Y-229396D01*
X-825894Y-230436D01*
X-824529Y-230956D01*
X-823164Y-230696D01*
X-821994Y-229916D01*
X-821214Y-228876D01*
G01X-810139Y-230956D02*
Y-220556D01*
G01Y-223156D02*
X-809359Y-221856D01*
X-808189Y-220816D01*
X-806629Y-220556D01*
X-805264Y-220816D01*
X-804094Y-221856D01*
X-803509Y-223676D01*
Y-230956D01*
G01X-785804Y-221856D02*
X-787169Y-220816D01*
X-788339Y-220556D01*
X-789899Y-221076D01*
X-791069Y-222116D01*
X-791849Y-223936D01*
X-792044Y-225756D01*
X-791849Y-227576D01*
X-791069Y-229136D01*
X-789899Y-230436D01*
X-788339Y-230956D01*
X-786974Y-230436D01*
X-785804Y-229396D01*
G01X-773949Y-223936D02*
X-767709D01*
X-768294Y-222116D01*
X-769269Y-221076D01*
X-770634Y-220556D01*
X-771999Y-220816D01*
X-773169Y-221596D01*
X-773949Y-223416D01*
X-774339Y-224976D01*
Y-226536D01*
X-773949Y-228096D01*
X-772974Y-229656D01*
X-771804Y-230696D01*
X-770439Y-230956D01*
X-769074Y-230436D01*
X-767709Y-228876D01*
G01X-752149Y-236156D02*
X-750199Y-233556D01*
X-749224Y-230956D01*
Y-220556D01*
X-750199Y-217956D01*
X-752149Y-215356D01*
G01X-2074604Y-65856D02*
X-2075969Y-64816D01*
X-2077139Y-64556D01*
X-2078699Y-65076D01*
X-2079869Y-66116D01*
X-2080649Y-67936D01*
X-2080844Y-69756D01*
X-2080649Y-71576D01*
X-2079869Y-73136D01*
X-2078699Y-74436D01*
X-2077139Y-74956D01*
X-2075774Y-74436D01*
X-2074604Y-73396D01*
G01X-2059824Y-75476D02*
X-2060214Y-75216D01*
Y-74696D01*
X-2059824Y-74436D01*
X-2059434Y-74696D01*
Y-75216D01*
X-2059824Y-75476D01*
G01X-2026364Y-59356D02*
X-2021684D01*
G01X-2024024D02*
Y-74956D01*
G01X-2026364D02*
X-2021684D01*
G01X-2002614Y-59356D02*
Y-74956D01*
G01Y-72616D02*
X-2003394Y-73916D01*
X-2004564Y-74696D01*
X-2005929Y-74956D01*
X-2007489Y-74436D01*
X-2008659Y-73136D01*
X-2009439Y-71576D01*
X-2009634Y-69756D01*
X-2009439Y-67936D01*
X-2008659Y-66376D01*
X-2007489Y-65076D01*
X-2005929Y-64556D01*
X-2004564Y-64816D01*
X-2003589Y-65336D01*
X-2002614Y-66376D01*
G01X-1991149Y-67936D02*
X-1984909D01*
X-1985494Y-66116D01*
X-1986469Y-65076D01*
X-1987834Y-64556D01*
X-1989199Y-64816D01*
X-1990369Y-65596D01*
X-1991149Y-67416D01*
X-1991539Y-68976D01*
Y-70536D01*
X-1991149Y-72096D01*
X-1990174Y-73656D01*
X-1989004Y-74696D01*
X-1987639Y-74956D01*
X-1986274Y-74436D01*
X-1984909Y-72876D01*
G01X-1973639Y-74956D02*
Y-64556D01*
G01Y-67156D02*
X-1972859Y-65856D01*
X-1971689Y-64816D01*
X-1970129Y-64556D01*
X-1968764Y-64816D01*
X-1967594Y-65856D01*
X-1967009Y-67676D01*
Y-74956D01*
G01X-1952424Y-59356D02*
Y-74956D01*
G01X-1955154Y-64556D02*
X-1949694D01*
G01X-1934524D02*
Y-74956D01*
G01Y-60396D02*
X-1934914Y-60136D01*
Y-59616D01*
X-1934524Y-59356D01*
X-1934134Y-59616D01*
Y-60136D01*
X-1934524Y-60396D01*
G01X-1917794Y-74956D02*
Y-61696D01*
X-1917404Y-60396D01*
X-1916624Y-59616D01*
X-1915454Y-59356D01*
X-1914284Y-59876D01*
X-1913699Y-61176D01*
G01X-1916039Y-65596D02*
X-1919939D01*
G01X-1898724Y-64556D02*
Y-74956D01*
G01Y-60396D02*
X-1899114Y-60136D01*
Y-59616D01*
X-1898724Y-59356D01*
X-1898334Y-59616D01*
Y-60136D01*
X-1898724Y-60396D01*
G01X-1877704Y-65856D02*
X-1879069Y-64816D01*
X-1880239Y-64556D01*
X-1881799Y-65076D01*
X-1882969Y-66116D01*
X-1883749Y-67936D01*
X-1883944Y-69756D01*
X-1883749Y-71576D01*
X-1882969Y-73136D01*
X-1881799Y-74436D01*
X-1880239Y-74956D01*
X-1878874Y-74436D01*
X-1877704Y-73396D01*
G01X-1859414Y-74956D02*
Y-64556D01*
G01Y-66376D02*
X-1860194Y-65336D01*
X-1861364Y-64816D01*
X-1862729Y-64556D01*
X-1864094Y-65076D01*
X-1865264Y-66116D01*
X-1866044Y-67676D01*
X-1866434Y-69756D01*
X-1866044Y-71836D01*
X-1865264Y-73396D01*
X-1864094Y-74436D01*
X-1862729Y-74956D01*
X-1861364Y-74696D01*
X-1860194Y-73916D01*
X-1859414Y-72876D01*
G01X-1845024Y-59356D02*
Y-74956D01*
G01X-1847754Y-64556D02*
X-1842294D01*
G01X-1827124D02*
Y-74956D01*
G01Y-60396D02*
X-1827514Y-60136D01*
Y-59616D01*
X-1827124Y-59356D01*
X-1826734Y-59616D01*
Y-60136D01*
X-1827124Y-60396D01*
G01X-1809224Y-74956D02*
X-1810394Y-74696D01*
X-1811564Y-73656D01*
X-1812344Y-71836D01*
X-1812734Y-69756D01*
X-1812344Y-67676D01*
X-1811564Y-65856D01*
X-1810394Y-64816D01*
X-1809224Y-64556D01*
X-1808054Y-64816D01*
X-1806884Y-65856D01*
X-1806104Y-67676D01*
X-1805909Y-69756D01*
X-1806104Y-71836D01*
X-1806884Y-73656D01*
X-1808054Y-74696D01*
X-1809224Y-74956D01*
G01X-1794639D02*
Y-64556D01*
G01Y-67156D02*
X-1793859Y-65856D01*
X-1792689Y-64816D01*
X-1791129Y-64556D01*
X-1789764Y-64816D01*
X-1788594Y-65856D01*
X-1788009Y-67676D01*
Y-74956D01*
G01X-1773424Y-75476D02*
X-1773814Y-75216D01*
Y-74696D01*
X-1773424Y-74436D01*
X-1773034Y-74696D01*
Y-75216D01*
X-1773424Y-75476D01*
G01Y-68456D02*
X-1773814Y-68196D01*
Y-67676D01*
X-1773424Y-67416D01*
X-1773034Y-67676D01*
Y-68196D01*
X-1773424Y-68456D01*
G01X-1741524Y-74956D02*
Y-59356D01*
X-1736844D01*
X-1735284Y-60136D01*
X-1734114Y-61956D01*
X-1733724Y-64036D01*
X-1734114Y-66116D01*
X-1735089Y-67676D01*
X-1736844Y-68456D01*
X-1741524D01*
G01X-1715434Y-60656D02*
X-1716604Y-59876D01*
X-1717969Y-59356D01*
X-1719529D01*
X-1721284Y-60136D01*
X-1722649Y-61436D01*
X-1723624Y-62996D01*
X-1724404Y-65596D01*
X-1724599Y-67936D01*
X-1724209Y-70276D01*
X-1723624Y-71836D01*
X-1722454Y-73396D01*
X-1721089Y-74436D01*
X-1719724Y-74956D01*
X-1718359D01*
X-1716994Y-74436D01*
X-1715824Y-73656D01*
X-1714849Y-72616D01*
G01X-1700264Y-66636D02*
X-1699484Y-65856D01*
X-1698899Y-64556D01*
X-1698509Y-62736D01*
X-1698899Y-61176D01*
X-1699679Y-60136D01*
X-1701044Y-59356D01*
X-1706309D01*
Y-74956D01*
X-1699874D01*
X-1698509Y-73916D01*
X-1697729Y-72356D01*
X-1697339Y-70536D01*
X-1697729Y-68716D01*
X-1698899Y-67156D01*
X-1700264Y-66636D01*
X-1706309D01*
G01X-1669534Y-80156D02*
Y-64556D01*
G01Y-66896D02*
X-1668559Y-65596D01*
X-1667584Y-64816D01*
X-1666024Y-64556D01*
X-1664659Y-64816D01*
X-1663294Y-66116D01*
X-1662709Y-67936D01*
X-1662514Y-69756D01*
X-1662709Y-71576D01*
X-1663294Y-73396D01*
X-1664464Y-74436D01*
X-1666024Y-74956D01*
X-1667389Y-74696D01*
X-1668754Y-73916D01*
X-1669534Y-72876D01*
G01X-1644614Y-74956D02*
Y-64556D01*
G01Y-66376D02*
X-1645394Y-65336D01*
X-1646564Y-64816D01*
X-1647929Y-64556D01*
X-1649294Y-65076D01*
X-1650464Y-66116D01*
X-1651244Y-67676D01*
X-1651634Y-69756D01*
X-1651244Y-71836D01*
X-1650464Y-73396D01*
X-1649294Y-74436D01*
X-1647929Y-74956D01*
X-1646564Y-74696D01*
X-1645394Y-73916D01*
X-1644614Y-72876D01*
G01X-1632954Y-74956D02*
Y-64556D01*
G01Y-66636D02*
X-1631979Y-65596D01*
X-1631004Y-64816D01*
X-1629639Y-64556D01*
X-1628664Y-64816D01*
X-1627494Y-65596D01*
G01X-1612324Y-59356D02*
Y-74956D01*
G01X-1615054Y-64556D02*
X-1609594D01*
G01X-1579839Y-74956D02*
Y-64556D01*
G01Y-67156D02*
X-1579059Y-65856D01*
X-1577889Y-64816D01*
X-1576329Y-64556D01*
X-1574964Y-64816D01*
X-1573794Y-65856D01*
X-1573209Y-67676D01*
Y-74956D01*
G01X-1561939Y-64556D02*
Y-71836D01*
X-1561159Y-73656D01*
X-1559989Y-74696D01*
X-1558624Y-74956D01*
X-1557259Y-74696D01*
X-1556089Y-73656D01*
X-1555309Y-71836D01*
G01Y-74956D02*
Y-64556D01*
G01X-1546574Y-74956D02*
Y-64556D01*
G01Y-67416D02*
X-1545989Y-66116D01*
X-1545014Y-65076D01*
X-1543649Y-64556D01*
X-1542284Y-65076D01*
X-1541309Y-66116D01*
X-1540724Y-67416D01*
Y-74956D01*
G01Y-67416D02*
X-1540139Y-66116D01*
X-1539164Y-65076D01*
X-1537799Y-64556D01*
X-1536434Y-65076D01*
X-1535459Y-66116D01*
X-1534874Y-67676D01*
Y-74956D01*
G01X-1526334D02*
Y-59356D01*
G01Y-67156D02*
X-1525359Y-65596D01*
X-1524189Y-64816D01*
X-1523019Y-64556D01*
X-1521264Y-65076D01*
X-1520094Y-66116D01*
X-1519314Y-67936D01*
Y-70016D01*
X-1519704Y-72096D01*
X-1520484Y-73656D01*
X-1521849Y-74696D01*
X-1523019Y-74956D01*
X-1524189Y-74696D01*
X-1525359Y-73916D01*
X-1526334Y-72616D01*
G01X-1507849Y-67936D02*
X-1501609D01*
X-1502194Y-66116D01*
X-1503169Y-65076D01*
X-1504534Y-64556D01*
X-1505899Y-64816D01*
X-1507069Y-65596D01*
X-1507849Y-67416D01*
X-1508239Y-68976D01*
Y-70536D01*
X-1507849Y-72096D01*
X-1506874Y-73656D01*
X-1505704Y-74696D01*
X-1504339Y-74956D01*
X-1502974Y-74436D01*
X-1501609Y-72876D01*
G01X-1489754Y-74956D02*
Y-64556D01*
G01Y-66636D02*
X-1488779Y-65596D01*
X-1487804Y-64816D01*
X-1486439Y-64556D01*
X-1485464Y-64816D01*
X-1484294Y-65596D01*
G01X-1451224Y-59356D02*
Y-74956D01*
G01X-1453954Y-64556D02*
X-1448494D01*
G01X-1433324Y-74956D02*
X-1434494Y-74696D01*
X-1435664Y-73656D01*
X-1436444Y-71836D01*
X-1436834Y-69756D01*
X-1436444Y-67676D01*
X-1435664Y-65856D01*
X-1434494Y-64816D01*
X-1433324Y-64556D01*
X-1432154Y-64816D01*
X-1430984Y-65856D01*
X-1430204Y-67676D01*
X-1430009Y-69756D01*
X-1430204Y-71836D01*
X-1430984Y-73656D01*
X-1432154Y-74696D01*
X-1433324Y-74956D01*
G01X-1401034D02*
Y-59356D01*
G01Y-67156D02*
X-1400059Y-65596D01*
X-1398889Y-64816D01*
X-1397719Y-64556D01*
X-1395964Y-65076D01*
X-1394794Y-66116D01*
X-1394014Y-67936D01*
Y-70016D01*
X-1394404Y-72096D01*
X-1395184Y-73656D01*
X-1396549Y-74696D01*
X-1397719Y-74956D01*
X-1398889Y-74696D01*
X-1400059Y-73916D01*
X-1401034Y-72616D01*
G01X-1382549Y-67936D02*
X-1376309D01*
X-1376894Y-66116D01*
X-1377869Y-65076D01*
X-1379234Y-64556D01*
X-1380599Y-64816D01*
X-1381769Y-65596D01*
X-1382549Y-67416D01*
X-1382939Y-68976D01*
Y-70536D01*
X-1382549Y-72096D01*
X-1381574Y-73656D01*
X-1380404Y-74696D01*
X-1379039Y-74956D01*
X-1377674Y-74436D01*
X-1376309Y-72876D01*
G01X-1346749Y-67936D02*
X-1340509D01*
X-1341094Y-66116D01*
X-1342069Y-65076D01*
X-1343434Y-64556D01*
X-1344799Y-64816D01*
X-1345969Y-65596D01*
X-1346749Y-67416D01*
X-1347139Y-68976D01*
Y-70536D01*
X-1346749Y-72096D01*
X-1345774Y-73656D01*
X-1344604Y-74696D01*
X-1343239Y-74956D01*
X-1341874Y-74436D01*
X-1340509Y-72876D01*
G01X-1325924Y-59356D02*
Y-74956D01*
G01X-1328654Y-64556D02*
X-1323194D01*
G01X-1304904Y-65856D02*
X-1306269Y-64816D01*
X-1307439Y-64556D01*
X-1308999Y-65076D01*
X-1310169Y-66116D01*
X-1310949Y-67936D01*
X-1311144Y-69756D01*
X-1310949Y-71576D01*
X-1310169Y-73136D01*
X-1308999Y-74436D01*
X-1307439Y-74956D01*
X-1306074Y-74436D01*
X-1304904Y-73396D01*
G01X-1293439Y-74956D02*
Y-59356D01*
G01Y-66896D02*
X-1292464Y-65596D01*
X-1291489Y-64816D01*
X-1289929Y-64556D01*
X-1288759Y-64816D01*
X-1287394Y-65856D01*
X-1286809Y-67416D01*
Y-74956D01*
G01X-1275149Y-67936D02*
X-1268909D01*
X-1269494Y-66116D01*
X-1270469Y-65076D01*
X-1271834Y-64556D01*
X-1273199Y-64816D01*
X-1274369Y-65596D01*
X-1275149Y-67416D01*
X-1275539Y-68976D01*
Y-70536D01*
X-1275149Y-72096D01*
X-1274174Y-73656D01*
X-1273004Y-74696D01*
X-1271639Y-74956D01*
X-1270274Y-74436D01*
X-1268909Y-72876D01*
G01X-1250814Y-59356D02*
Y-74956D01*
G01Y-72616D02*
X-1251594Y-73916D01*
X-1252764Y-74696D01*
X-1254129Y-74956D01*
X-1255689Y-74436D01*
X-1256859Y-73136D01*
X-1257639Y-71576D01*
X-1257834Y-69756D01*
X-1257639Y-67936D01*
X-1256859Y-66376D01*
X-1255689Y-65076D01*
X-1254129Y-64556D01*
X-1252764Y-64816D01*
X-1251789Y-65336D01*
X-1250814Y-66376D01*
G01X-1218524Y-74956D02*
X-1219694Y-74696D01*
X-1220864Y-73656D01*
X-1221644Y-71836D01*
X-1222034Y-69756D01*
X-1221644Y-67676D01*
X-1220864Y-65856D01*
X-1219694Y-64816D01*
X-1218524Y-64556D01*
X-1217354Y-64816D01*
X-1216184Y-65856D01*
X-1215404Y-67676D01*
X-1215209Y-69756D01*
X-1215404Y-71836D01*
X-1216184Y-73656D01*
X-1217354Y-74696D01*
X-1218524Y-74956D01*
G01X-1203939D02*
Y-64556D01*
G01Y-67156D02*
X-1203159Y-65856D01*
X-1201989Y-64816D01*
X-1200429Y-64556D01*
X-1199064Y-64816D01*
X-1197894Y-65856D01*
X-1197309Y-67676D01*
Y-74956D01*
G01X-1161704Y-65856D02*
X-1163069Y-64816D01*
X-1164239Y-64556D01*
X-1165799Y-65076D01*
X-1166969Y-66116D01*
X-1167749Y-67936D01*
X-1167944Y-69756D01*
X-1167749Y-71576D01*
X-1166969Y-73136D01*
X-1165799Y-74436D01*
X-1164239Y-74956D01*
X-1162874Y-74436D01*
X-1161704Y-73396D01*
G01X-1146924Y-74956D02*
X-1148094Y-74696D01*
X-1149264Y-73656D01*
X-1150044Y-71836D01*
X-1150434Y-69756D01*
X-1150044Y-67676D01*
X-1149264Y-65856D01*
X-1148094Y-64816D01*
X-1146924Y-64556D01*
X-1145754Y-64816D01*
X-1144584Y-65856D01*
X-1143804Y-67676D01*
X-1143609Y-69756D01*
X-1143804Y-71836D01*
X-1144584Y-73656D01*
X-1145754Y-74696D01*
X-1146924Y-74956D01*
G01X-1134874D02*
Y-64556D01*
G01Y-67416D02*
X-1134289Y-66116D01*
X-1133314Y-65076D01*
X-1131949Y-64556D01*
X-1130584Y-65076D01*
X-1129609Y-66116D01*
X-1129024Y-67416D01*
Y-74956D01*
G01Y-67416D02*
X-1128439Y-66116D01*
X-1127464Y-65076D01*
X-1126099Y-64556D01*
X-1124734Y-65076D01*
X-1123759Y-66116D01*
X-1123174Y-67676D01*
Y-74956D01*
G01X-1114634Y-80156D02*
Y-64556D01*
G01Y-66896D02*
X-1113659Y-65596D01*
X-1112684Y-64816D01*
X-1111124Y-64556D01*
X-1109759Y-64816D01*
X-1108394Y-66116D01*
X-1107809Y-67936D01*
X-1107614Y-69756D01*
X-1107809Y-71576D01*
X-1108394Y-73396D01*
X-1109564Y-74436D01*
X-1111124Y-74956D01*
X-1112489Y-74696D01*
X-1113854Y-73916D01*
X-1114634Y-72876D01*
G01X-1093224Y-74956D02*
X-1094394Y-74696D01*
X-1095564Y-73656D01*
X-1096344Y-71836D01*
X-1096734Y-69756D01*
X-1096344Y-67676D01*
X-1095564Y-65856D01*
X-1094394Y-64816D01*
X-1093224Y-64556D01*
X-1092054Y-64816D01*
X-1090884Y-65856D01*
X-1090104Y-67676D01*
X-1089909Y-69756D01*
X-1090104Y-71836D01*
X-1090884Y-73656D01*
X-1092054Y-74696D01*
X-1093224Y-74956D01*
G01X-1078639D02*
Y-64556D01*
G01Y-67156D02*
X-1077859Y-65856D01*
X-1076689Y-64816D01*
X-1075129Y-64556D01*
X-1073764Y-64816D01*
X-1072594Y-65856D01*
X-1072009Y-67676D01*
Y-74956D01*
G01X-1060349Y-67936D02*
X-1054109D01*
X-1054694Y-66116D01*
X-1055669Y-65076D01*
X-1057034Y-64556D01*
X-1058399Y-64816D01*
X-1059569Y-65596D01*
X-1060349Y-67416D01*
X-1060739Y-68976D01*
Y-70536D01*
X-1060349Y-72096D01*
X-1059374Y-73656D01*
X-1058204Y-74696D01*
X-1056839Y-74956D01*
X-1055474Y-74436D01*
X-1054109Y-72876D01*
G01X-1042839Y-74956D02*
Y-64556D01*
G01Y-67156D02*
X-1042059Y-65856D01*
X-1040889Y-64816D01*
X-1039329Y-64556D01*
X-1037964Y-64816D01*
X-1036794Y-65856D01*
X-1036209Y-67676D01*
Y-74956D01*
G01X-1021624Y-59356D02*
Y-74956D01*
G01X-1024354Y-64556D02*
X-1018894D01*
G01X-988749Y-73136D02*
X-987774Y-74176D01*
X-986409Y-74956D01*
X-985239D01*
X-984069Y-74436D01*
X-983289Y-73656D01*
X-982899Y-72616D01*
X-983094Y-71056D01*
X-983874Y-70276D01*
X-987384Y-68716D01*
X-988164Y-66896D01*
X-987774Y-65596D01*
X-986994Y-64816D01*
X-985824Y-64556D01*
X-984654Y-64816D01*
X-983484Y-65596D01*
G01X-967924Y-64556D02*
Y-74956D01*
G01Y-60396D02*
X-968314Y-60136D01*
Y-59616D01*
X-967924Y-59356D01*
X-967534Y-59616D01*
Y-60136D01*
X-967924Y-60396D01*
G01X-946514Y-59356D02*
Y-74956D01*
G01Y-72616D02*
X-947294Y-73916D01*
X-948464Y-74696D01*
X-949829Y-74956D01*
X-951389Y-74436D01*
X-952559Y-73136D01*
X-953339Y-71576D01*
X-953534Y-69756D01*
X-953339Y-67936D01*
X-952559Y-66376D01*
X-951389Y-65076D01*
X-949829Y-64556D01*
X-948464Y-64816D01*
X-947489Y-65336D01*
X-946514Y-66376D01*
G01X-935049Y-67936D02*
X-928809D01*
X-929394Y-66116D01*
X-930369Y-65076D01*
X-931734Y-64556D01*
X-933099Y-64816D01*
X-934269Y-65596D01*
X-935049Y-67416D01*
X-935439Y-68976D01*
Y-70536D01*
X-935049Y-72096D01*
X-934074Y-73656D01*
X-932904Y-74696D01*
X-931539Y-74956D01*
X-930174Y-74436D01*
X-928809Y-72876D01*
G01X-914224Y-75476D02*
X-914614Y-75216D01*
Y-74696D01*
X-914224Y-74436D01*
X-913834Y-74696D01*
Y-75216D01*
X-914224Y-75476D01*
G01X-2081234Y-6956D02*
Y8644D01*
G01Y844D02*
X-2080259Y2404D01*
X-2079089Y3184D01*
X-2077919Y3444D01*
X-2076164Y2924D01*
X-2074994Y1884D01*
X-2074214Y64D01*
Y-2016D01*
X-2074604Y-4096D01*
X-2075384Y-5656D01*
X-2076749Y-6696D01*
X-2077919Y-6956D01*
X-2079089Y-6696D01*
X-2080259Y-5916D01*
X-2081234Y-4616D01*
G01X-2059824Y-7476D02*
X-2060214Y-7216D01*
Y-6696D01*
X-2059824Y-6436D01*
X-2059434Y-6696D01*
Y-7216D01*
X-2059824Y-7476D01*
G01X-2019734Y7344D02*
X-2020904Y8124D01*
X-2022269Y8644D01*
X-2023829D01*
X-2025584Y7864D01*
X-2026949Y6564D01*
X-2027924Y5004D01*
X-2028704Y2404D01*
X-2028899Y64D01*
X-2028509Y-2276D01*
X-2027924Y-3836D01*
X-2026754Y-5396D01*
X-2025389Y-6436D01*
X-2024024Y-6956D01*
X-2022659D01*
X-2021294Y-6436D01*
X-2020124Y-5656D01*
X-2019149Y-4616D01*
G01X-2006124Y-6956D02*
X-2007294Y-6696D01*
X-2008464Y-5656D01*
X-2009244Y-3836D01*
X-2009634Y-1756D01*
X-2009244Y324D01*
X-2008464Y2144D01*
X-2007294Y3184D01*
X-2006124Y3444D01*
X-2004954Y3184D01*
X-2003784Y2144D01*
X-2003004Y324D01*
X-2002809Y-1756D01*
X-2003004Y-3836D01*
X-2003784Y-5656D01*
X-2004954Y-6696D01*
X-2006124Y-6956D01*
G01X-1994074D02*
Y3444D01*
G01Y584D02*
X-1993489Y1884D01*
X-1992514Y2924D01*
X-1991149Y3444D01*
X-1989784Y2924D01*
X-1988809Y1884D01*
X-1988224Y584D01*
Y-6956D01*
G01Y584D02*
X-1987639Y1884D01*
X-1986664Y2924D01*
X-1985299Y3444D01*
X-1983934Y2924D01*
X-1982959Y1884D01*
X-1982374Y324D01*
Y-6956D01*
G01X-1973834Y-12156D02*
Y3444D01*
G01Y1104D02*
X-1972859Y2404D01*
X-1971884Y3184D01*
X-1970324Y3444D01*
X-1968959Y3184D01*
X-1967594Y1884D01*
X-1967009Y64D01*
X-1966814Y-1756D01*
X-1967009Y-3576D01*
X-1967594Y-5396D01*
X-1968764Y-6436D01*
X-1970324Y-6956D01*
X-1971689Y-6696D01*
X-1973054Y-5916D01*
X-1973834Y-4876D01*
G01X-1952424Y-6956D02*
X-1953594Y-6696D01*
X-1954764Y-5656D01*
X-1955544Y-3836D01*
X-1955934Y-1756D01*
X-1955544Y324D01*
X-1954764Y2144D01*
X-1953594Y3184D01*
X-1952424Y3444D01*
X-1951254Y3184D01*
X-1950084Y2144D01*
X-1949304Y324D01*
X-1949109Y-1756D01*
X-1949304Y-3836D01*
X-1950084Y-5656D01*
X-1951254Y-6696D01*
X-1952424Y-6956D01*
G01X-1937839D02*
Y3444D01*
G01Y844D02*
X-1937059Y2144D01*
X-1935889Y3184D01*
X-1934329Y3444D01*
X-1932964Y3184D01*
X-1931794Y2144D01*
X-1931209Y324D01*
Y-6956D01*
G01X-1919549Y64D02*
X-1913309D01*
X-1913894Y1884D01*
X-1914869Y2924D01*
X-1916234Y3444D01*
X-1917599Y3184D01*
X-1918769Y2404D01*
X-1919549Y584D01*
X-1919939Y-976D01*
Y-2536D01*
X-1919549Y-4096D01*
X-1918574Y-5656D01*
X-1917404Y-6696D01*
X-1916039Y-6956D01*
X-1914674Y-6436D01*
X-1913309Y-4876D01*
G01X-1902039Y-6956D02*
Y3444D01*
G01Y844D02*
X-1901259Y2144D01*
X-1900089Y3184D01*
X-1898529Y3444D01*
X-1897164Y3184D01*
X-1895994Y2144D01*
X-1895409Y324D01*
Y-6956D01*
G01X-1880824Y8644D02*
Y-6956D01*
G01X-1883554Y3444D02*
X-1878094D01*
G01X-1850094Y-6956D02*
Y8644D01*
X-1845024Y-4356D01*
X-1839954Y8644D01*
Y-6956D01*
G01X-1823614D02*
Y3444D01*
G01Y1624D02*
X-1824394Y2664D01*
X-1825564Y3184D01*
X-1826929Y3444D01*
X-1828294Y2924D01*
X-1829464Y1884D01*
X-1830244Y324D01*
X-1830634Y-1756D01*
X-1830244Y-3836D01*
X-1829464Y-5396D01*
X-1828294Y-6436D01*
X-1826929Y-6956D01*
X-1825564Y-6696D01*
X-1824394Y-5916D01*
X-1823614Y-4876D01*
G01X-1811954Y-6956D02*
Y3444D01*
G01Y1364D02*
X-1810979Y2404D01*
X-1810004Y3184D01*
X-1808639Y3444D01*
X-1807664Y3184D01*
X-1806494Y2404D01*
G01X-1794639Y-6956D02*
Y8644D01*
G01X-1788399Y3444D02*
X-1794639Y-2536D01*
G01X-1792104Y-196D02*
X-1788009Y-6956D01*
G01X-1773424Y3444D02*
Y-6956D01*
G01Y7604D02*
X-1773814Y7864D01*
Y8384D01*
X-1773424Y8644D01*
X-1773034Y8384D01*
Y7864D01*
X-1773424Y7604D01*
G01X-1758839Y-6956D02*
Y3444D01*
G01Y844D02*
X-1758059Y2144D01*
X-1756889Y3184D01*
X-1755329Y3444D01*
X-1753964Y3184D01*
X-1752794Y2144D01*
X-1752209Y324D01*
Y-6956D01*
G01X-1740354Y-10856D02*
X-1738989Y-11896D01*
X-1737429Y-12156D01*
X-1736064Y-11896D01*
X-1734894Y-10596D01*
X-1734114Y-8776D01*
Y3444D01*
G01Y1364D02*
X-1734894Y2404D01*
X-1736064Y3184D01*
X-1737429Y3444D01*
X-1738989Y2924D01*
X-1739964Y1884D01*
X-1740744Y64D01*
X-1741134Y-1756D01*
X-1740939Y-3316D01*
X-1740159Y-5136D01*
X-1738989Y-6436D01*
X-1737429Y-6956D01*
X-1736259Y-6696D01*
X-1734894Y-5656D01*
X-1734114Y-4616D01*
G01X-1719724Y-7476D02*
X-1720114Y-7216D01*
Y-6696D01*
X-1719724Y-6436D01*
X-1719334Y-6696D01*
Y-7216D01*
X-1719724Y-7476D01*
G01Y-456D02*
X-1720114Y-196D01*
Y324D01*
X-1719724Y584D01*
X-1719334Y324D01*
Y-196D01*
X-1719724Y-456D01*
G01X-1688019Y-4876D02*
X-1686459Y-6176D01*
X-1684704Y-6956D01*
X-1683144D01*
X-1681584Y-6176D01*
X-1680414Y-4876D01*
X-1679829Y-3056D01*
X-1680219Y-1236D01*
X-1681194Y324D01*
X-1682949Y1364D01*
X-1685289Y1884D01*
X-1686654Y2924D01*
X-1687239Y4744D01*
X-1686849Y6564D01*
X-1685874Y7864D01*
X-1684509Y8644D01*
X-1683144D01*
X-1681779Y8124D01*
X-1680609Y6824D01*
G01X-1666024Y3444D02*
Y-6956D01*
G01Y7604D02*
X-1666414Y7864D01*
Y8384D01*
X-1666024Y8644D01*
X-1665634Y8384D01*
Y7864D01*
X-1666024Y7604D01*
G01X-1648124Y-6956D02*
Y8644D01*
G01X-1633539Y-6956D02*
Y8644D01*
G01X-1627299Y3444D02*
X-1633539Y-2536D01*
G01X-1631004Y-196D02*
X-1626909Y-6956D01*
G01X-1615249Y-5136D02*
X-1614274Y-6176D01*
X-1612909Y-6956D01*
X-1611739D01*
X-1610569Y-6436D01*
X-1609789Y-5656D01*
X-1609399Y-4616D01*
X-1609594Y-3056D01*
X-1610374Y-2276D01*
X-1613884Y-716D01*
X-1614664Y1104D01*
X-1614274Y2404D01*
X-1613494Y3184D01*
X-1612324Y3444D01*
X-1611154Y3184D01*
X-1609984Y2404D01*
G01X-1591304Y2144D02*
X-1592669Y3184D01*
X-1593839Y3444D01*
X-1595399Y2924D01*
X-1596569Y1884D01*
X-1597349Y64D01*
X-1597544Y-1756D01*
X-1597349Y-3576D01*
X-1596569Y-5136D01*
X-1595399Y-6436D01*
X-1593839Y-6956D01*
X-1592474Y-6436D01*
X-1591304Y-5396D01*
G01X-1579254Y-6956D02*
Y3444D01*
G01Y1364D02*
X-1578279Y2404D01*
X-1577304Y3184D01*
X-1575939Y3444D01*
X-1574964Y3184D01*
X-1573794Y2404D01*
G01X-1561549Y64D02*
X-1555309D01*
X-1555894Y1884D01*
X-1556869Y2924D01*
X-1558234Y3444D01*
X-1559599Y3184D01*
X-1560769Y2404D01*
X-1561549Y584D01*
X-1561939Y-976D01*
Y-2536D01*
X-1561549Y-4096D01*
X-1560574Y-5656D01*
X-1559404Y-6696D01*
X-1558039Y-6956D01*
X-1556674Y-6436D01*
X-1555309Y-4876D01*
G01X-1543649Y64D02*
X-1537409D01*
X-1537994Y1884D01*
X-1538969Y2924D01*
X-1540334Y3444D01*
X-1541699Y3184D01*
X-1542869Y2404D01*
X-1543649Y584D01*
X-1544039Y-976D01*
Y-2536D01*
X-1543649Y-4096D01*
X-1542674Y-5656D01*
X-1541504Y-6696D01*
X-1540139Y-6956D01*
X-1538774Y-6436D01*
X-1537409Y-4876D01*
G01X-1526139Y-6956D02*
Y3444D01*
G01Y844D02*
X-1525359Y2144D01*
X-1524189Y3184D01*
X-1522629Y3444D01*
X-1521264Y3184D01*
X-1520094Y2144D01*
X-1519509Y324D01*
Y-6956D01*
G01X-1490534D02*
Y8644D01*
G01Y844D02*
X-1489559Y2404D01*
X-1488389Y3184D01*
X-1487219Y3444D01*
X-1485464Y2924D01*
X-1484294Y1884D01*
X-1483514Y64D01*
Y-2016D01*
X-1483904Y-4096D01*
X-1484684Y-5656D01*
X-1486049Y-6696D01*
X-1487219Y-6956D01*
X-1488389Y-6696D01*
X-1489559Y-5916D01*
X-1490534Y-4616D01*
G01X-1469124Y-6956D02*
X-1470294Y-6696D01*
X-1471464Y-5656D01*
X-1472244Y-3836D01*
X-1472634Y-1756D01*
X-1472244Y324D01*
X-1471464Y2144D01*
X-1470294Y3184D01*
X-1469124Y3444D01*
X-1467954Y3184D01*
X-1466784Y2144D01*
X-1466004Y324D01*
X-1465809Y-1756D01*
X-1466004Y-3836D01*
X-1466784Y-5656D01*
X-1467954Y-6696D01*
X-1469124Y-6956D01*
G01X-1451224Y8644D02*
Y-6956D01*
G01X-1453954Y3444D02*
X-1448494D01*
G01X-1436639Y-6956D02*
Y8644D01*
G01Y1104D02*
X-1435664Y2404D01*
X-1434689Y3184D01*
X-1433129Y3444D01*
X-1431959Y3184D01*
X-1430594Y2144D01*
X-1430009Y584D01*
Y-6956D01*
G01X-1400449Y-5136D02*
X-1399474Y-6176D01*
X-1398109Y-6956D01*
X-1396939D01*
X-1395769Y-6436D01*
X-1394989Y-5656D01*
X-1394599Y-4616D01*
X-1394794Y-3056D01*
X-1395574Y-2276D01*
X-1399084Y-716D01*
X-1399864Y1104D01*
X-1399474Y2404D01*
X-1398694Y3184D01*
X-1397524Y3444D01*
X-1396354Y3184D01*
X-1395184Y2404D01*
G01X-1379624Y3444D02*
Y-6956D01*
G01Y7604D02*
X-1380014Y7864D01*
Y8384D01*
X-1379624Y8644D01*
X-1379234Y8384D01*
Y7864D01*
X-1379624Y7604D01*
G01X-1358214Y8644D02*
Y-6956D01*
G01Y-4616D02*
X-1358994Y-5916D01*
X-1360164Y-6696D01*
X-1361529Y-6956D01*
X-1363089Y-6436D01*
X-1364259Y-5136D01*
X-1365039Y-3576D01*
X-1365234Y-1756D01*
X-1365039Y64D01*
X-1364259Y1624D01*
X-1363089Y2924D01*
X-1361529Y3444D01*
X-1360164Y3184D01*
X-1359189Y2664D01*
X-1358214Y1624D01*
G01X-1346749Y64D02*
X-1340509D01*
X-1341094Y1884D01*
X-1342069Y2924D01*
X-1343434Y3444D01*
X-1344799Y3184D01*
X-1345969Y2404D01*
X-1346749Y584D01*
X-1347139Y-976D01*
Y-2536D01*
X-1346749Y-4096D01*
X-1345774Y-5656D01*
X-1344604Y-6696D01*
X-1343239Y-6956D01*
X-1341874Y-6436D01*
X-1340509Y-4876D01*
G01X-1328849Y-5136D02*
X-1327874Y-6176D01*
X-1326509Y-6956D01*
X-1325339D01*
X-1324169Y-6436D01*
X-1323389Y-5656D01*
X-1322999Y-4616D01*
X-1323194Y-3056D01*
X-1323974Y-2276D01*
X-1327484Y-716D01*
X-1328264Y1104D01*
X-1327874Y2404D01*
X-1327094Y3184D01*
X-1325924Y3444D01*
X-1324754Y3184D01*
X-1323584Y2404D01*
G01X-1294999Y3444D02*
X-1292659Y-6956D01*
X-1290124Y3444D01*
X-1287589Y-6956D01*
X-1285249Y3444D01*
G01X-1272224D02*
Y-6956D01*
G01Y7604D02*
X-1272614Y7864D01*
Y8384D01*
X-1272224Y8644D01*
X-1271834Y8384D01*
Y7864D01*
X-1272224Y7604D01*
G01X-1254324Y8644D02*
Y-6956D01*
G01X-1257054Y3444D02*
X-1251594D01*
G01X-1239739Y-6956D02*
Y8644D01*
G01Y1104D02*
X-1238764Y2404D01*
X-1237789Y3184D01*
X-1236229Y3444D01*
X-1235059Y3184D01*
X-1233694Y2144D01*
X-1233109Y584D01*
Y-6956D01*
G01X-1205499Y3444D02*
X-1203159Y-6956D01*
X-1200624Y3444D01*
X-1198089Y-6956D01*
X-1195749Y3444D01*
G01X-1186039Y-6956D02*
Y8644D01*
G01Y1104D02*
X-1185064Y2404D01*
X-1184089Y3184D01*
X-1182529Y3444D01*
X-1181359Y3184D01*
X-1179994Y2144D01*
X-1179409Y584D01*
Y-6956D01*
G01X-1164824Y3444D02*
Y-6956D01*
G01Y7604D02*
X-1165214Y7864D01*
Y8384D01*
X-1164824Y8644D01*
X-1164434Y8384D01*
Y7864D01*
X-1164824Y7604D01*
G01X-1146924Y8644D02*
Y-6956D01*
G01X-1149654Y3444D02*
X-1144194D01*
G01X-1131949Y64D02*
X-1125709D01*
X-1126294Y1884D01*
X-1127269Y2924D01*
X-1128634Y3444D01*
X-1129999Y3184D01*
X-1131169Y2404D01*
X-1131949Y584D01*
X-1132339Y-976D01*
Y-2536D01*
X-1131949Y-4096D01*
X-1130974Y-5656D01*
X-1129804Y-6696D01*
X-1128439Y-6956D01*
X-1127074Y-6436D01*
X-1125709Y-4876D01*
G01X-1111514Y-9816D02*
X-1110734Y-6436D01*
G01X-1078639Y-6956D02*
Y3444D01*
G01Y844D02*
X-1077859Y2144D01*
X-1076689Y3184D01*
X-1075129Y3444D01*
X-1073764Y3184D01*
X-1072594Y2144D01*
X-1072009Y324D01*
Y-6956D01*
G01X-1057424D02*
X-1058594Y-6696D01*
X-1059764Y-5656D01*
X-1060544Y-3836D01*
X-1060934Y-1756D01*
X-1060544Y324D01*
X-1059764Y2144D01*
X-1058594Y3184D01*
X-1057424Y3444D01*
X-1056254Y3184D01*
X-1055084Y2144D01*
X-1054304Y324D01*
X-1054109Y-1756D01*
X-1054304Y-3836D01*
X-1055084Y-5656D01*
X-1056254Y-6696D01*
X-1057424Y-6956D01*
G01X-1042839D02*
Y3444D01*
G01Y844D02*
X-1042059Y2144D01*
X-1040889Y3184D01*
X-1039329Y3444D01*
X-1037964Y3184D01*
X-1036794Y2144D01*
X-1036209Y324D01*
Y-6956D01*
G01X-1024159Y-1756D02*
X-1019089D01*
G01X-1000604Y2144D02*
X-1001969Y3184D01*
X-1003139Y3444D01*
X-1004699Y2924D01*
X-1005869Y1884D01*
X-1006649Y64D01*
X-1006844Y-1756D01*
X-1006649Y-3576D01*
X-1005869Y-5136D01*
X-1004699Y-6436D01*
X-1003139Y-6956D01*
X-1001774Y-6436D01*
X-1000604Y-5396D01*
G01X-985824Y-6956D02*
X-986994Y-6696D01*
X-988164Y-5656D01*
X-988944Y-3836D01*
X-989334Y-1756D01*
X-988944Y324D01*
X-988164Y2144D01*
X-986994Y3184D01*
X-985824Y3444D01*
X-984654Y3184D01*
X-983484Y2144D01*
X-982704Y324D01*
X-982509Y-1756D01*
X-982704Y-3836D01*
X-983484Y-5656D01*
X-984654Y-6696D01*
X-985824Y-6956D01*
G01X-971239D02*
Y3444D01*
G01Y844D02*
X-970459Y2144D01*
X-969289Y3184D01*
X-967729Y3444D01*
X-966364Y3184D01*
X-965194Y2144D01*
X-964609Y324D01*
Y-6956D01*
G01X-946514Y8644D02*
Y-6956D01*
G01Y-4616D02*
X-947294Y-5916D01*
X-948464Y-6696D01*
X-949829Y-6956D01*
X-951389Y-6436D01*
X-952559Y-5136D01*
X-953339Y-3576D01*
X-953534Y-1756D01*
X-953339Y64D01*
X-952559Y1624D01*
X-951389Y2924D01*
X-949829Y3444D01*
X-948464Y3184D01*
X-947489Y2664D01*
X-946514Y1624D01*
G01X-935439Y3444D02*
Y-3836D01*
X-934659Y-5656D01*
X-933489Y-6696D01*
X-932124Y-6956D01*
X-930759Y-6696D01*
X-929589Y-5656D01*
X-928809Y-3836D01*
G01Y-6956D02*
Y3444D01*
G01X-911104Y2144D02*
X-912469Y3184D01*
X-913639Y3444D01*
X-915199Y2924D01*
X-916369Y1884D01*
X-917149Y64D01*
X-917344Y-1756D01*
X-917149Y-3576D01*
X-916369Y-5136D01*
X-915199Y-6436D01*
X-913639Y-6956D01*
X-912274Y-6436D01*
X-911104Y-5396D01*
G01X-896324Y8644D02*
Y-6956D01*
G01X-899054Y3444D02*
X-893594D01*
G01X-878424D02*
Y-6956D01*
G01Y7604D02*
X-878814Y7864D01*
Y8384D01*
X-878424Y8644D01*
X-878034Y8384D01*
Y7864D01*
X-878424Y7604D01*
G01X-864034Y3444D02*
X-860524Y-6956D01*
X-857014Y3444D01*
G01X-845549Y64D02*
X-839309D01*
X-839894Y1884D01*
X-840869Y2924D01*
X-842234Y3444D01*
X-843599Y3184D01*
X-844769Y2404D01*
X-845549Y584D01*
X-845939Y-976D01*
Y-2536D01*
X-845549Y-4096D01*
X-844574Y-5656D01*
X-843404Y-6696D01*
X-842039Y-6956D01*
X-840674Y-6436D01*
X-839309Y-4876D01*
G01X-809749Y64D02*
X-803509D01*
X-804094Y1884D01*
X-805069Y2924D01*
X-806434Y3444D01*
X-807799Y3184D01*
X-808969Y2404D01*
X-809749Y584D01*
X-810139Y-976D01*
Y-2536D01*
X-809749Y-4096D01*
X-808774Y-5656D01*
X-807604Y-6696D01*
X-806239Y-6956D01*
X-804874Y-6436D01*
X-803509Y-4876D01*
G01X-792434Y-12156D02*
Y3444D01*
G01Y1104D02*
X-791459Y2404D01*
X-790484Y3184D01*
X-788924Y3444D01*
X-787559Y3184D01*
X-786194Y1884D01*
X-785609Y64D01*
X-785414Y-1756D01*
X-785609Y-3576D01*
X-786194Y-5396D01*
X-787364Y-6436D01*
X-788924Y-6956D01*
X-790289Y-6696D01*
X-791654Y-5916D01*
X-792434Y-4876D01*
G01X-771024Y-6956D02*
X-772194Y-6696D01*
X-773364Y-5656D01*
X-774144Y-3836D01*
X-774534Y-1756D01*
X-774144Y324D01*
X-773364Y2144D01*
X-772194Y3184D01*
X-771024Y3444D01*
X-769854Y3184D01*
X-768684Y2144D01*
X-767904Y324D01*
X-767709Y-1756D01*
X-767904Y-3836D01*
X-768684Y-5656D01*
X-769854Y-6696D01*
X-771024Y-6956D01*
G01X-756049Y3444D02*
X-750199Y-6956D01*
G01Y3444D02*
X-756049Y-6956D01*
G01X-739319Y-11636D02*
X-738149Y-12156D01*
X-736589Y-11636D01*
X-735614Y-10596D01*
X-734834Y-9296D01*
X-733664Y-5136D01*
X-731129Y3444D01*
G01X-737369D02*
X-733664Y-5136D01*
G01X-699424Y3444D02*
Y-6956D01*
G01Y7604D02*
X-699814Y7864D01*
Y8384D01*
X-699424Y8644D01*
X-699034Y8384D01*
Y7864D01*
X-699424Y7604D01*
G01X-684839Y-6956D02*
Y3444D01*
G01Y844D02*
X-684059Y2144D01*
X-682889Y3184D01*
X-681329Y3444D01*
X-679964Y3184D01*
X-678794Y2144D01*
X-678209Y324D01*
Y-6956D01*
G01X-666939D02*
Y8644D01*
G01X-660699Y3444D02*
X-666939Y-2536D01*
G01X-664404Y-196D02*
X-660309Y-6956D01*
G01X-645724Y-7476D02*
X-646114Y-7216D01*
Y-6696D01*
X-645724Y-6436D01*
X-645334Y-6696D01*
Y-7216D01*
X-645724Y-7476D01*
G01X-2074214Y95044D02*
Y105444D01*
G01Y103624D02*
X-2074994Y104664D01*
X-2076164Y105184D01*
X-2077529Y105444D01*
X-2078894Y104924D01*
X-2080064Y103884D01*
X-2080844Y102324D01*
X-2081234Y100244D01*
X-2080844Y98164D01*
X-2080064Y96604D01*
X-2078894Y95564D01*
X-2077529Y95044D01*
X-2076164Y95304D01*
X-2074994Y96084D01*
X-2074214Y97124D01*
G01X-2059824Y94524D02*
X-2060214Y94784D01*
Y95304D01*
X-2059824Y95564D01*
X-2059434Y95304D01*
Y94784D01*
X-2059824Y94524D01*
G01X-2028119Y97124D02*
X-2026559Y95824D01*
X-2024804Y95044D01*
X-2023244D01*
X-2021684Y95824D01*
X-2020514Y97124D01*
X-2019929Y98944D01*
X-2020319Y100764D01*
X-2021294Y102324D01*
X-2023049Y103364D01*
X-2025389Y103884D01*
X-2026754Y104924D01*
X-2027339Y106744D01*
X-2026949Y108564D01*
X-2025974Y109864D01*
X-2024609Y110644D01*
X-2023244D01*
X-2021879Y110124D01*
X-2020709Y108824D01*
G01X-2006124Y95044D02*
X-2007294Y95304D01*
X-2008464Y96344D01*
X-2009244Y98164D01*
X-2009634Y100244D01*
X-2009244Y102324D01*
X-2008464Y104144D01*
X-2007294Y105184D01*
X-2006124Y105444D01*
X-2004954Y105184D01*
X-2003784Y104144D01*
X-2003004Y102324D01*
X-2002809Y100244D01*
X-2003004Y98164D01*
X-2003784Y96344D01*
X-2004954Y95304D01*
X-2006124Y95044D01*
G01X-1988224D02*
Y110644D01*
G01X-1966814D02*
Y95044D01*
G01Y97384D02*
X-1967594Y96084D01*
X-1968764Y95304D01*
X-1970129Y95044D01*
X-1971689Y95564D01*
X-1972859Y96864D01*
X-1973639Y98424D01*
X-1973834Y100244D01*
X-1973639Y102064D01*
X-1972859Y103624D01*
X-1971689Y104924D01*
X-1970129Y105444D01*
X-1968764Y105184D01*
X-1967789Y104664D01*
X-1966814Y103624D01*
G01X-1955349Y102064D02*
X-1949109D01*
X-1949694Y103884D01*
X-1950669Y104924D01*
X-1952034Y105444D01*
X-1953399Y105184D01*
X-1954569Y104404D01*
X-1955349Y102584D01*
X-1955739Y101024D01*
Y99464D01*
X-1955349Y97904D01*
X-1954374Y96344D01*
X-1953204Y95304D01*
X-1951839Y95044D01*
X-1950474Y95564D01*
X-1949109Y97124D01*
G01X-1937254Y95044D02*
Y105444D01*
G01Y103364D02*
X-1936279Y104404D01*
X-1935304Y105184D01*
X-1933939Y105444D01*
X-1932964Y105184D01*
X-1931794Y104404D01*
G01X-1922474Y95044D02*
Y105444D01*
G01Y102584D02*
X-1921889Y103884D01*
X-1920914Y104924D01*
X-1919549Y105444D01*
X-1918184Y104924D01*
X-1917209Y103884D01*
X-1916624Y102584D01*
Y95044D01*
G01Y102584D02*
X-1916039Y103884D01*
X-1915064Y104924D01*
X-1913699Y105444D01*
X-1912334Y104924D01*
X-1911359Y103884D01*
X-1910774Y102324D01*
Y95044D01*
G01X-1895214D02*
Y105444D01*
G01Y103624D02*
X-1895994Y104664D01*
X-1897164Y105184D01*
X-1898529Y105444D01*
X-1899894Y104924D01*
X-1901064Y103884D01*
X-1901844Y102324D01*
X-1902234Y100244D01*
X-1901844Y98164D01*
X-1901064Y96604D01*
X-1899894Y95564D01*
X-1898529Y95044D01*
X-1897164Y95304D01*
X-1895994Y96084D01*
X-1895214Y97124D01*
G01X-1883749Y96864D02*
X-1882774Y95824D01*
X-1881409Y95044D01*
X-1880239D01*
X-1879069Y95564D01*
X-1878289Y96344D01*
X-1877899Y97384D01*
X-1878094Y98944D01*
X-1878874Y99724D01*
X-1882384Y101284D01*
X-1883164Y103104D01*
X-1882774Y104404D01*
X-1881994Y105184D01*
X-1880824Y105444D01*
X-1879654Y105184D01*
X-1878484Y104404D01*
G01X-1866239Y95044D02*
Y110644D01*
G01X-1859999Y105444D02*
X-1866239Y99464D01*
G01X-1863704Y101804D02*
X-1859609Y95044D01*
G01X-1845414Y92184D02*
X-1844634Y95564D01*
G01X-1830634Y89844D02*
Y105444D01*
G01Y103104D02*
X-1829659Y104404D01*
X-1828684Y105184D01*
X-1827124Y105444D01*
X-1825759Y105184D01*
X-1824394Y103884D01*
X-1823809Y102064D01*
X-1823614Y100244D01*
X-1823809Y98424D01*
X-1824394Y96604D01*
X-1825564Y95564D01*
X-1827124Y95044D01*
X-1828489Y95304D01*
X-1829854Y96084D01*
X-1830634Y97124D01*
G01X-1812539Y95044D02*
Y110644D01*
G01Y103104D02*
X-1811564Y104404D01*
X-1810589Y105184D01*
X-1809029Y105444D01*
X-1807859Y105184D01*
X-1806494Y104144D01*
X-1805909Y102584D01*
Y95044D01*
G01X-1791324D02*
X-1792494Y95304D01*
X-1793664Y96344D01*
X-1794444Y98164D01*
X-1794834Y100244D01*
X-1794444Y102324D01*
X-1793664Y104144D01*
X-1792494Y105184D01*
X-1791324Y105444D01*
X-1790154Y105184D01*
X-1788984Y104144D01*
X-1788204Y102324D01*
X-1788009Y100244D01*
X-1788204Y98164D01*
X-1788984Y96344D01*
X-1790154Y95304D01*
X-1791324Y95044D01*
G01X-1773424Y110644D02*
Y95044D01*
G01X-1776154Y105444D02*
X-1770694D01*
G01X-1755524Y95044D02*
X-1756694Y95304D01*
X-1757864Y96344D01*
X-1758644Y98164D01*
X-1759034Y100244D01*
X-1758644Y102324D01*
X-1757864Y104144D01*
X-1756694Y105184D01*
X-1755524Y105444D01*
X-1754354Y105184D01*
X-1753184Y104144D01*
X-1752404Y102324D01*
X-1752209Y100244D01*
X-1752404Y98164D01*
X-1753184Y96344D01*
X-1754354Y95304D01*
X-1755524Y95044D01*
G01X-1740159Y100244D02*
X-1735089D01*
G01X-1719724Y105444D02*
Y95044D01*
G01Y109604D02*
X-1720114Y109864D01*
Y110384D01*
X-1719724Y110644D01*
X-1719334Y110384D01*
Y109864D01*
X-1719724Y109604D01*
G01X-1707674Y95044D02*
Y105444D01*
G01Y102584D02*
X-1707089Y103884D01*
X-1706114Y104924D01*
X-1704749Y105444D01*
X-1703384Y104924D01*
X-1702409Y103884D01*
X-1701824Y102584D01*
Y95044D01*
G01Y102584D02*
X-1701239Y103884D01*
X-1700264Y104924D01*
X-1698899Y105444D01*
X-1697534Y104924D01*
X-1696559Y103884D01*
X-1695974Y102324D01*
Y95044D01*
G01X-1680414D02*
Y105444D01*
G01Y103624D02*
X-1681194Y104664D01*
X-1682364Y105184D01*
X-1683729Y105444D01*
X-1685094Y104924D01*
X-1686264Y103884D01*
X-1687044Y102324D01*
X-1687434Y100244D01*
X-1687044Y98164D01*
X-1686264Y96604D01*
X-1685094Y95564D01*
X-1683729Y95044D01*
X-1682364Y95304D01*
X-1681194Y96084D01*
X-1680414Y97124D01*
G01X-1668754Y91144D02*
X-1667389Y90104D01*
X-1665829Y89844D01*
X-1664464Y90104D01*
X-1663294Y91404D01*
X-1662514Y93224D01*
Y105444D01*
G01Y103364D02*
X-1663294Y104404D01*
X-1664464Y105184D01*
X-1665829Y105444D01*
X-1667389Y104924D01*
X-1668364Y103884D01*
X-1669144Y102064D01*
X-1669534Y100244D01*
X-1669339Y98684D01*
X-1668559Y96864D01*
X-1667389Y95564D01*
X-1665829Y95044D01*
X-1664659Y95304D01*
X-1663294Y96344D01*
X-1662514Y97384D01*
G01X-1651049Y102064D02*
X-1644809D01*
X-1645394Y103884D01*
X-1646369Y104924D01*
X-1647734Y105444D01*
X-1649099Y105184D01*
X-1650269Y104404D01*
X-1651049Y102584D01*
X-1651439Y101024D01*
Y99464D01*
X-1651049Y97904D01*
X-1650074Y96344D01*
X-1648904Y95304D01*
X-1647539Y95044D01*
X-1646174Y95564D01*
X-1644809Y97124D01*
G01X-1626714Y110644D02*
Y95044D01*
G01Y97384D02*
X-1627494Y96084D01*
X-1628664Y95304D01*
X-1630029Y95044D01*
X-1631589Y95564D01*
X-1632759Y96864D01*
X-1633539Y98424D01*
X-1633734Y100244D01*
X-1633539Y102064D01*
X-1632759Y103624D01*
X-1631589Y104924D01*
X-1630029Y105444D01*
X-1628664Y105184D01*
X-1627689Y104664D01*
X-1626714Y103624D01*
G01X-1594424Y95044D02*
Y110644D01*
G01X-1576524Y105444D02*
Y95044D01*
G01Y109604D02*
X-1576914Y109864D01*
Y110384D01*
X-1576524Y110644D01*
X-1576134Y110384D01*
Y109864D01*
X-1576524Y109604D01*
G01X-1555114Y89844D02*
Y105444D01*
G01Y103104D02*
X-1556089Y104404D01*
X-1557259Y105184D01*
X-1558624Y105444D01*
X-1559794Y105184D01*
X-1561159Y103884D01*
X-1561939Y102064D01*
X-1562134Y100244D01*
X-1561939Y98424D01*
X-1561159Y96604D01*
X-1559794Y95304D01*
X-1558624Y95044D01*
X-1557259Y95304D01*
X-1556089Y96084D01*
X-1555114Y97384D01*
G01X-1544039Y105444D02*
Y98164D01*
X-1543259Y96344D01*
X-1542089Y95304D01*
X-1540724Y95044D01*
X-1539359Y95304D01*
X-1538189Y96344D01*
X-1537409Y98164D01*
G01Y95044D02*
Y105444D01*
G01X-1522824D02*
Y95044D01*
G01Y109604D02*
X-1523214Y109864D01*
Y110384D01*
X-1522824Y110644D01*
X-1522434Y110384D01*
Y109864D01*
X-1522824Y109604D01*
G01X-1501414Y110644D02*
Y95044D01*
G01Y97384D02*
X-1502194Y96084D01*
X-1503364Y95304D01*
X-1504729Y95044D01*
X-1506289Y95564D01*
X-1507459Y96864D01*
X-1508239Y98424D01*
X-1508434Y100244D01*
X-1508239Y102064D01*
X-1507459Y103624D01*
X-1506289Y104924D01*
X-1504729Y105444D01*
X-1503364Y105184D01*
X-1502389Y104664D01*
X-1501414Y103624D01*
G01X-1472634Y89844D02*
Y105444D01*
G01Y103104D02*
X-1471659Y104404D01*
X-1470684Y105184D01*
X-1469124Y105444D01*
X-1467759Y105184D01*
X-1466394Y103884D01*
X-1465809Y102064D01*
X-1465614Y100244D01*
X-1465809Y98424D01*
X-1466394Y96604D01*
X-1467564Y95564D01*
X-1469124Y95044D01*
X-1470489Y95304D01*
X-1471854Y96084D01*
X-1472634Y97124D01*
G01X-1451224Y95044D02*
X-1452394Y95304D01*
X-1453564Y96344D01*
X-1454344Y98164D01*
X-1454734Y100244D01*
X-1454344Y102324D01*
X-1453564Y104144D01*
X-1452394Y105184D01*
X-1451224Y105444D01*
X-1450054Y105184D01*
X-1448884Y104144D01*
X-1448104Y102324D01*
X-1447909Y100244D01*
X-1448104Y98164D01*
X-1448884Y96344D01*
X-1450054Y95304D01*
X-1451224Y95044D01*
G01X-1433324D02*
Y110644D01*
G01X-1419519Y90364D02*
X-1418349Y89844D01*
X-1416789Y90364D01*
X-1415814Y91404D01*
X-1415034Y92704D01*
X-1413864Y96864D01*
X-1411329Y105444D01*
G01X-1417569D02*
X-1413864Y96864D01*
G01X-1403374Y95044D02*
Y105444D01*
G01Y102584D02*
X-1402789Y103884D01*
X-1401814Y104924D01*
X-1400449Y105444D01*
X-1399084Y104924D01*
X-1398109Y103884D01*
X-1397524Y102584D01*
Y95044D01*
G01Y102584D02*
X-1396939Y103884D01*
X-1395964Y104924D01*
X-1394599Y105444D01*
X-1393234Y104924D01*
X-1392259Y103884D01*
X-1391674Y102324D01*
Y95044D01*
G01X-1382549Y102064D02*
X-1376309D01*
X-1376894Y103884D01*
X-1377869Y104924D01*
X-1379234Y105444D01*
X-1380599Y105184D01*
X-1381769Y104404D01*
X-1382549Y102584D01*
X-1382939Y101024D01*
Y99464D01*
X-1382549Y97904D01*
X-1381574Y96344D01*
X-1380404Y95304D01*
X-1379039Y95044D01*
X-1377674Y95564D01*
X-1376309Y97124D01*
G01X-1364454Y95044D02*
Y105444D01*
G01Y103364D02*
X-1363479Y104404D01*
X-1362504Y105184D01*
X-1361139Y105444D01*
X-1360164Y105184D01*
X-1358994Y104404D01*
G01X-1325924Y95044D02*
X-1327094Y95304D01*
X-1328264Y96344D01*
X-1329044Y98164D01*
X-1329434Y100244D01*
X-1329044Y102324D01*
X-1328264Y104144D01*
X-1327094Y105184D01*
X-1325924Y105444D01*
X-1324754Y105184D01*
X-1323584Y104144D01*
X-1322804Y102324D01*
X-1322609Y100244D01*
X-1322804Y98164D01*
X-1323584Y96344D01*
X-1324754Y95304D01*
X-1325924Y95044D01*
G01X-1311339D02*
Y105444D01*
G01Y102844D02*
X-1310559Y104144D01*
X-1309389Y105184D01*
X-1307829Y105444D01*
X-1306464Y105184D01*
X-1305294Y104144D01*
X-1304709Y102324D01*
Y95044D01*
G01X-1275734D02*
Y110644D01*
G01Y102844D02*
X-1274759Y104404D01*
X-1273589Y105184D01*
X-1272419Y105444D01*
X-1270664Y104924D01*
X-1269494Y103884D01*
X-1268714Y102064D01*
Y99984D01*
X-1269104Y97904D01*
X-1269884Y96344D01*
X-1271249Y95304D01*
X-1272419Y95044D01*
X-1273589Y95304D01*
X-1274759Y96084D01*
X-1275734Y97384D01*
G01X-1254324Y95044D02*
X-1255494Y95304D01*
X-1256664Y96344D01*
X-1257444Y98164D01*
X-1257834Y100244D01*
X-1257444Y102324D01*
X-1256664Y104144D01*
X-1255494Y105184D01*
X-1254324Y105444D01*
X-1253154Y105184D01*
X-1251984Y104144D01*
X-1251204Y102324D01*
X-1251009Y100244D01*
X-1251204Y98164D01*
X-1251984Y96344D01*
X-1253154Y95304D01*
X-1254324Y95044D01*
G01X-1236424Y110644D02*
Y95044D01*
G01X-1239154Y105444D02*
X-1233694D01*
G01X-1221839Y95044D02*
Y110644D01*
G01Y103104D02*
X-1220864Y104404D01*
X-1219889Y105184D01*
X-1218329Y105444D01*
X-1217159Y105184D01*
X-1215794Y104144D01*
X-1215209Y102584D01*
Y95044D01*
G01X-1185649Y96864D02*
X-1184674Y95824D01*
X-1183309Y95044D01*
X-1182139D01*
X-1180969Y95564D01*
X-1180189Y96344D01*
X-1179799Y97384D01*
X-1179994Y98944D01*
X-1180774Y99724D01*
X-1184284Y101284D01*
X-1185064Y103104D01*
X-1184674Y104404D01*
X-1183894Y105184D01*
X-1182724Y105444D01*
X-1181554Y105184D01*
X-1180384Y104404D01*
G01X-1164824Y105444D02*
Y95044D01*
G01Y109604D02*
X-1165214Y109864D01*
Y110384D01*
X-1164824Y110644D01*
X-1164434Y110384D01*
Y109864D01*
X-1164824Y109604D01*
G01X-1143414Y110644D02*
Y95044D01*
G01Y97384D02*
X-1144194Y96084D01*
X-1145364Y95304D01*
X-1146729Y95044D01*
X-1148289Y95564D01*
X-1149459Y96864D01*
X-1150239Y98424D01*
X-1150434Y100244D01*
X-1150239Y102064D01*
X-1149459Y103624D01*
X-1148289Y104924D01*
X-1146729Y105444D01*
X-1145364Y105184D01*
X-1144389Y104664D01*
X-1143414Y103624D01*
G01X-1131949Y102064D02*
X-1125709D01*
X-1126294Y103884D01*
X-1127269Y104924D01*
X-1128634Y105444D01*
X-1129999Y105184D01*
X-1131169Y104404D01*
X-1131949Y102584D01*
X-1132339Y101024D01*
Y99464D01*
X-1131949Y97904D01*
X-1130974Y96344D01*
X-1129804Y95304D01*
X-1128439Y95044D01*
X-1127074Y95564D01*
X-1125709Y97124D01*
G01X-1114049Y96864D02*
X-1113074Y95824D01*
X-1111709Y95044D01*
X-1110539D01*
X-1109369Y95564D01*
X-1108589Y96344D01*
X-1108199Y97384D01*
X-1108394Y98944D01*
X-1109174Y99724D01*
X-1112684Y101284D01*
X-1113464Y103104D01*
X-1113074Y104404D01*
X-1112294Y105184D01*
X-1111124Y105444D01*
X-1109954Y105184D01*
X-1108784Y104404D01*
G01X-1075324Y95044D02*
X-1076494Y95304D01*
X-1077664Y96344D01*
X-1078444Y98164D01*
X-1078834Y100244D01*
X-1078444Y102324D01*
X-1077664Y104144D01*
X-1076494Y105184D01*
X-1075324Y105444D01*
X-1074154Y105184D01*
X-1072984Y104144D01*
X-1072204Y102324D01*
X-1072009Y100244D01*
X-1072204Y98164D01*
X-1072984Y96344D01*
X-1074154Y95304D01*
X-1075324Y95044D01*
G01X-1058594D02*
Y108304D01*
X-1058204Y109604D01*
X-1057424Y110384D01*
X-1056254Y110644D01*
X-1055084Y110124D01*
X-1054499Y108824D01*
G01X-1056839Y104404D02*
X-1060739D01*
G01X-1025134Y95044D02*
Y110644D01*
G01Y102844D02*
X-1024159Y104404D01*
X-1022989Y105184D01*
X-1021819Y105444D01*
X-1020064Y104924D01*
X-1018894Y103884D01*
X-1018114Y102064D01*
Y99984D01*
X-1018504Y97904D01*
X-1019284Y96344D01*
X-1020649Y95304D01*
X-1021819Y95044D01*
X-1022989Y95304D01*
X-1024159Y96084D01*
X-1025134Y97384D01*
G01X-1003724Y95044D02*
X-1004894Y95304D01*
X-1006064Y96344D01*
X-1006844Y98164D01*
X-1007234Y100244D01*
X-1006844Y102324D01*
X-1006064Y104144D01*
X-1004894Y105184D01*
X-1003724Y105444D01*
X-1002554Y105184D01*
X-1001384Y104144D01*
X-1000604Y102324D01*
X-1000409Y100244D01*
X-1000604Y98164D01*
X-1001384Y96344D01*
X-1002554Y95304D01*
X-1003724Y95044D01*
G01X-982314D02*
Y105444D01*
G01Y103624D02*
X-983094Y104664D01*
X-984264Y105184D01*
X-985629Y105444D01*
X-986994Y104924D01*
X-988164Y103884D01*
X-988944Y102324D01*
X-989334Y100244D01*
X-988944Y98164D01*
X-988164Y96604D01*
X-986994Y95564D01*
X-985629Y95044D01*
X-984264Y95304D01*
X-983094Y96084D01*
X-982314Y97124D01*
G01X-970654Y95044D02*
Y105444D01*
G01Y103364D02*
X-969679Y104404D01*
X-968704Y105184D01*
X-967339Y105444D01*
X-966364Y105184D01*
X-965194Y104404D01*
G01X-946514Y110644D02*
Y95044D01*
G01Y97384D02*
X-947294Y96084D01*
X-948464Y95304D01*
X-949829Y95044D01*
X-951389Y95564D01*
X-952559Y96864D01*
X-953339Y98424D01*
X-953534Y100244D01*
X-953339Y102064D01*
X-952559Y103624D01*
X-951389Y104924D01*
X-949829Y105444D01*
X-948464Y105184D01*
X-947489Y104664D01*
X-946514Y103624D01*
G01X-935049Y96864D02*
X-934074Y95824D01*
X-932709Y95044D01*
X-931539D01*
X-930369Y95564D01*
X-929589Y96344D01*
X-929199Y97384D01*
X-929394Y98944D01*
X-930174Y99724D01*
X-933684Y101284D01*
X-934464Y103104D01*
X-934074Y104404D01*
X-933294Y105184D01*
X-932124Y105444D01*
X-930954Y105184D01*
X-929784Y104404D01*
G01X-896324Y105444D02*
Y95044D01*
G01Y109604D02*
X-896714Y109864D01*
Y110384D01*
X-896324Y110644D01*
X-895934Y110384D01*
Y109864D01*
X-896324Y109604D01*
G01X-881739Y95044D02*
Y105444D01*
G01Y102844D02*
X-880959Y104144D01*
X-879789Y105184D01*
X-878229Y105444D01*
X-876864Y105184D01*
X-875694Y104144D01*
X-875109Y102324D01*
Y95044D01*
G01X-839114D02*
Y105444D01*
G01Y103624D02*
X-839894Y104664D01*
X-841064Y105184D01*
X-842429Y105444D01*
X-843794Y104924D01*
X-844964Y103884D01*
X-845744Y102324D01*
X-846134Y100244D01*
X-845744Y98164D01*
X-844964Y96604D01*
X-843794Y95564D01*
X-842429Y95044D01*
X-841064Y95304D01*
X-839894Y96084D01*
X-839114Y97124D01*
G01X-821604Y104144D02*
X-822969Y105184D01*
X-824139Y105444D01*
X-825699Y104924D01*
X-826869Y103884D01*
X-827649Y102064D01*
X-827844Y100244D01*
X-827649Y98424D01*
X-826869Y96864D01*
X-825699Y95564D01*
X-824139Y95044D01*
X-822774Y95564D01*
X-821604Y96604D01*
G01X-803704Y104144D02*
X-805069Y105184D01*
X-806239Y105444D01*
X-807799Y104924D01*
X-808969Y103884D01*
X-809749Y102064D01*
X-809944Y100244D01*
X-809749Y98424D01*
X-808969Y96864D01*
X-807799Y95564D01*
X-806239Y95044D01*
X-804874Y95564D01*
X-803704Y96604D01*
G01X-788924Y95044D02*
X-790094Y95304D01*
X-791264Y96344D01*
X-792044Y98164D01*
X-792434Y100244D01*
X-792044Y102324D01*
X-791264Y104144D01*
X-790094Y105184D01*
X-788924Y105444D01*
X-787754Y105184D01*
X-786584Y104144D01*
X-785804Y102324D01*
X-785609Y100244D01*
X-785804Y98164D01*
X-786584Y96344D01*
X-787754Y95304D01*
X-788924Y95044D01*
G01X-773754D02*
Y105444D01*
G01Y103364D02*
X-772779Y104404D01*
X-771804Y105184D01*
X-770439Y105444D01*
X-769464Y105184D01*
X-768294Y104404D01*
G01X-749614Y110644D02*
Y95044D01*
G01Y97384D02*
X-750394Y96084D01*
X-751564Y95304D01*
X-752929Y95044D01*
X-754489Y95564D01*
X-755659Y96864D01*
X-756439Y98424D01*
X-756634Y100244D01*
X-756439Y102064D01*
X-755659Y103624D01*
X-754489Y104924D01*
X-752929Y105444D01*
X-751564Y105184D01*
X-750589Y104664D01*
X-749614Y103624D01*
G01X-731714Y95044D02*
Y105444D01*
G01Y103624D02*
X-732494Y104664D01*
X-733664Y105184D01*
X-735029Y105444D01*
X-736394Y104924D01*
X-737564Y103884D01*
X-738344Y102324D01*
X-738734Y100244D01*
X-738344Y98164D01*
X-737564Y96604D01*
X-736394Y95564D01*
X-735029Y95044D01*
X-733664Y95304D01*
X-732494Y96084D01*
X-731714Y97124D01*
G01X-720639Y95044D02*
Y105444D01*
G01Y102844D02*
X-719859Y104144D01*
X-718689Y105184D01*
X-717129Y105444D01*
X-715764Y105184D01*
X-714594Y104144D01*
X-714009Y102324D01*
Y95044D01*
G01X-696304Y104144D02*
X-697669Y105184D01*
X-698839Y105444D01*
X-700399Y104924D01*
X-701569Y103884D01*
X-702349Y102064D01*
X-702544Y100244D01*
X-702349Y98424D01*
X-701569Y96864D01*
X-700399Y95564D01*
X-698839Y95044D01*
X-697474Y95564D01*
X-696304Y96604D01*
G01X-684449Y102064D02*
X-678209D01*
X-678794Y103884D01*
X-679769Y104924D01*
X-681134Y105444D01*
X-682499Y105184D01*
X-683669Y104404D01*
X-684449Y102584D01*
X-684839Y101024D01*
Y99464D01*
X-684449Y97904D01*
X-683474Y96344D01*
X-682304Y95304D01*
X-680939Y95044D01*
X-679574Y95564D01*
X-678209Y97124D01*
G01X-2074604Y192144D02*
X-2075969Y193184D01*
X-2077139Y193444D01*
X-2078699Y192924D01*
X-2079869Y191884D01*
X-2080649Y190064D01*
X-2080844Y188244D01*
X-2080649Y186424D01*
X-2079869Y184864D01*
X-2078699Y183564D01*
X-2077139Y183044D01*
X-2075774Y183564D01*
X-2074604Y184604D01*
G01X-2059824Y182524D02*
X-2060214Y182784D01*
Y183304D01*
X-2059824Y183564D01*
X-2059434Y183304D01*
Y182784D01*
X-2059824Y182524D01*
G01X-2028899Y183044D02*
X-2024024Y198644D01*
X-2019149Y183044D01*
G01X-2020904Y188504D02*
X-2027144D01*
G01X-2006124Y183044D02*
Y198644D01*
G01X-1988224Y183044D02*
Y198644D01*
G01X-1955934Y177844D02*
Y193444D01*
G01Y191104D02*
X-1954959Y192404D01*
X-1953984Y193184D01*
X-1952424Y193444D01*
X-1951059Y193184D01*
X-1949694Y191884D01*
X-1949109Y190064D01*
X-1948914Y188244D01*
X-1949109Y186424D01*
X-1949694Y184604D01*
X-1950864Y183564D01*
X-1952424Y183044D01*
X-1953789Y183304D01*
X-1955154Y184084D01*
X-1955934Y185124D01*
G01X-1937254Y183044D02*
Y193444D01*
G01Y191364D02*
X-1936279Y192404D01*
X-1935304Y193184D01*
X-1933939Y193444D01*
X-1932964Y193184D01*
X-1931794Y192404D01*
G01X-1919549Y190064D02*
X-1913309D01*
X-1913894Y191884D01*
X-1914869Y192924D01*
X-1916234Y193444D01*
X-1917599Y193184D01*
X-1918769Y192404D01*
X-1919549Y190584D01*
X-1919939Y189024D01*
Y187464D01*
X-1919549Y185904D01*
X-1918574Y184344D01*
X-1917404Y183304D01*
X-1916039Y183044D01*
X-1914674Y183564D01*
X-1913309Y185124D01*
G01X-1901649Y184864D02*
X-1900674Y183824D01*
X-1899309Y183044D01*
X-1898139D01*
X-1896969Y183564D01*
X-1896189Y184344D01*
X-1895799Y185384D01*
X-1895994Y186944D01*
X-1896774Y187724D01*
X-1900284Y189284D01*
X-1901064Y191104D01*
X-1900674Y192404D01*
X-1899894Y193184D01*
X-1898724Y193444D01*
X-1897554Y193184D01*
X-1896384Y192404D01*
G01X-1883749Y184864D02*
X-1882774Y183824D01*
X-1881409Y183044D01*
X-1880239D01*
X-1879069Y183564D01*
X-1878289Y184344D01*
X-1877899Y185384D01*
X-1878094Y186944D01*
X-1878874Y187724D01*
X-1882384Y189284D01*
X-1883164Y191104D01*
X-1882774Y192404D01*
X-1881994Y193184D01*
X-1880824Y193444D01*
X-1879654Y193184D01*
X-1878484Y192404D01*
G01X-1865459Y188244D02*
X-1860389D01*
G01X-1846194Y183044D02*
Y196304D01*
X-1845804Y197604D01*
X-1845024Y198384D01*
X-1843854Y198644D01*
X-1842684Y198124D01*
X-1842099Y196824D01*
G01X-1844439Y192404D02*
X-1848339D01*
G01X-1827124Y193444D02*
Y183044D01*
G01Y197604D02*
X-1827514Y197864D01*
Y198384D01*
X-1827124Y198644D01*
X-1826734Y198384D01*
Y197864D01*
X-1827124Y197604D01*
G01X-1809224Y198644D02*
Y183044D01*
G01X-1811954Y193444D02*
X-1806494D01*
G01X-1776739Y183044D02*
Y198644D01*
G01Y191104D02*
X-1775764Y192404D01*
X-1774789Y193184D01*
X-1773229Y193444D01*
X-1772059Y193184D01*
X-1770694Y192144D01*
X-1770109Y190584D01*
Y183044D01*
G01X-1755524D02*
X-1756694Y183304D01*
X-1757864Y184344D01*
X-1758644Y186164D01*
X-1759034Y188244D01*
X-1758644Y190324D01*
X-1757864Y192144D01*
X-1756694Y193184D01*
X-1755524Y193444D01*
X-1754354Y193184D01*
X-1753184Y192144D01*
X-1752404Y190324D01*
X-1752209Y188244D01*
X-1752404Y186164D01*
X-1753184Y184344D01*
X-1754354Y183304D01*
X-1755524Y183044D01*
G01X-1737624D02*
Y198644D01*
G01X-1722649Y190064D02*
X-1716409D01*
X-1716994Y191884D01*
X-1717969Y192924D01*
X-1719334Y193444D01*
X-1720699Y193184D01*
X-1721869Y192404D01*
X-1722649Y190584D01*
X-1723039Y189024D01*
Y187464D01*
X-1722649Y185904D01*
X-1721674Y184344D01*
X-1720504Y183304D01*
X-1719139Y183044D01*
X-1717774Y183564D01*
X-1716409Y185124D01*
G01X-1686849Y184864D02*
X-1685874Y183824D01*
X-1684509Y183044D01*
X-1683339D01*
X-1682169Y183564D01*
X-1681389Y184344D01*
X-1680999Y185384D01*
X-1681194Y186944D01*
X-1681974Y187724D01*
X-1685484Y189284D01*
X-1686264Y191104D01*
X-1685874Y192404D01*
X-1685094Y193184D01*
X-1683924Y193444D01*
X-1682754Y193184D01*
X-1681584Y192404D01*
G01X-1666024Y193444D02*
Y183044D01*
G01Y197604D02*
X-1666414Y197864D01*
Y198384D01*
X-1666024Y198644D01*
X-1665634Y198384D01*
Y197864D01*
X-1666024Y197604D01*
G01X-1651049Y193444D02*
X-1645199D01*
X-1651049Y183044D01*
X-1645199D01*
G01X-1633149Y190064D02*
X-1626909D01*
X-1627494Y191884D01*
X-1628469Y192924D01*
X-1629834Y193444D01*
X-1631199Y193184D01*
X-1632369Y192404D01*
X-1633149Y190584D01*
X-1633539Y189024D01*
Y187464D01*
X-1633149Y185904D01*
X-1632174Y184344D01*
X-1631004Y183304D01*
X-1629639Y183044D01*
X-1628274Y183564D01*
X-1626909Y185124D01*
G01X-1599299Y193444D02*
X-1596959Y183044D01*
X-1594424Y193444D01*
X-1591889Y183044D01*
X-1589549Y193444D01*
G01X-1576524D02*
Y183044D01*
G01Y197604D02*
X-1576914Y197864D01*
Y198384D01*
X-1576524Y198644D01*
X-1576134Y198384D01*
Y197864D01*
X-1576524Y197604D01*
G01X-1558624Y198644D02*
Y183044D01*
G01X-1561354Y193444D02*
X-1555894D01*
G01X-1544039Y183044D02*
Y198644D01*
G01Y191104D02*
X-1543064Y192404D01*
X-1542089Y193184D01*
X-1540529Y193444D01*
X-1539359Y193184D01*
X-1537994Y192144D01*
X-1537409Y190584D01*
Y183044D01*
G01X-1507069Y188244D02*
X-1502389D01*
G01X-1504924Y191624D02*
Y184864D01*
G01X-1490534Y182524D02*
X-1483514Y198644D01*
G01X-1471659Y188244D02*
X-1466589D01*
G01X-1454929Y196044D02*
X-1453759Y197604D01*
X-1452394Y198384D01*
X-1450834Y198644D01*
X-1448884Y198124D01*
X-1447519Y196824D01*
X-1447129Y195264D01*
X-1447324Y193704D01*
X-1448104Y192404D01*
X-1452004Y189804D01*
X-1453759Y187984D01*
X-1454929Y185384D01*
X-1455319Y183044D01*
X-1447129D01*
G01X-1439174D02*
Y193444D01*
G01Y190584D02*
X-1438589Y191884D01*
X-1437614Y192924D01*
X-1436249Y193444D01*
X-1434884Y192924D01*
X-1433909Y191884D01*
X-1433324Y190584D01*
Y183044D01*
G01Y190584D02*
X-1432739Y191884D01*
X-1431764Y192924D01*
X-1430399Y193444D01*
X-1429034Y192924D01*
X-1428059Y191884D01*
X-1427474Y190324D01*
Y183044D01*
G01X-1415424Y193444D02*
Y183044D01*
G01Y197604D02*
X-1415814Y197864D01*
Y198384D01*
X-1415424Y198644D01*
X-1415034Y198384D01*
Y197864D01*
X-1415424Y197604D01*
G01X-1397524Y183044D02*
Y198644D01*
G01X-1361724D02*
Y183044D01*
G01X-1364454Y193444D02*
X-1358994D01*
G01X-1343824Y183044D02*
X-1344994Y183304D01*
X-1346164Y184344D01*
X-1346944Y186164D01*
X-1347334Y188244D01*
X-1346944Y190324D01*
X-1346164Y192144D01*
X-1344994Y193184D01*
X-1343824Y193444D01*
X-1342654Y193184D01*
X-1341484Y192144D01*
X-1340704Y190324D01*
X-1340509Y188244D01*
X-1340704Y186164D01*
X-1341484Y184344D01*
X-1342654Y183304D01*
X-1343824Y183044D01*
G01X-1325924D02*
Y198644D01*
G01X-1310949Y190064D02*
X-1304709D01*
X-1305294Y191884D01*
X-1306269Y192924D01*
X-1307634Y193444D01*
X-1308999Y193184D01*
X-1310169Y192404D01*
X-1310949Y190584D01*
X-1311339Y189024D01*
Y187464D01*
X-1310949Y185904D01*
X-1309974Y184344D01*
X-1308804Y183304D01*
X-1307439Y183044D01*
X-1306074Y183564D01*
X-1304709Y185124D01*
G01X-1292854Y183044D02*
Y193444D01*
G01Y191364D02*
X-1291879Y192404D01*
X-1290904Y193184D01*
X-1289539Y193444D01*
X-1288564Y193184D01*
X-1287394Y192404D01*
G01X-1268714Y183044D02*
Y193444D01*
G01Y191624D02*
X-1269494Y192664D01*
X-1270664Y193184D01*
X-1272029Y193444D01*
X-1273394Y192924D01*
X-1274564Y191884D01*
X-1275344Y190324D01*
X-1275734Y188244D01*
X-1275344Y186164D01*
X-1274564Y184604D01*
X-1273394Y183564D01*
X-1272029Y183044D01*
X-1270664Y183304D01*
X-1269494Y184084D01*
X-1268714Y185124D01*
G01X-1257639Y183044D02*
Y193444D01*
G01Y190844D02*
X-1256859Y192144D01*
X-1255689Y193184D01*
X-1254129Y193444D01*
X-1252764Y193184D01*
X-1251594Y192144D01*
X-1251009Y190324D01*
Y183044D01*
G01X-1233304Y192144D02*
X-1234669Y193184D01*
X-1235839Y193444D01*
X-1237399Y192924D01*
X-1238569Y191884D01*
X-1239349Y190064D01*
X-1239544Y188244D01*
X-1239349Y186424D01*
X-1238569Y184864D01*
X-1237399Y183564D01*
X-1235839Y183044D01*
X-1234474Y183564D01*
X-1233304Y184604D01*
G01X-1221449Y190064D02*
X-1215209D01*
X-1215794Y191884D01*
X-1216769Y192924D01*
X-1218134Y193444D01*
X-1219499Y193184D01*
X-1220669Y192404D01*
X-1221449Y190584D01*
X-1221839Y189024D01*
Y187464D01*
X-1221449Y185904D01*
X-1220474Y184344D01*
X-1219304Y183304D01*
X-1217939Y183044D01*
X-1216574Y183564D01*
X-1215209Y185124D01*
G01X-2081234Y251044D02*
Y266644D01*
G01Y258844D02*
X-2080259Y260404D01*
X-2079089Y261184D01*
X-2077919Y261444D01*
X-2076164Y260924D01*
X-2074994Y259884D01*
X-2074214Y258064D01*
Y255984D01*
X-2074604Y253904D01*
X-2075384Y252344D01*
X-2076749Y251304D01*
X-2077919Y251044D01*
X-2079089Y251304D01*
X-2080259Y252084D01*
X-2081234Y253384D01*
G01X-2059824Y250524D02*
X-2060214Y250784D01*
Y251304D01*
X-2059824Y251564D01*
X-2059434Y251304D01*
Y250784D01*
X-2059824Y250524D01*
G01X-2028314Y251044D02*
Y266644D01*
X-2024414D01*
X-2022854Y265864D01*
X-2021684Y264824D01*
X-2020709Y263264D01*
X-2019929Y261444D01*
X-2019734Y258844D01*
X-2019929Y256244D01*
X-2020709Y254424D01*
X-2021684Y252864D01*
X-2022854Y251824D01*
X-2024414Y251044D01*
X-2028314D01*
G01X-2006124Y261444D02*
Y251044D01*
G01Y265604D02*
X-2006514Y265864D01*
Y266384D01*
X-2006124Y266644D01*
X-2005734Y266384D01*
Y265864D01*
X-2006124Y265604D01*
G01X-1984714Y251044D02*
Y261444D01*
G01Y259624D02*
X-1985494Y260664D01*
X-1986664Y261184D01*
X-1988029Y261444D01*
X-1989394Y260924D01*
X-1990564Y259884D01*
X-1991344Y258324D01*
X-1991734Y256244D01*
X-1991344Y254164D01*
X-1990564Y252604D01*
X-1989394Y251564D01*
X-1988029Y251044D01*
X-1986664Y251304D01*
X-1985494Y252084D01*
X-1984714Y253124D01*
G01X-1976174Y251044D02*
Y261444D01*
G01Y258584D02*
X-1975589Y259884D01*
X-1974614Y260924D01*
X-1973249Y261444D01*
X-1971884Y260924D01*
X-1970909Y259884D01*
X-1970324Y258584D01*
Y251044D01*
G01Y258584D02*
X-1969739Y259884D01*
X-1968764Y260924D01*
X-1967399Y261444D01*
X-1966034Y260924D01*
X-1965059Y259884D01*
X-1964474Y258324D01*
Y251044D01*
G01X-1955349Y258064D02*
X-1949109D01*
X-1949694Y259884D01*
X-1950669Y260924D01*
X-1952034Y261444D01*
X-1953399Y261184D01*
X-1954569Y260404D01*
X-1955349Y258584D01*
X-1955739Y257024D01*
Y255464D01*
X-1955349Y253904D01*
X-1954374Y252344D01*
X-1953204Y251304D01*
X-1951839Y251044D01*
X-1950474Y251564D01*
X-1949109Y253124D01*
G01X-1934524Y266644D02*
Y251044D01*
G01X-1937254Y261444D02*
X-1931794D01*
G01X-1919549Y258064D02*
X-1913309D01*
X-1913894Y259884D01*
X-1914869Y260924D01*
X-1916234Y261444D01*
X-1917599Y261184D01*
X-1918769Y260404D01*
X-1919549Y258584D01*
X-1919939Y257024D01*
Y255464D01*
X-1919549Y253904D01*
X-1918574Y252344D01*
X-1917404Y251304D01*
X-1916039Y251044D01*
X-1914674Y251564D01*
X-1913309Y253124D01*
G01X-1901454Y251044D02*
Y261444D01*
G01Y259364D02*
X-1900479Y260404D01*
X-1899504Y261184D01*
X-1898139Y261444D01*
X-1897164Y261184D01*
X-1895994Y260404D01*
G01X-1883749Y252864D02*
X-1882774Y251824D01*
X-1881409Y251044D01*
X-1880239D01*
X-1879069Y251564D01*
X-1878289Y252344D01*
X-1877899Y253384D01*
X-1878094Y254944D01*
X-1878874Y255724D01*
X-1882384Y257284D01*
X-1883164Y259104D01*
X-1882774Y260404D01*
X-1881994Y261184D01*
X-1880824Y261444D01*
X-1879654Y261184D01*
X-1878484Y260404D01*
G01X-1845024Y261444D02*
Y251044D01*
G01Y265604D02*
X-1845414Y265864D01*
Y266384D01*
X-1845024Y266644D01*
X-1844634Y266384D01*
Y265864D01*
X-1845024Y265604D01*
G01X-1830439Y251044D02*
Y261444D01*
G01Y258844D02*
X-1829659Y260144D01*
X-1828489Y261184D01*
X-1826929Y261444D01*
X-1825564Y261184D01*
X-1824394Y260144D01*
X-1823809Y258324D01*
Y251044D01*
G01X-1791324Y266644D02*
Y251044D01*
G01X-1794054Y261444D02*
X-1788594D01*
G01X-1776739Y251044D02*
Y266644D01*
G01Y259104D02*
X-1775764Y260404D01*
X-1774789Y261184D01*
X-1773229Y261444D01*
X-1772059Y261184D01*
X-1770694Y260144D01*
X-1770109Y258584D01*
Y251044D01*
G01X-1758449Y258064D02*
X-1752209D01*
X-1752794Y259884D01*
X-1753769Y260924D01*
X-1755134Y261444D01*
X-1756499Y261184D01*
X-1757669Y260404D01*
X-1758449Y258584D01*
X-1758839Y257024D01*
Y255464D01*
X-1758449Y253904D01*
X-1757474Y252344D01*
X-1756304Y251304D01*
X-1754939Y251044D01*
X-1753574Y251564D01*
X-1752209Y253124D01*
G01X-1716214Y266644D02*
Y251044D01*
G01Y253384D02*
X-1716994Y252084D01*
X-1718164Y251304D01*
X-1719529Y251044D01*
X-1721089Y251564D01*
X-1722259Y252864D01*
X-1723039Y254424D01*
X-1723234Y256244D01*
X-1723039Y258064D01*
X-1722259Y259624D01*
X-1721089Y260924D01*
X-1719529Y261444D01*
X-1718164Y261184D01*
X-1717189Y260664D01*
X-1716214Y259624D01*
G01X-1704554Y251044D02*
Y261444D01*
G01Y259364D02*
X-1703579Y260404D01*
X-1702604Y261184D01*
X-1701239Y261444D01*
X-1700264Y261184D01*
X-1699094Y260404D01*
G01X-1683924Y261444D02*
Y251044D01*
G01Y265604D02*
X-1684314Y265864D01*
Y266384D01*
X-1683924Y266644D01*
X-1683534Y266384D01*
Y265864D01*
X-1683924Y265604D01*
G01X-1666024Y251044D02*
Y266644D01*
G01X-1648124Y251044D02*
Y266644D01*
G01X-1612324D02*
Y251044D01*
G01X-1615054Y261444D02*
X-1609594D01*
G01X-1590914Y251044D02*
Y261444D01*
G01Y259624D02*
X-1591694Y260664D01*
X-1592864Y261184D01*
X-1594229Y261444D01*
X-1595594Y260924D01*
X-1596764Y259884D01*
X-1597544Y258324D01*
X-1597934Y256244D01*
X-1597544Y254164D01*
X-1596764Y252604D01*
X-1595594Y251564D01*
X-1594229Y251044D01*
X-1592864Y251304D01*
X-1591694Y252084D01*
X-1590914Y253124D01*
G01X-1580034Y251044D02*
Y266644D01*
G01Y258844D02*
X-1579059Y260404D01*
X-1577889Y261184D01*
X-1576719Y261444D01*
X-1574964Y260924D01*
X-1573794Y259884D01*
X-1573014Y258064D01*
Y255984D01*
X-1573404Y253904D01*
X-1574184Y252344D01*
X-1575549Y251304D01*
X-1576719Y251044D01*
X-1577889Y251304D01*
X-1579059Y252084D01*
X-1580034Y253384D01*
G01X-1558624Y251044D02*
Y266644D01*
G01X-1543649Y258064D02*
X-1537409D01*
X-1537994Y259884D01*
X-1538969Y260924D01*
X-1540334Y261444D01*
X-1541699Y261184D01*
X-1542869Y260404D01*
X-1543649Y258584D01*
X-1544039Y257024D01*
Y255464D01*
X-1543649Y253904D01*
X-1542674Y252344D01*
X-1541504Y251304D01*
X-1540139Y251044D01*
X-1538774Y251564D01*
X-1537409Y253124D01*
G01X-1501414Y251044D02*
Y261444D01*
G01Y259624D02*
X-1502194Y260664D01*
X-1503364Y261184D01*
X-1504729Y261444D01*
X-1506094Y260924D01*
X-1507264Y259884D01*
X-1508044Y258324D01*
X-1508434Y256244D01*
X-1508044Y254164D01*
X-1507264Y252604D01*
X-1506094Y251564D01*
X-1504729Y251044D01*
X-1503364Y251304D01*
X-1502194Y252084D01*
X-1501414Y253124D01*
G01X-1489754Y251044D02*
Y261444D01*
G01Y259364D02*
X-1488779Y260404D01*
X-1487804Y261184D01*
X-1486439Y261444D01*
X-1485464Y261184D01*
X-1484294Y260404D01*
G01X-1472049Y258064D02*
X-1465809D01*
X-1466394Y259884D01*
X-1467369Y260924D01*
X-1468734Y261444D01*
X-1470099Y261184D01*
X-1471269Y260404D01*
X-1472049Y258584D01*
X-1472439Y257024D01*
Y255464D01*
X-1472049Y253904D01*
X-1471074Y252344D01*
X-1469904Y251304D01*
X-1468539Y251044D01*
X-1467174Y251564D01*
X-1465809Y253124D01*
G01X-1434494Y251044D02*
Y264304D01*
X-1434104Y265604D01*
X-1433324Y266384D01*
X-1432154Y266644D01*
X-1430984Y266124D01*
X-1430399Y264824D01*
G01X-1432739Y260404D02*
X-1436639D01*
G01X-1415424Y261444D02*
Y251044D01*
G01Y265604D02*
X-1415814Y265864D01*
Y266384D01*
X-1415424Y266644D01*
X-1415034Y266384D01*
Y265864D01*
X-1415424Y265604D01*
G01X-1400839Y251044D02*
Y261444D01*
G01Y258844D02*
X-1400059Y260144D01*
X-1398889Y261184D01*
X-1397329Y261444D01*
X-1395964Y261184D01*
X-1394794Y260144D01*
X-1394209Y258324D01*
Y251044D01*
G01X-1379624Y261444D02*
Y251044D01*
G01Y265604D02*
X-1380014Y265864D01*
Y266384D01*
X-1379624Y266644D01*
X-1379234Y266384D01*
Y265864D01*
X-1379624Y265604D01*
G01X-1364649Y252864D02*
X-1363674Y251824D01*
X-1362309Y251044D01*
X-1361139D01*
X-1359969Y251564D01*
X-1359189Y252344D01*
X-1358799Y253384D01*
X-1358994Y254944D01*
X-1359774Y255724D01*
X-1363284Y257284D01*
X-1364064Y259104D01*
X-1363674Y260404D01*
X-1362894Y261184D01*
X-1361724Y261444D01*
X-1360554Y261184D01*
X-1359384Y260404D01*
G01X-1347139Y251044D02*
Y266644D01*
G01Y259104D02*
X-1346164Y260404D01*
X-1345189Y261184D01*
X-1343629Y261444D01*
X-1342459Y261184D01*
X-1341094Y260144D01*
X-1340509Y258584D01*
Y251044D01*
G01X-1328849Y258064D02*
X-1322609D01*
X-1323194Y259884D01*
X-1324169Y260924D01*
X-1325534Y261444D01*
X-1326899Y261184D01*
X-1328069Y260404D01*
X-1328849Y258584D01*
X-1329239Y257024D01*
Y255464D01*
X-1328849Y253904D01*
X-1327874Y252344D01*
X-1326704Y251304D01*
X-1325339Y251044D01*
X-1323974Y251564D01*
X-1322609Y253124D01*
G01X-1304514Y266644D02*
Y251044D01*
G01Y253384D02*
X-1305294Y252084D01*
X-1306464Y251304D01*
X-1307829Y251044D01*
X-1309389Y251564D01*
X-1310559Y252864D01*
X-1311339Y254424D01*
X-1311534Y256244D01*
X-1311339Y258064D01*
X-1310559Y259624D01*
X-1309389Y260924D01*
X-1307829Y261444D01*
X-1306464Y261184D01*
X-1305489Y260664D01*
X-1304514Y259624D01*
G01X-1275539Y251044D02*
Y266644D01*
G01Y259104D02*
X-1274564Y260404D01*
X-1273589Y261184D01*
X-1272029Y261444D01*
X-1270859Y261184D01*
X-1269494Y260144D01*
X-1268909Y258584D01*
Y251044D01*
G01X-1254324D02*
X-1255494Y251304D01*
X-1256664Y252344D01*
X-1257444Y254164D01*
X-1257834Y256244D01*
X-1257444Y258324D01*
X-1256664Y260144D01*
X-1255494Y261184D01*
X-1254324Y261444D01*
X-1253154Y261184D01*
X-1251984Y260144D01*
X-1251204Y258324D01*
X-1251009Y256244D01*
X-1251204Y254164D01*
X-1251984Y252344D01*
X-1253154Y251304D01*
X-1254324Y251044D01*
G01X-1236424D02*
Y266644D01*
G01X-1221449Y258064D02*
X-1215209D01*
X-1215794Y259884D01*
X-1216769Y260924D01*
X-1218134Y261444D01*
X-1219499Y261184D01*
X-1220669Y260404D01*
X-1221449Y258584D01*
X-1221839Y257024D01*
Y255464D01*
X-1221449Y253904D01*
X-1220474Y252344D01*
X-1219304Y251304D01*
X-1217939Y251044D01*
X-1216574Y251564D01*
X-1215209Y253124D01*
G01X-1185649Y252864D02*
X-1184674Y251824D01*
X-1183309Y251044D01*
X-1182139D01*
X-1180969Y251564D01*
X-1180189Y252344D01*
X-1179799Y253384D01*
X-1179994Y254944D01*
X-1180774Y255724D01*
X-1184284Y257284D01*
X-1185064Y259104D01*
X-1184674Y260404D01*
X-1183894Y261184D01*
X-1182724Y261444D01*
X-1181554Y261184D01*
X-1180384Y260404D01*
G01X-1164824Y261444D02*
Y251044D01*
G01Y265604D02*
X-1165214Y265864D01*
Y266384D01*
X-1164824Y266644D01*
X-1164434Y266384D01*
Y265864D01*
X-1164824Y265604D01*
G01X-1149849Y261444D02*
X-1143999D01*
X-1149849Y251044D01*
X-1143999D01*
G01X-1131949Y258064D02*
X-1125709D01*
X-1126294Y259884D01*
X-1127269Y260924D01*
X-1128634Y261444D01*
X-1129999Y261184D01*
X-1131169Y260404D01*
X-1131949Y258584D01*
X-1132339Y257024D01*
Y255464D01*
X-1131949Y253904D01*
X-1130974Y252344D01*
X-1129804Y251304D01*
X-1128439Y251044D01*
X-1127074Y251564D01*
X-1125709Y253124D01*
G01X-1114049Y252864D02*
X-1113074Y251824D01*
X-1111709Y251044D01*
X-1110539D01*
X-1109369Y251564D01*
X-1108589Y252344D01*
X-1108199Y253384D01*
X-1108394Y254944D01*
X-1109174Y255724D01*
X-1112684Y257284D01*
X-1113464Y259104D01*
X-1113074Y260404D01*
X-1112294Y261184D01*
X-1111124Y261444D01*
X-1109954Y261184D01*
X-1108784Y260404D01*
G01X-1080199Y261444D02*
X-1077859Y251044D01*
X-1075324Y261444D01*
X-1072789Y251044D01*
X-1070449Y261444D01*
G01X-1057424D02*
Y251044D01*
G01Y265604D02*
X-1057814Y265864D01*
Y266384D01*
X-1057424Y266644D01*
X-1057034Y266384D01*
Y265864D01*
X-1057424Y265604D01*
G01X-1039524Y266644D02*
Y251044D01*
G01X-1042254Y261444D02*
X-1036794D01*
G01X-1024939Y251044D02*
Y266644D01*
G01Y259104D02*
X-1023964Y260404D01*
X-1022989Y261184D01*
X-1021429Y261444D01*
X-1020259Y261184D01*
X-1018894Y260144D01*
X-1018309Y258584D01*
Y251044D01*
G01X-987969Y256244D02*
X-983289D01*
G01X-985824Y259624D02*
Y252864D01*
G01X-971434Y250524D02*
X-964414Y266644D01*
G01X-952559Y256244D02*
X-947489D01*
G01X-932124Y266644D02*
X-933684Y266124D01*
X-934854Y264824D01*
X-935634Y263264D01*
X-936219Y261184D01*
X-936414Y258844D01*
X-936219Y256504D01*
X-935634Y254424D01*
X-934854Y252864D01*
X-933684Y251564D01*
X-932124Y251044D01*
X-930564Y251564D01*
X-929394Y252864D01*
X-928614Y254424D01*
X-928029Y256504D01*
X-927834Y258844D01*
X-928029Y261184D01*
X-928614Y263264D01*
X-929394Y264824D01*
X-930564Y266124D01*
X-932124Y266644D01*
G01X-914224Y250524D02*
X-914614Y250784D01*
Y251304D01*
X-914224Y251564D01*
X-913834Y251304D01*
Y250784D01*
X-914224Y250524D01*
G01X-896324Y266644D02*
X-897884Y266124D01*
X-899054Y264824D01*
X-899834Y263264D01*
X-900419Y261184D01*
X-900614Y258844D01*
X-900419Y256504D01*
X-899834Y254424D01*
X-899054Y252864D01*
X-897884Y251564D01*
X-896324Y251044D01*
X-894764Y251564D01*
X-893594Y252864D01*
X-892814Y254424D01*
X-892229Y256504D01*
X-892034Y258844D01*
X-892229Y261184D01*
X-892814Y263264D01*
X-893594Y264824D01*
X-894764Y266124D01*
X-896324Y266644D01*
G01X-878424D02*
X-879984Y266124D01*
X-881154Y264824D01*
X-881934Y263264D01*
X-882519Y261184D01*
X-882714Y258844D01*
X-882519Y256504D01*
X-881934Y254424D01*
X-881154Y252864D01*
X-879984Y251564D01*
X-878424Y251044D01*
X-876864Y251564D01*
X-875694Y252864D01*
X-874914Y254424D01*
X-874329Y256504D01*
X-874134Y258844D01*
X-874329Y261184D01*
X-874914Y263264D01*
X-875694Y264824D01*
X-876864Y266124D01*
X-878424Y266644D01*
G01X-864814Y254164D02*
X-863644Y252344D01*
X-862084Y251304D01*
X-860329Y251044D01*
X-858769Y251304D01*
X-857209Y252604D01*
X-856234Y254164D01*
X-856039Y255724D01*
X-856429Y257544D01*
X-857794Y258844D01*
X-859159Y259364D01*
X-860914D01*
G01X-859159D02*
X-857989Y260144D01*
X-857014Y261444D01*
X-856624Y263004D01*
X-857014Y264564D01*
X-857989Y265864D01*
X-859744Y266644D01*
X-861499Y266384D01*
X-863254Y265344D01*
G01X-844379Y263264D02*
X-843404Y266644D01*
G01X-840869D02*
X-841844Y263264D01*
G01X-806824Y266644D02*
Y251044D01*
G01X-809554Y261444D02*
X-804094D01*
G01X-788924Y251044D02*
X-790094Y251304D01*
X-791264Y252344D01*
X-792044Y254164D01*
X-792434Y256244D01*
X-792044Y258324D01*
X-791264Y260144D01*
X-790094Y261184D01*
X-788924Y261444D01*
X-787754Y261184D01*
X-786584Y260144D01*
X-785804Y258324D01*
X-785609Y256244D01*
X-785804Y254164D01*
X-786584Y252344D01*
X-787754Y251304D01*
X-788924Y251044D01*
G01X-771024D02*
Y266644D01*
G01X-756049Y258064D02*
X-749809D01*
X-750394Y259884D01*
X-751369Y260924D01*
X-752734Y261444D01*
X-754099Y261184D01*
X-755269Y260404D01*
X-756049Y258584D01*
X-756439Y257024D01*
Y255464D01*
X-756049Y253904D01*
X-755074Y252344D01*
X-753904Y251304D01*
X-752539Y251044D01*
X-751174Y251564D01*
X-749809Y253124D01*
G01X-737954Y251044D02*
Y261444D01*
G01Y259364D02*
X-736979Y260404D01*
X-736004Y261184D01*
X-734639Y261444D01*
X-733664Y261184D01*
X-732494Y260404D01*
G01X-713814Y251044D02*
Y261444D01*
G01Y259624D02*
X-714594Y260664D01*
X-715764Y261184D01*
X-717129Y261444D01*
X-718494Y260924D01*
X-719664Y259884D01*
X-720444Y258324D01*
X-720834Y256244D01*
X-720444Y254164D01*
X-719664Y252604D01*
X-718494Y251564D01*
X-717129Y251044D01*
X-715764Y251304D01*
X-714594Y252084D01*
X-713814Y253124D01*
G01X-702739Y251044D02*
Y261444D01*
G01Y258844D02*
X-701959Y260144D01*
X-700789Y261184D01*
X-699229Y261444D01*
X-697864Y261184D01*
X-696694Y260144D01*
X-696109Y258324D01*
Y251044D01*
G01X-678404Y260144D02*
X-679769Y261184D01*
X-680939Y261444D01*
X-682499Y260924D01*
X-683669Y259884D01*
X-684449Y258064D01*
X-684644Y256244D01*
X-684449Y254424D01*
X-683669Y252864D01*
X-682499Y251564D01*
X-680939Y251044D01*
X-679574Y251564D01*
X-678404Y252604D01*
G01X-666549Y258064D02*
X-660309D01*
X-660894Y259884D01*
X-661869Y260924D01*
X-663234Y261444D01*
X-664599Y261184D01*
X-665769Y260404D01*
X-666549Y258584D01*
X-666939Y257024D01*
Y255464D01*
X-666549Y253904D01*
X-665574Y252344D01*
X-664404Y251304D01*
X-663039Y251044D01*
X-661674Y251564D01*
X-660309Y253124D01*
G01X-631139Y261444D02*
Y254164D01*
X-630359Y252344D01*
X-629189Y251304D01*
X-627824Y251044D01*
X-626459Y251304D01*
X-625289Y252344D01*
X-624509Y254164D01*
G01Y251044D02*
Y261444D01*
G01X-613239Y251044D02*
Y261444D01*
G01Y258844D02*
X-612459Y260144D01*
X-611289Y261184D01*
X-609729Y261444D01*
X-608364Y261184D01*
X-607194Y260144D01*
X-606609Y258324D01*
Y251044D01*
G01X-592024D02*
Y266644D01*
G01X-577049Y258064D02*
X-570809D01*
X-571394Y259884D01*
X-572369Y260924D01*
X-573734Y261444D01*
X-575099Y261184D01*
X-576269Y260404D01*
X-577049Y258584D01*
X-577439Y257024D01*
Y255464D01*
X-577049Y253904D01*
X-576074Y252344D01*
X-574904Y251304D01*
X-573539Y251044D01*
X-572174Y251564D01*
X-570809Y253124D01*
G01X-559149Y252864D02*
X-558174Y251824D01*
X-556809Y251044D01*
X-555639D01*
X-554469Y251564D01*
X-553689Y252344D01*
X-553299Y253384D01*
X-553494Y254944D01*
X-554274Y255724D01*
X-557784Y257284D01*
X-558564Y259104D01*
X-558174Y260404D01*
X-557394Y261184D01*
X-556224Y261444D01*
X-555054Y261184D01*
X-553884Y260404D01*
G01X-541249Y252864D02*
X-540274Y251824D01*
X-538909Y251044D01*
X-537739D01*
X-536569Y251564D01*
X-535789Y252344D01*
X-535399Y253384D01*
X-535594Y254944D01*
X-536374Y255724D01*
X-539884Y257284D01*
X-540664Y259104D01*
X-540274Y260404D01*
X-539494Y261184D01*
X-538324Y261444D01*
X-537154Y261184D01*
X-535984Y260404D01*
G01X-2074214Y285044D02*
Y295444D01*
G01Y293624D02*
X-2074994Y294664D01*
X-2076164Y295184D01*
X-2077529Y295444D01*
X-2078894Y294924D01*
X-2080064Y293884D01*
X-2080844Y292324D01*
X-2081234Y290244D01*
X-2080844Y288164D01*
X-2080064Y286604D01*
X-2078894Y285564D01*
X-2077529Y285044D01*
X-2076164Y285304D01*
X-2074994Y286084D01*
X-2074214Y287124D01*
G01X-2059824Y284524D02*
X-2060214Y284784D01*
Y285304D01*
X-2059824Y285564D01*
X-2059434Y285304D01*
Y284784D01*
X-2059824Y284524D01*
G01X-2028899Y285044D02*
X-2024024Y300644D01*
X-2019149Y285044D01*
G01X-2020904Y290504D02*
X-2027144D01*
G01X-2006124Y285044D02*
Y300644D01*
G01X-1988224Y285044D02*
Y300644D01*
G01X-1955739Y285044D02*
Y300644D01*
G01Y293104D02*
X-1954764Y294404D01*
X-1953789Y295184D01*
X-1952229Y295444D01*
X-1951059Y295184D01*
X-1949694Y294144D01*
X-1949109Y292584D01*
Y285044D01*
G01X-1934524D02*
X-1935694Y285304D01*
X-1936864Y286344D01*
X-1937644Y288164D01*
X-1938034Y290244D01*
X-1937644Y292324D01*
X-1936864Y294144D01*
X-1935694Y295184D01*
X-1934524Y295444D01*
X-1933354Y295184D01*
X-1932184Y294144D01*
X-1931404Y292324D01*
X-1931209Y290244D01*
X-1931404Y288164D01*
X-1932184Y286344D01*
X-1933354Y285304D01*
X-1934524Y285044D01*
G01X-1916624D02*
Y300644D01*
G01X-1901649Y292064D02*
X-1895409D01*
X-1895994Y293884D01*
X-1896969Y294924D01*
X-1898334Y295444D01*
X-1899699Y295184D01*
X-1900869Y294404D01*
X-1901649Y292584D01*
X-1902039Y291024D01*
Y289464D01*
X-1901649Y287904D01*
X-1900674Y286344D01*
X-1899504Y285304D01*
X-1898139Y285044D01*
X-1896774Y285564D01*
X-1895409Y287124D01*
G01X-1865849Y286864D02*
X-1864874Y285824D01*
X-1863509Y285044D01*
X-1862339D01*
X-1861169Y285564D01*
X-1860389Y286344D01*
X-1859999Y287384D01*
X-1860194Y288944D01*
X-1860974Y289724D01*
X-1864484Y291284D01*
X-1865264Y293104D01*
X-1864874Y294404D01*
X-1864094Y295184D01*
X-1862924Y295444D01*
X-1861754Y295184D01*
X-1860584Y294404D01*
G01X-1849119Y280364D02*
X-1847949Y279844D01*
X-1846389Y280364D01*
X-1845414Y281404D01*
X-1844634Y282704D01*
X-1843464Y286864D01*
X-1840929Y295444D01*
G01X-1847169D02*
X-1843464Y286864D01*
G01X-1832974Y285044D02*
Y295444D01*
G01Y292584D02*
X-1832389Y293884D01*
X-1831414Y294924D01*
X-1830049Y295444D01*
X-1828684Y294924D01*
X-1827709Y293884D01*
X-1827124Y292584D01*
Y285044D01*
G01Y292584D02*
X-1826539Y293884D01*
X-1825564Y294924D01*
X-1824199Y295444D01*
X-1822834Y294924D01*
X-1821859Y293884D01*
X-1821274Y292324D01*
Y285044D01*
G01X-1812734D02*
Y300644D01*
G01Y292844D02*
X-1811759Y294404D01*
X-1810589Y295184D01*
X-1809419Y295444D01*
X-1807664Y294924D01*
X-1806494Y293884D01*
X-1805714Y292064D01*
Y289984D01*
X-1806104Y287904D01*
X-1806884Y286344D01*
X-1808249Y285304D01*
X-1809419Y285044D01*
X-1810589Y285304D01*
X-1811759Y286084D01*
X-1812734Y287384D01*
G01X-1791324Y285044D02*
X-1792494Y285304D01*
X-1793664Y286344D01*
X-1794444Y288164D01*
X-1794834Y290244D01*
X-1794444Y292324D01*
X-1793664Y294144D01*
X-1792494Y295184D01*
X-1791324Y295444D01*
X-1790154Y295184D01*
X-1788984Y294144D01*
X-1788204Y292324D01*
X-1788009Y290244D01*
X-1788204Y288164D01*
X-1788984Y286344D01*
X-1790154Y285304D01*
X-1791324Y285044D01*
G01X-1773424D02*
Y300644D01*
G01X-1758449Y286864D02*
X-1757474Y285824D01*
X-1756109Y285044D01*
X-1754939D01*
X-1753769Y285564D01*
X-1752989Y286344D01*
X-1752599Y287384D01*
X-1752794Y288944D01*
X-1753574Y289724D01*
X-1757084Y291284D01*
X-1757864Y293104D01*
X-1757474Y294404D01*
X-1756694Y295184D01*
X-1755524Y295444D01*
X-1754354Y295184D01*
X-1753184Y294404D01*
G01X-1725574Y285044D02*
Y295444D01*
G01Y292584D02*
X-1724989Y293884D01*
X-1724014Y294924D01*
X-1722649Y295444D01*
X-1721284Y294924D01*
X-1720309Y293884D01*
X-1719724Y292584D01*
Y285044D01*
G01Y292584D02*
X-1719139Y293884D01*
X-1718164Y294924D01*
X-1716799Y295444D01*
X-1715434Y294924D01*
X-1714459Y293884D01*
X-1713874Y292324D01*
Y285044D01*
G01X-1698314D02*
Y295444D01*
G01Y293624D02*
X-1699094Y294664D01*
X-1700264Y295184D01*
X-1701629Y295444D01*
X-1702994Y294924D01*
X-1704164Y293884D01*
X-1704944Y292324D01*
X-1705334Y290244D01*
X-1704944Y288164D01*
X-1704164Y286604D01*
X-1702994Y285564D01*
X-1701629Y285044D01*
X-1700264Y285304D01*
X-1699094Y286084D01*
X-1698314Y287124D01*
G01X-1688019Y280364D02*
X-1686849Y279844D01*
X-1685289Y280364D01*
X-1684314Y281404D01*
X-1683534Y282704D01*
X-1682364Y286864D01*
X-1679829Y295444D01*
G01X-1686069D02*
X-1682364Y286864D01*
G01X-1651439Y285044D02*
Y295444D01*
G01Y292844D02*
X-1650659Y294144D01*
X-1649489Y295184D01*
X-1647929Y295444D01*
X-1646564Y295184D01*
X-1645394Y294144D01*
X-1644809Y292324D01*
Y285044D01*
G01X-1630224D02*
X-1631394Y285304D01*
X-1632564Y286344D01*
X-1633344Y288164D01*
X-1633734Y290244D01*
X-1633344Y292324D01*
X-1632564Y294144D01*
X-1631394Y295184D01*
X-1630224Y295444D01*
X-1629054Y295184D01*
X-1627884Y294144D01*
X-1627104Y292324D01*
X-1626909Y290244D01*
X-1627104Y288164D01*
X-1627884Y286344D01*
X-1629054Y285304D01*
X-1630224Y285044D01*
G01X-1612324Y300644D02*
Y285044D01*
G01X-1615054Y295444D02*
X-1609594D01*
G01X-1580034Y285044D02*
Y300644D01*
G01Y292844D02*
X-1579059Y294404D01*
X-1577889Y295184D01*
X-1576719Y295444D01*
X-1574964Y294924D01*
X-1573794Y293884D01*
X-1573014Y292064D01*
Y289984D01*
X-1573404Y287904D01*
X-1574184Y286344D01*
X-1575549Y285304D01*
X-1576719Y285044D01*
X-1577889Y285304D01*
X-1579059Y286084D01*
X-1580034Y287384D01*
G01X-1561549Y292064D02*
X-1555309D01*
X-1555894Y293884D01*
X-1556869Y294924D01*
X-1558234Y295444D01*
X-1559599Y295184D01*
X-1560769Y294404D01*
X-1561549Y292584D01*
X-1561939Y291024D01*
Y289464D01*
X-1561549Y287904D01*
X-1560574Y286344D01*
X-1559404Y285304D01*
X-1558039Y285044D01*
X-1556674Y285564D01*
X-1555309Y287124D01*
G01X-1525749Y286864D02*
X-1524774Y285824D01*
X-1523409Y285044D01*
X-1522239D01*
X-1521069Y285564D01*
X-1520289Y286344D01*
X-1519899Y287384D01*
X-1520094Y288944D01*
X-1520874Y289724D01*
X-1524384Y291284D01*
X-1525164Y293104D01*
X-1524774Y294404D01*
X-1523994Y295184D01*
X-1522824Y295444D01*
X-1521654Y295184D01*
X-1520484Y294404D01*
G01X-1508239Y285044D02*
Y300644D01*
G01Y293104D02*
X-1507264Y294404D01*
X-1506289Y295184D01*
X-1504729Y295444D01*
X-1503559Y295184D01*
X-1502194Y294144D01*
X-1501609Y292584D01*
Y285044D01*
G01X-1487024D02*
X-1488194Y285304D01*
X-1489364Y286344D01*
X-1490144Y288164D01*
X-1490534Y290244D01*
X-1490144Y292324D01*
X-1489364Y294144D01*
X-1488194Y295184D01*
X-1487024Y295444D01*
X-1485854Y295184D01*
X-1484684Y294144D01*
X-1483904Y292324D01*
X-1483709Y290244D01*
X-1483904Y288164D01*
X-1484684Y286344D01*
X-1485854Y285304D01*
X-1487024Y285044D01*
G01X-1473999Y295444D02*
X-1471659Y285044D01*
X-1469124Y295444D01*
X-1466589Y285044D01*
X-1464249Y295444D01*
G01X-1454539Y285044D02*
Y295444D01*
G01Y292844D02*
X-1453759Y294144D01*
X-1452589Y295184D01*
X-1451029Y295444D01*
X-1449664Y295184D01*
X-1448494Y294144D01*
X-1447909Y292324D01*
Y285044D01*
G01X-1415424Y295444D02*
Y285044D01*
G01Y299604D02*
X-1415814Y299864D01*
Y300384D01*
X-1415424Y300644D01*
X-1415034Y300384D01*
Y299864D01*
X-1415424Y299604D01*
G01X-1400839Y285044D02*
Y295444D01*
G01Y292844D02*
X-1400059Y294144D01*
X-1398889Y295184D01*
X-1397329Y295444D01*
X-1395964Y295184D01*
X-1394794Y294144D01*
X-1394209Y292324D01*
Y285044D01*
G01X-1361724Y300644D02*
Y285044D01*
G01X-1364454Y295444D02*
X-1358994D01*
G01X-1347139Y285044D02*
Y300644D01*
G01Y293104D02*
X-1346164Y294404D01*
X-1345189Y295184D01*
X-1343629Y295444D01*
X-1342459Y295184D01*
X-1341094Y294144D01*
X-1340509Y292584D01*
Y285044D01*
G01X-1328849Y292064D02*
X-1322609D01*
X-1323194Y293884D01*
X-1324169Y294924D01*
X-1325534Y295444D01*
X-1326899Y295184D01*
X-1328069Y294404D01*
X-1328849Y292584D01*
X-1329239Y291024D01*
Y289464D01*
X-1328849Y287904D01*
X-1327874Y286344D01*
X-1326704Y285304D01*
X-1325339Y285044D01*
X-1323974Y285564D01*
X-1322609Y287124D01*
G01X-1286614Y300644D02*
Y285044D01*
G01Y287384D02*
X-1287394Y286084D01*
X-1288564Y285304D01*
X-1289929Y285044D01*
X-1291489Y285564D01*
X-1292659Y286864D01*
X-1293439Y288424D01*
X-1293634Y290244D01*
X-1293439Y292064D01*
X-1292659Y293624D01*
X-1291489Y294924D01*
X-1289929Y295444D01*
X-1288564Y295184D01*
X-1287589Y294664D01*
X-1286614Y293624D01*
G01X-1274954Y285044D02*
Y295444D01*
G01Y293364D02*
X-1273979Y294404D01*
X-1273004Y295184D01*
X-1271639Y295444D01*
X-1270664Y295184D01*
X-1269494Y294404D01*
G01X-1250814Y285044D02*
Y295444D01*
G01Y293624D02*
X-1251594Y294664D01*
X-1252764Y295184D01*
X-1254129Y295444D01*
X-1255494Y294924D01*
X-1256664Y293884D01*
X-1257444Y292324D01*
X-1257834Y290244D01*
X-1257444Y288164D01*
X-1256664Y286604D01*
X-1255494Y285564D01*
X-1254129Y285044D01*
X-1252764Y285304D01*
X-1251594Y286084D01*
X-1250814Y287124D01*
G01X-1241299Y295444D02*
X-1238959Y285044D01*
X-1236424Y295444D01*
X-1233889Y285044D01*
X-1231549Y295444D01*
G01X-1218524D02*
Y285044D01*
G01Y299604D02*
X-1218914Y299864D01*
Y300384D01*
X-1218524Y300644D01*
X-1218134Y300384D01*
Y299864D01*
X-1218524Y299604D01*
G01X-1203939Y285044D02*
Y295444D01*
G01Y292844D02*
X-1203159Y294144D01*
X-1201989Y295184D01*
X-1200429Y295444D01*
X-1199064Y295184D01*
X-1197894Y294144D01*
X-1197309Y292324D01*
Y285044D01*
G01X-1185454Y281144D02*
X-1184089Y280104D01*
X-1182529Y279844D01*
X-1181164Y280104D01*
X-1179994Y281404D01*
X-1179214Y283224D01*
Y295444D01*
G01Y293364D02*
X-1179994Y294404D01*
X-1181164Y295184D01*
X-1182529Y295444D01*
X-1184089Y294924D01*
X-1185064Y293884D01*
X-1185844Y292064D01*
X-1186234Y290244D01*
X-1186039Y288684D01*
X-1185259Y286864D01*
X-1184089Y285564D01*
X-1182529Y285044D01*
X-1181359Y285304D01*
X-1179994Y286344D01*
X-1179214Y287384D01*
G01X-1164824Y284524D02*
X-1165214Y284784D01*
Y285304D01*
X-1164824Y285564D01*
X-1164434Y285304D01*
Y284784D01*
X-1164824Y284524D01*
G01X-1133119Y287124D02*
X-1131559Y285824D01*
X-1129804Y285044D01*
X-1128244D01*
X-1126684Y285824D01*
X-1125514Y287124D01*
X-1124929Y288944D01*
X-1125319Y290764D01*
X-1126294Y292324D01*
X-1128049Y293364D01*
X-1130389Y293884D01*
X-1131754Y294924D01*
X-1132339Y296744D01*
X-1131949Y298564D01*
X-1130974Y299864D01*
X-1129609Y300644D01*
X-1128244D01*
X-1126879Y300124D01*
X-1125709Y298824D01*
G01X-1114049Y292064D02*
X-1107809D01*
X-1108394Y293884D01*
X-1109369Y294924D01*
X-1110734Y295444D01*
X-1112099Y295184D01*
X-1113269Y294404D01*
X-1114049Y292584D01*
X-1114439Y291024D01*
Y289464D01*
X-1114049Y287904D01*
X-1113074Y286344D01*
X-1111904Y285304D01*
X-1110539Y285044D01*
X-1109174Y285564D01*
X-1107809Y287124D01*
G01X-1096149Y292064D02*
X-1089909D01*
X-1090494Y293884D01*
X-1091469Y294924D01*
X-1092834Y295444D01*
X-1094199Y295184D01*
X-1095369Y294404D01*
X-1096149Y292584D01*
X-1096539Y291024D01*
Y289464D01*
X-1096149Y287904D01*
X-1095174Y286344D01*
X-1094004Y285304D01*
X-1092639Y285044D01*
X-1091274Y285564D01*
X-1089909Y287124D01*
G01X-1061714Y285044D02*
Y300644D01*
X-1057814D01*
X-1056254Y299864D01*
X-1055084Y298824D01*
X-1054109Y297264D01*
X-1053329Y295444D01*
X-1053134Y292844D01*
X-1053329Y290244D01*
X-1054109Y288424D01*
X-1055084Y286864D01*
X-1056254Y285824D01*
X-1057814Y285044D01*
X-1061714D01*
G01X-1042254D02*
Y295444D01*
G01Y293364D02*
X-1041279Y294404D01*
X-1040304Y295184D01*
X-1038939Y295444D01*
X-1037964Y295184D01*
X-1036794Y294404D01*
G01X-1021624Y295444D02*
Y285044D01*
G01Y299604D02*
X-1022014Y299864D01*
Y300384D01*
X-1021624Y300644D01*
X-1021234Y300384D01*
Y299864D01*
X-1021624Y299604D01*
G01X-1003724Y285044D02*
Y300644D01*
G01X-985824Y285044D02*
Y300644D01*
G01X-946904Y294144D02*
X-948269Y295184D01*
X-949439Y295444D01*
X-950999Y294924D01*
X-952169Y293884D01*
X-952949Y292064D01*
X-953144Y290244D01*
X-952949Y288424D01*
X-952169Y286864D01*
X-950999Y285564D01*
X-949439Y285044D01*
X-948074Y285564D01*
X-946904Y286604D01*
G01X-935439Y285044D02*
Y300644D01*
G01Y293104D02*
X-934464Y294404D01*
X-933489Y295184D01*
X-931929Y295444D01*
X-930759Y295184D01*
X-929394Y294144D01*
X-928809Y292584D01*
Y285044D01*
G01X-910714D02*
Y295444D01*
G01Y293624D02*
X-911494Y294664D01*
X-912664Y295184D01*
X-914029Y295444D01*
X-915394Y294924D01*
X-916564Y293884D01*
X-917344Y292324D01*
X-917734Y290244D01*
X-917344Y288164D01*
X-916564Y286604D01*
X-915394Y285564D01*
X-914029Y285044D01*
X-912664Y285304D01*
X-911494Y286084D01*
X-910714Y287124D01*
G01X-899054Y285044D02*
Y295444D01*
G01Y293364D02*
X-898079Y294404D01*
X-897104Y295184D01*
X-895739Y295444D01*
X-894764Y295184D01*
X-893594Y294404D01*
G01X-878424Y300644D02*
Y285044D01*
G01X-881154Y295444D02*
X-875694D01*
G01X-843794Y285044D02*
Y298304D01*
X-843404Y299604D01*
X-842624Y300384D01*
X-841454Y300644D01*
X-840284Y300124D01*
X-839699Y298824D01*
G01X-842039Y294404D02*
X-845939D01*
G01X-824724Y285044D02*
X-825894Y285304D01*
X-827064Y286344D01*
X-827844Y288164D01*
X-828234Y290244D01*
X-827844Y292324D01*
X-827064Y294144D01*
X-825894Y295184D01*
X-824724Y295444D01*
X-823554Y295184D01*
X-822384Y294144D01*
X-821604Y292324D01*
X-821409Y290244D01*
X-821604Y288164D01*
X-822384Y286344D01*
X-823554Y285304D01*
X-824724Y285044D01*
G01X-809554D02*
Y295444D01*
G01Y293364D02*
X-808579Y294404D01*
X-807604Y295184D01*
X-806239Y295444D01*
X-805264Y295184D01*
X-804094Y294404D01*
G01X-767514Y300644D02*
Y285044D01*
G01Y287384D02*
X-768294Y286084D01*
X-769464Y285304D01*
X-770829Y285044D01*
X-772389Y285564D01*
X-773559Y286864D01*
X-774339Y288424D01*
X-774534Y290244D01*
X-774339Y292064D01*
X-773559Y293624D01*
X-772389Y294924D01*
X-770829Y295444D01*
X-769464Y295184D01*
X-768489Y294664D01*
X-767514Y293624D01*
G01X-756049Y292064D02*
X-749809D01*
X-750394Y293884D01*
X-751369Y294924D01*
X-752734Y295444D01*
X-754099Y295184D01*
X-755269Y294404D01*
X-756049Y292584D01*
X-756439Y291024D01*
Y289464D01*
X-756049Y287904D01*
X-755074Y286344D01*
X-753904Y285304D01*
X-752539Y285044D01*
X-751174Y285564D01*
X-749809Y287124D01*
G01X-735224Y300644D02*
Y285044D01*
G01X-737954Y295444D02*
X-732494D01*
G01X-713814Y285044D02*
Y295444D01*
G01Y293624D02*
X-714594Y294664D01*
X-715764Y295184D01*
X-717129Y295444D01*
X-718494Y294924D01*
X-719664Y293884D01*
X-720444Y292324D01*
X-720834Y290244D01*
X-720444Y288164D01*
X-719664Y286604D01*
X-718494Y285564D01*
X-717129Y285044D01*
X-715764Y285304D01*
X-714594Y286084D01*
X-713814Y287124D01*
G01X-699424Y295444D02*
Y285044D01*
G01Y299604D02*
X-699814Y299864D01*
Y300384D01*
X-699424Y300644D01*
X-699034Y300384D01*
Y299864D01*
X-699424Y299604D01*
G01X-681524Y285044D02*
Y300644D01*
G01X-666549Y286864D02*
X-665574Y285824D01*
X-664209Y285044D01*
X-663039D01*
X-661869Y285564D01*
X-661089Y286344D01*
X-660699Y287384D01*
X-660894Y288944D01*
X-661674Y289724D01*
X-665184Y291284D01*
X-665964Y293104D01*
X-665574Y294404D01*
X-664794Y295184D01*
X-663624Y295444D01*
X-662454Y295184D01*
X-661284Y294404D01*
G01X-645724Y284524D02*
X-646114Y284784D01*
Y285304D01*
X-645724Y285564D01*
X-645334Y285304D01*
Y284784D01*
X-645724Y284524D01*
G01X-2074214Y407044D02*
Y417444D01*
G01Y415624D02*
X-2074994Y416664D01*
X-2076164Y417184D01*
X-2077529Y417444D01*
X-2078894Y416924D01*
X-2080064Y415884D01*
X-2080844Y414324D01*
X-2081234Y412244D01*
X-2080844Y410164D01*
X-2080064Y408604D01*
X-2078894Y407564D01*
X-2077529Y407044D01*
X-2076164Y407304D01*
X-2074994Y408084D01*
X-2074214Y409124D01*
G01X-2059824Y406524D02*
X-2060214Y406784D01*
Y407304D01*
X-2059824Y407564D01*
X-2059434Y407304D01*
Y406784D01*
X-2059824Y406524D01*
G01X-2024024Y422644D02*
Y407044D01*
G01X-2028509Y422644D02*
X-2019539D01*
G01X-2002614Y407044D02*
Y417444D01*
G01Y415624D02*
X-2003394Y416664D01*
X-2004564Y417184D01*
X-2005929Y417444D01*
X-2007294Y416924D01*
X-2008464Y415884D01*
X-2009244Y414324D01*
X-2009634Y412244D01*
X-2009244Y410164D01*
X-2008464Y408604D01*
X-2007294Y407564D01*
X-2005929Y407044D01*
X-2004564Y407304D01*
X-2003394Y408084D01*
X-2002614Y409124D01*
G01X-1991539Y407044D02*
Y417444D01*
G01Y414844D02*
X-1990759Y416144D01*
X-1989589Y417184D01*
X-1988029Y417444D01*
X-1986664Y417184D01*
X-1985494Y416144D01*
X-1984909Y414324D01*
Y407044D01*
G01X-1973054Y403144D02*
X-1971689Y402104D01*
X-1970129Y401844D01*
X-1968764Y402104D01*
X-1967594Y403404D01*
X-1966814Y405224D01*
Y417444D01*
G01Y415364D02*
X-1967594Y416404D01*
X-1968764Y417184D01*
X-1970129Y417444D01*
X-1971689Y416924D01*
X-1972664Y415884D01*
X-1973444Y414064D01*
X-1973834Y412244D01*
X-1973639Y410684D01*
X-1972859Y408864D01*
X-1971689Y407564D01*
X-1970129Y407044D01*
X-1968959Y407304D01*
X-1967594Y408344D01*
X-1966814Y409384D01*
G01X-1955349Y414064D02*
X-1949109D01*
X-1949694Y415884D01*
X-1950669Y416924D01*
X-1952034Y417444D01*
X-1953399Y417184D01*
X-1954569Y416404D01*
X-1955349Y414584D01*
X-1955739Y413024D01*
Y411464D01*
X-1955349Y409904D01*
X-1954374Y408344D01*
X-1953204Y407304D01*
X-1951839Y407044D01*
X-1950474Y407564D01*
X-1949109Y409124D01*
G01X-1937839Y407044D02*
Y417444D01*
G01Y414844D02*
X-1937059Y416144D01*
X-1935889Y417184D01*
X-1934329Y417444D01*
X-1932964Y417184D01*
X-1931794Y416144D01*
X-1931209Y414324D01*
Y407044D01*
G01X-1913504Y416144D02*
X-1914869Y417184D01*
X-1916039Y417444D01*
X-1917599Y416924D01*
X-1918769Y415884D01*
X-1919549Y414064D01*
X-1919744Y412244D01*
X-1919549Y410424D01*
X-1918769Y408864D01*
X-1917599Y407564D01*
X-1916039Y407044D01*
X-1914674Y407564D01*
X-1913504Y408604D01*
G01X-1902819Y402364D02*
X-1901649Y401844D01*
X-1900089Y402364D01*
X-1899114Y403404D01*
X-1898334Y404704D01*
X-1897164Y408864D01*
X-1894629Y417444D01*
G01X-1900869D02*
X-1897164Y408864D01*
G01X-1862924Y417444D02*
Y407044D01*
G01Y421604D02*
X-1863314Y421864D01*
Y422384D01*
X-1862924Y422644D01*
X-1862534Y422384D01*
Y421864D01*
X-1862924Y421604D01*
G01X-1847949Y408864D02*
X-1846974Y407824D01*
X-1845609Y407044D01*
X-1844439D01*
X-1843269Y407564D01*
X-1842489Y408344D01*
X-1842099Y409384D01*
X-1842294Y410944D01*
X-1843074Y411724D01*
X-1846584Y413284D01*
X-1847364Y415104D01*
X-1846974Y416404D01*
X-1846194Y417184D01*
X-1845024Y417444D01*
X-1843854Y417184D01*
X-1842684Y416404D01*
G01X-1805714Y407044D02*
Y417444D01*
G01Y415624D02*
X-1806494Y416664D01*
X-1807664Y417184D01*
X-1809029Y417444D01*
X-1810394Y416924D01*
X-1811564Y415884D01*
X-1812344Y414324D01*
X-1812734Y412244D01*
X-1812344Y410164D01*
X-1811564Y408604D01*
X-1810394Y407564D01*
X-1809029Y407044D01*
X-1807664Y407304D01*
X-1806494Y408084D01*
X-1805714Y409124D01*
G01X-1791324Y407044D02*
Y422644D01*
G01X-1773424Y407044D02*
Y422644D01*
G01X-1755524Y407044D02*
X-1756694Y407304D01*
X-1757864Y408344D01*
X-1758644Y410164D01*
X-1759034Y412244D01*
X-1758644Y414324D01*
X-1757864Y416144D01*
X-1756694Y417184D01*
X-1755524Y417444D01*
X-1754354Y417184D01*
X-1753184Y416144D01*
X-1752404Y414324D01*
X-1752209Y412244D01*
X-1752404Y410164D01*
X-1753184Y408344D01*
X-1754354Y407304D01*
X-1755524Y407044D01*
G01X-1742499Y417444D02*
X-1740159Y407044D01*
X-1737624Y417444D01*
X-1735089Y407044D01*
X-1732749Y417444D01*
G01X-1722649Y414064D02*
X-1716409D01*
X-1716994Y415884D01*
X-1717969Y416924D01*
X-1719334Y417444D01*
X-1720699Y417184D01*
X-1721869Y416404D01*
X-1722649Y414584D01*
X-1723039Y413024D01*
Y411464D01*
X-1722649Y409904D01*
X-1721674Y408344D01*
X-1720504Y407304D01*
X-1719139Y407044D01*
X-1717774Y407564D01*
X-1716409Y409124D01*
G01X-1698314Y422644D02*
Y407044D01*
G01Y409384D02*
X-1699094Y408084D01*
X-1700264Y407304D01*
X-1701629Y407044D01*
X-1703189Y407564D01*
X-1704359Y408864D01*
X-1705139Y410424D01*
X-1705334Y412244D01*
X-1705139Y414064D01*
X-1704359Y415624D01*
X-1703189Y416924D01*
X-1701629Y417444D01*
X-1700264Y417184D01*
X-1699289Y416664D01*
X-1698314Y415624D01*
G01X-1666024Y407044D02*
X-1667194Y407304D01*
X-1668364Y408344D01*
X-1669144Y410164D01*
X-1669534Y412244D01*
X-1669144Y414324D01*
X-1668364Y416144D01*
X-1667194Y417184D01*
X-1666024Y417444D01*
X-1664854Y417184D01*
X-1663684Y416144D01*
X-1662904Y414324D01*
X-1662709Y412244D01*
X-1662904Y410164D01*
X-1663684Y408344D01*
X-1664854Y407304D01*
X-1666024Y407044D01*
G01X-1651439D02*
Y417444D01*
G01Y414844D02*
X-1650659Y416144D01*
X-1649489Y417184D01*
X-1647929Y417444D01*
X-1646564Y417184D01*
X-1645394Y416144D01*
X-1644809Y414324D01*
Y407044D01*
G01X-1615834Y417444D02*
X-1612324Y407044D01*
X-1608814Y417444D01*
G01X-1594424D02*
Y407044D01*
G01Y421604D02*
X-1594814Y421864D01*
Y422384D01*
X-1594424Y422644D01*
X-1594034Y422384D01*
Y421864D01*
X-1594424Y421604D01*
G01X-1573014Y407044D02*
Y417444D01*
G01Y415624D02*
X-1573794Y416664D01*
X-1574964Y417184D01*
X-1576329Y417444D01*
X-1577694Y416924D01*
X-1578864Y415884D01*
X-1579644Y414324D01*
X-1580034Y412244D01*
X-1579644Y410164D01*
X-1578864Y408604D01*
X-1577694Y407564D01*
X-1576329Y407044D01*
X-1574964Y407304D01*
X-1573794Y408084D01*
X-1573014Y409124D01*
G01X-1543649Y408864D02*
X-1542674Y407824D01*
X-1541309Y407044D01*
X-1540139D01*
X-1538969Y407564D01*
X-1538189Y408344D01*
X-1537799Y409384D01*
X-1537994Y410944D01*
X-1538774Y411724D01*
X-1542284Y413284D01*
X-1543064Y415104D01*
X-1542674Y416404D01*
X-1541894Y417184D01*
X-1540724Y417444D01*
X-1539554Y417184D01*
X-1538384Y416404D01*
G01X-1522824Y417444D02*
Y407044D01*
G01Y421604D02*
X-1523214Y421864D01*
Y422384D01*
X-1522824Y422644D01*
X-1522434Y422384D01*
Y421864D01*
X-1522824Y421604D01*
G01X-1507849Y417444D02*
X-1501999D01*
X-1507849Y407044D01*
X-1501999D01*
G01X-1489949Y414064D02*
X-1483709D01*
X-1484294Y415884D01*
X-1485269Y416924D01*
X-1486634Y417444D01*
X-1487999Y417184D01*
X-1489169Y416404D01*
X-1489949Y414584D01*
X-1490339Y413024D01*
Y411464D01*
X-1489949Y409904D01*
X-1488974Y408344D01*
X-1487804Y407304D01*
X-1486439Y407044D01*
X-1485074Y407564D01*
X-1483709Y409124D01*
G01X-1451224Y407044D02*
X-1449859Y407304D01*
X-1448299Y408084D01*
X-1447324Y409384D01*
X-1446934Y411204D01*
X-1447324Y413024D01*
X-1448494Y414584D01*
X-1450249Y415364D01*
X-1452199D01*
X-1453369Y415884D01*
X-1454344Y417184D01*
X-1454734Y419004D01*
X-1454149Y420824D01*
X-1452784Y422124D01*
X-1451224Y422644D01*
X-1449664Y422124D01*
X-1448299Y420824D01*
X-1447714Y419004D01*
X-1448104Y417184D01*
X-1449079Y415884D01*
X-1450249Y415364D01*
X-1452199D01*
X-1453954Y414584D01*
X-1455124Y413024D01*
X-1455514Y411204D01*
X-1455124Y409384D01*
X-1454149Y408084D01*
X-1452589Y407304D01*
X-1451224Y407044D01*
G01X-1439174D02*
Y417444D01*
G01Y414584D02*
X-1438589Y415884D01*
X-1437614Y416924D01*
X-1436249Y417444D01*
X-1434884Y416924D01*
X-1433909Y415884D01*
X-1433324Y414584D01*
Y407044D01*
G01Y414584D02*
X-1432739Y415884D01*
X-1431764Y416924D01*
X-1430399Y417444D01*
X-1429034Y416924D01*
X-1428059Y415884D01*
X-1427474Y414324D01*
Y407044D01*
G01X-1415424Y417444D02*
Y407044D01*
G01Y421604D02*
X-1415814Y421864D01*
Y422384D01*
X-1415424Y422644D01*
X-1415034Y422384D01*
Y421864D01*
X-1415424Y421604D01*
G01X-1397524Y407044D02*
Y422644D01*
G01X-1380014Y404184D02*
X-1379234Y407564D01*
G01X-1343824Y407044D02*
Y422644D01*
X-1346164Y419524D01*
G01Y407044D02*
X-1341484D01*
G01X-1325924Y422644D02*
X-1327484Y422124D01*
X-1328654Y420824D01*
X-1329434Y419264D01*
X-1330019Y417184D01*
X-1330214Y414844D01*
X-1330019Y412504D01*
X-1329434Y410424D01*
X-1328654Y408864D01*
X-1327484Y407564D01*
X-1325924Y407044D01*
X-1324364Y407564D01*
X-1323194Y408864D01*
X-1322414Y410424D01*
X-1321829Y412504D01*
X-1321634Y414844D01*
X-1321829Y417184D01*
X-1322414Y419264D01*
X-1323194Y420824D01*
X-1324364Y422124D01*
X-1325924Y422644D01*
G01X-1295974Y407044D02*
Y417444D01*
G01Y414584D02*
X-1295389Y415884D01*
X-1294414Y416924D01*
X-1293049Y417444D01*
X-1291684Y416924D01*
X-1290709Y415884D01*
X-1290124Y414584D01*
Y407044D01*
G01Y414584D02*
X-1289539Y415884D01*
X-1288564Y416924D01*
X-1287199Y417444D01*
X-1285834Y416924D01*
X-1284859Y415884D01*
X-1284274Y414324D01*
Y407044D01*
G01X-1272224Y417444D02*
Y407044D01*
G01Y421604D02*
X-1272614Y421864D01*
Y422384D01*
X-1272224Y422644D01*
X-1271834Y422384D01*
Y421864D01*
X-1272224Y421604D01*
G01X-1254324Y407044D02*
Y422644D01*
G01X-1239349Y408864D02*
X-1238374Y407824D01*
X-1237009Y407044D01*
X-1235839D01*
X-1234669Y407564D01*
X-1233889Y408344D01*
X-1233499Y409384D01*
X-1233694Y410944D01*
X-1234474Y411724D01*
X-1237984Y413284D01*
X-1238764Y415104D01*
X-1238374Y416404D01*
X-1237594Y417184D01*
X-1236424Y417444D01*
X-1235254Y417184D01*
X-1234084Y416404D01*
G01X-1197114Y407044D02*
Y417444D01*
G01Y415624D02*
X-1197894Y416664D01*
X-1199064Y417184D01*
X-1200429Y417444D01*
X-1201794Y416924D01*
X-1202964Y415884D01*
X-1203744Y414324D01*
X-1204134Y412244D01*
X-1203744Y410164D01*
X-1202964Y408604D01*
X-1201794Y407564D01*
X-1200429Y407044D01*
X-1199064Y407304D01*
X-1197894Y408084D01*
X-1197114Y409124D01*
G01X-1186039Y407044D02*
Y417444D01*
G01Y414844D02*
X-1185259Y416144D01*
X-1184089Y417184D01*
X-1182529Y417444D01*
X-1181164Y417184D01*
X-1179994Y416144D01*
X-1179409Y414324D01*
Y407044D01*
G01X-1161314Y422644D02*
Y407044D01*
G01Y409384D02*
X-1162094Y408084D01*
X-1163264Y407304D01*
X-1164629Y407044D01*
X-1166189Y407564D01*
X-1167359Y408864D01*
X-1168139Y410424D01*
X-1168334Y412244D01*
X-1168139Y414064D01*
X-1167359Y415624D01*
X-1166189Y416924D01*
X-1164629Y417444D01*
X-1163264Y417184D01*
X-1162289Y416664D01*
X-1161314Y415624D01*
G01X-1129024Y407044D02*
Y422644D01*
X-1131364Y419524D01*
G01Y407044D02*
X-1126684D01*
G01X-1114829Y420044D02*
X-1113659Y421604D01*
X-1112294Y422384D01*
X-1110734Y422644D01*
X-1108784Y422124D01*
X-1107419Y420824D01*
X-1107029Y419264D01*
X-1107224Y417704D01*
X-1108004Y416404D01*
X-1111904Y413804D01*
X-1113659Y411984D01*
X-1114829Y409384D01*
X-1115219Y407044D01*
X-1107029D01*
G01X-1081174D02*
Y417444D01*
G01Y414584D02*
X-1080589Y415884D01*
X-1079614Y416924D01*
X-1078249Y417444D01*
X-1076884Y416924D01*
X-1075909Y415884D01*
X-1075324Y414584D01*
Y407044D01*
G01Y414584D02*
X-1074739Y415884D01*
X-1073764Y416924D01*
X-1072399Y417444D01*
X-1071034Y416924D01*
X-1070059Y415884D01*
X-1069474Y414324D01*
Y407044D01*
G01X-1057424Y417444D02*
Y407044D01*
G01Y421604D02*
X-1057814Y421864D01*
Y422384D01*
X-1057424Y422644D01*
X-1057034Y422384D01*
Y421864D01*
X-1057424Y421604D01*
G01X-1039524Y407044D02*
Y422644D01*
G01X-1024549Y408864D02*
X-1023574Y407824D01*
X-1022209Y407044D01*
X-1021039D01*
X-1019869Y407564D01*
X-1019089Y408344D01*
X-1018699Y409384D01*
X-1018894Y410944D01*
X-1019674Y411724D01*
X-1023184Y413284D01*
X-1023964Y415104D01*
X-1023574Y416404D01*
X-1022794Y417184D01*
X-1021624Y417444D01*
X-1020454Y417184D01*
X-1019284Y416404D01*
G01X-989334Y401844D02*
Y417444D01*
G01Y415104D02*
X-988359Y416404D01*
X-987384Y417184D01*
X-985824Y417444D01*
X-984459Y417184D01*
X-983094Y415884D01*
X-982509Y414064D01*
X-982314Y412244D01*
X-982509Y410424D01*
X-983094Y408604D01*
X-984264Y407564D01*
X-985824Y407044D01*
X-987189Y407304D01*
X-988554Y408084D01*
X-989334Y409124D01*
G01X-970654Y407044D02*
Y417444D01*
G01Y415364D02*
X-969679Y416404D01*
X-968704Y417184D01*
X-967339Y417444D01*
X-966364Y417184D01*
X-965194Y416404D01*
G01X-950024Y407044D02*
X-951194Y407304D01*
X-952364Y408344D01*
X-953144Y410164D01*
X-953534Y412244D01*
X-953144Y414324D01*
X-952364Y416144D01*
X-951194Y417184D01*
X-950024Y417444D01*
X-948854Y417184D01*
X-947684Y416144D01*
X-946904Y414324D01*
X-946709Y412244D01*
X-946904Y410164D01*
X-947684Y408344D01*
X-948854Y407304D01*
X-950024Y407044D01*
G01X-935634Y417444D02*
X-932124Y407044D01*
X-928614Y417444D01*
G01X-914224D02*
Y407044D01*
G01Y421604D02*
X-914614Y421864D01*
Y422384D01*
X-914224Y422644D01*
X-913834Y422384D01*
Y421864D01*
X-914224Y421604D01*
G01X-892814Y422644D02*
Y407044D01*
G01Y409384D02*
X-893594Y408084D01*
X-894764Y407304D01*
X-896129Y407044D01*
X-897689Y407564D01*
X-898859Y408864D01*
X-899639Y410424D01*
X-899834Y412244D01*
X-899639Y414064D01*
X-898859Y415624D01*
X-897689Y416924D01*
X-896129Y417444D01*
X-894764Y417184D01*
X-893789Y416664D01*
X-892814Y415624D01*
G01X-881349Y414064D02*
X-875109D01*
X-875694Y415884D01*
X-876669Y416924D01*
X-878034Y417444D01*
X-879399Y417184D01*
X-880569Y416404D01*
X-881349Y414584D01*
X-881739Y413024D01*
Y411464D01*
X-881349Y409904D01*
X-880374Y408344D01*
X-879204Y407304D01*
X-877839Y407044D01*
X-876474Y407564D01*
X-875109Y409124D01*
G01X-857014Y422644D02*
Y407044D01*
G01Y409384D02*
X-857794Y408084D01*
X-858964Y407304D01*
X-860329Y407044D01*
X-861889Y407564D01*
X-863059Y408864D01*
X-863839Y410424D01*
X-864034Y412244D01*
X-863839Y414064D01*
X-863059Y415624D01*
X-861889Y416924D01*
X-860329Y417444D01*
X-858964Y417184D01*
X-857989Y416664D01*
X-857014Y415624D01*
G01X-842624Y406524D02*
X-843014Y406784D01*
Y407304D01*
X-842624Y407564D01*
X-842234Y407304D01*
Y406784D01*
X-842624Y406524D01*
G01X-2080844Y491144D02*
X-2079479Y490104D01*
X-2078309Y489844D01*
X-2076749Y490364D01*
X-2075579Y491664D01*
X-2074994Y494004D01*
Y505444D01*
G01Y509604D02*
X-2075384Y509864D01*
Y510384D01*
X-2074994Y510644D01*
X-2074604Y510384D01*
Y509864D01*
X-2074994Y509604D01*
G01X-2059824Y494524D02*
X-2060214Y494784D01*
Y495304D01*
X-2059824Y495564D01*
X-2059434Y495304D01*
Y494784D01*
X-2059824Y494524D01*
G01X-2024024Y510644D02*
Y495044D01*
G01X-2028509Y510644D02*
X-2019539D01*
G01X-2009439Y495044D02*
Y510644D01*
G01Y503104D02*
X-2008464Y504404D01*
X-2007489Y505184D01*
X-2005929Y505444D01*
X-2004759Y505184D01*
X-2003394Y504144D01*
X-2002809Y502584D01*
Y495044D01*
G01X-1991149Y502064D02*
X-1984909D01*
X-1985494Y503884D01*
X-1986469Y504924D01*
X-1987834Y505444D01*
X-1989199Y505184D01*
X-1990369Y504404D01*
X-1991149Y502584D01*
X-1991539Y501024D01*
Y499464D01*
X-1991149Y497904D01*
X-1990174Y496344D01*
X-1989004Y495304D01*
X-1987639Y495044D01*
X-1986274Y495564D01*
X-1984909Y497124D01*
G01X-1955349Y502064D02*
X-1949109D01*
X-1949694Y503884D01*
X-1950669Y504924D01*
X-1952034Y505444D01*
X-1953399Y505184D01*
X-1954569Y504404D01*
X-1955349Y502584D01*
X-1955739Y501024D01*
Y499464D01*
X-1955349Y497904D01*
X-1954374Y496344D01*
X-1953204Y495304D01*
X-1951839Y495044D01*
X-1950474Y495564D01*
X-1949109Y497124D01*
G01X-1937839Y495044D02*
Y505444D01*
G01Y502844D02*
X-1937059Y504144D01*
X-1935889Y505184D01*
X-1934329Y505444D01*
X-1932964Y505184D01*
X-1931794Y504144D01*
X-1931209Y502324D01*
Y495044D01*
G01X-1916624Y510644D02*
Y495044D01*
G01X-1919354Y505444D02*
X-1913894D01*
G01X-1898724D02*
Y495044D01*
G01Y509604D02*
X-1899114Y509864D01*
Y510384D01*
X-1898724Y510644D01*
X-1898334Y510384D01*
Y509864D01*
X-1898724Y509604D01*
G01X-1883554Y495044D02*
Y505444D01*
G01Y503364D02*
X-1882579Y504404D01*
X-1881604Y505184D01*
X-1880239Y505444D01*
X-1879264Y505184D01*
X-1878094Y504404D01*
G01X-1865849Y502064D02*
X-1859609D01*
X-1860194Y503884D01*
X-1861169Y504924D01*
X-1862534Y505444D01*
X-1863899Y505184D01*
X-1865069Y504404D01*
X-1865849Y502584D01*
X-1866239Y501024D01*
Y499464D01*
X-1865849Y497904D01*
X-1864874Y496344D01*
X-1863704Y495304D01*
X-1862339Y495044D01*
X-1860974Y495564D01*
X-1859609Y497124D01*
G01X-1823614Y495044D02*
Y505444D01*
G01Y503624D02*
X-1824394Y504664D01*
X-1825564Y505184D01*
X-1826929Y505444D01*
X-1828294Y504924D01*
X-1829464Y503884D01*
X-1830244Y502324D01*
X-1830634Y500244D01*
X-1830244Y498164D01*
X-1829464Y496604D01*
X-1828294Y495564D01*
X-1826929Y495044D01*
X-1825564Y495304D01*
X-1824394Y496084D01*
X-1823614Y497124D01*
G01X-1812149Y496864D02*
X-1811174Y495824D01*
X-1809809Y495044D01*
X-1808639D01*
X-1807469Y495564D01*
X-1806689Y496344D01*
X-1806299Y497384D01*
X-1806494Y498944D01*
X-1807274Y499724D01*
X-1810784Y501284D01*
X-1811564Y503104D01*
X-1811174Y504404D01*
X-1810394Y505184D01*
X-1809224Y505444D01*
X-1808054Y505184D01*
X-1806884Y504404D01*
G01X-1794249Y496864D02*
X-1793274Y495824D01*
X-1791909Y495044D01*
X-1790739D01*
X-1789569Y495564D01*
X-1788789Y496344D01*
X-1788399Y497384D01*
X-1788594Y498944D01*
X-1789374Y499724D01*
X-1792884Y501284D01*
X-1793664Y503104D01*
X-1793274Y504404D01*
X-1792494Y505184D01*
X-1791324Y505444D01*
X-1790154Y505184D01*
X-1788984Y504404D01*
G01X-1776349Y502064D02*
X-1770109D01*
X-1770694Y503884D01*
X-1771669Y504924D01*
X-1773034Y505444D01*
X-1774399Y505184D01*
X-1775569Y504404D01*
X-1776349Y502584D01*
X-1776739Y501024D01*
Y499464D01*
X-1776349Y497904D01*
X-1775374Y496344D01*
X-1774204Y495304D01*
X-1772839Y495044D01*
X-1771474Y495564D01*
X-1770109Y497124D01*
G01X-1761374Y495044D02*
Y505444D01*
G01Y502584D02*
X-1760789Y503884D01*
X-1759814Y504924D01*
X-1758449Y505444D01*
X-1757084Y504924D01*
X-1756109Y503884D01*
X-1755524Y502584D01*
Y495044D01*
G01Y502584D02*
X-1754939Y503884D01*
X-1753964Y504924D01*
X-1752599Y505444D01*
X-1751234Y504924D01*
X-1750259Y503884D01*
X-1749674Y502324D01*
Y495044D01*
G01X-1741134D02*
Y510644D01*
G01Y502844D02*
X-1740159Y504404D01*
X-1738989Y505184D01*
X-1737819Y505444D01*
X-1736064Y504924D01*
X-1734894Y503884D01*
X-1734114Y502064D01*
Y499984D01*
X-1734504Y497904D01*
X-1735284Y496344D01*
X-1736649Y495304D01*
X-1737819Y495044D01*
X-1738989Y495304D01*
X-1740159Y496084D01*
X-1741134Y497384D01*
G01X-1719724Y495044D02*
Y510644D01*
G01X-1705919Y490364D02*
X-1704749Y489844D01*
X-1703189Y490364D01*
X-1702214Y491404D01*
X-1701434Y492704D01*
X-1700264Y496864D01*
X-1697729Y505444D01*
G01X-1703969D02*
X-1700264Y496864D01*
G01X-1671874Y495044D02*
Y505444D01*
G01Y502584D02*
X-1671289Y503884D01*
X-1670314Y504924D01*
X-1668949Y505444D01*
X-1667584Y504924D01*
X-1666609Y503884D01*
X-1666024Y502584D01*
Y495044D01*
G01Y502584D02*
X-1665439Y503884D01*
X-1664464Y504924D01*
X-1663099Y505444D01*
X-1661734Y504924D01*
X-1660759Y503884D01*
X-1660174Y502324D01*
Y495044D01*
G01X-1651439Y505444D02*
Y498164D01*
X-1650659Y496344D01*
X-1649489Y495304D01*
X-1648124Y495044D01*
X-1646759Y495304D01*
X-1645589Y496344D01*
X-1644809Y498164D01*
G01Y495044D02*
Y505444D01*
G01X-1633149Y496864D02*
X-1632174Y495824D01*
X-1630809Y495044D01*
X-1629639D01*
X-1628469Y495564D01*
X-1627689Y496344D01*
X-1627299Y497384D01*
X-1627494Y498944D01*
X-1628274Y499724D01*
X-1631784Y501284D01*
X-1632564Y503104D01*
X-1632174Y504404D01*
X-1631394Y505184D01*
X-1630224Y505444D01*
X-1629054Y505184D01*
X-1627884Y504404D01*
G01X-1612324Y510644D02*
Y495044D01*
G01X-1615054Y505444D02*
X-1609594D01*
G01X-1580034Y495044D02*
Y510644D01*
G01Y502844D02*
X-1579059Y504404D01*
X-1577889Y505184D01*
X-1576719Y505444D01*
X-1574964Y504924D01*
X-1573794Y503884D01*
X-1573014Y502064D01*
Y499984D01*
X-1573404Y497904D01*
X-1574184Y496344D01*
X-1575549Y495304D01*
X-1576719Y495044D01*
X-1577889Y495304D01*
X-1579059Y496084D01*
X-1580034Y497384D01*
G01X-1561549Y502064D02*
X-1555309D01*
X-1555894Y503884D01*
X-1556869Y504924D01*
X-1558234Y505444D01*
X-1559599Y505184D01*
X-1560769Y504404D01*
X-1561549Y502584D01*
X-1561939Y501024D01*
Y499464D01*
X-1561549Y497904D01*
X-1560574Y496344D01*
X-1559404Y495304D01*
X-1558039Y495044D01*
X-1556674Y495564D01*
X-1555309Y497124D01*
G01X-1525164Y510644D02*
X-1520484D01*
G01X-1522824D02*
Y495044D01*
G01X-1525164D02*
X-1520484D01*
G01X-1501024D02*
X-1508824D01*
Y510644D01*
X-1501024D01*
G01X-1504144Y503104D02*
X-1508824D01*
G01X-1482734Y509344D02*
X-1483904Y510124D01*
X-1485269Y510644D01*
X-1486829D01*
X-1488584Y509864D01*
X-1489949Y508564D01*
X-1490924Y507004D01*
X-1491704Y504404D01*
X-1491899Y502064D01*
X-1491509Y499724D01*
X-1490924Y498164D01*
X-1489754Y496604D01*
X-1488389Y495564D01*
X-1487024Y495044D01*
X-1485659D01*
X-1484294Y495564D01*
X-1483124Y496344D01*
X-1482149Y497384D01*
G01X-1472634Y494524D02*
X-1465614Y510644D01*
G01X-1447324Y495044D02*
X-1455124D01*
Y510644D01*
X-1447324D01*
G01X-1450444Y503104D02*
X-1455124D01*
G01X-1437809Y495044D02*
Y510644D01*
X-1428839Y495044D01*
Y510644D01*
G01X-1419129Y501544D02*
X-1417764Y503364D01*
X-1416594Y504404D01*
X-1415034Y504924D01*
X-1413669Y504404D01*
X-1412694Y503364D01*
X-1411914Y501804D01*
X-1411719Y499984D01*
X-1411914Y498424D01*
X-1412694Y496864D01*
X-1413864Y495564D01*
X-1415229Y495044D01*
X-1416789Y495564D01*
X-1418154Y497124D01*
X-1418934Y499464D01*
X-1419129Y502064D01*
X-1418739Y505444D01*
X-1418154Y507264D01*
X-1417179Y509084D01*
X-1415814Y510384D01*
X-1414449Y510644D01*
X-1413084Y510124D01*
X-1412109Y508824D01*
G01X-1397524Y510644D02*
X-1399084Y510124D01*
X-1400254Y508824D01*
X-1401034Y507264D01*
X-1401619Y505184D01*
X-1401814Y502844D01*
X-1401619Y500504D01*
X-1401034Y498424D01*
X-1400254Y496864D01*
X-1399084Y495564D01*
X-1397524Y495044D01*
X-1395964Y495564D01*
X-1394794Y496864D01*
X-1394014Y498424D01*
X-1393429Y500504D01*
X-1393234Y502844D01*
X-1393429Y505184D01*
X-1394014Y507264D01*
X-1394794Y508824D01*
X-1395964Y510124D01*
X-1397524Y510644D01*
G01X-1382939Y496864D02*
X-1381574Y495564D01*
X-1380014Y495044D01*
X-1378454Y495564D01*
X-1377089Y497124D01*
X-1376114Y499464D01*
X-1375724Y501804D01*
Y504664D01*
X-1376114Y507004D01*
X-1377089Y509084D01*
X-1378259Y510124D01*
X-1379624Y510644D01*
X-1381184Y510124D01*
X-1382354Y509084D01*
X-1383134Y507524D01*
X-1383524Y505444D01*
X-1383134Y503624D01*
X-1382159Y501804D01*
X-1380989Y500764D01*
X-1379624Y500504D01*
X-1378064Y501024D01*
X-1376894Y502324D01*
X-1375724Y504664D01*
G01X-1366014Y497384D02*
X-1364844Y496084D01*
X-1363479Y495304D01*
X-1361724Y495044D01*
X-1359969Y495564D01*
X-1358604Y496604D01*
X-1357629Y498424D01*
X-1357434Y500504D01*
X-1357824Y502584D01*
X-1358799Y503884D01*
X-1360164Y504924D01*
X-1361529Y505184D01*
X-1362894Y504924D01*
X-1364649Y503884D01*
X-1364064Y510644D01*
X-1358799D01*
G01X-1343824D02*
X-1345384Y510124D01*
X-1346554Y508824D01*
X-1347334Y507264D01*
X-1347919Y505184D01*
X-1348114Y502844D01*
X-1347919Y500504D01*
X-1347334Y498424D01*
X-1346554Y496864D01*
X-1345384Y495564D01*
X-1343824Y495044D01*
X-1342264Y495564D01*
X-1341094Y496864D01*
X-1340314Y498424D01*
X-1339729Y500504D01*
X-1339534Y502844D01*
X-1339729Y505184D01*
X-1340314Y507264D01*
X-1341094Y508824D01*
X-1342264Y510124D01*
X-1343824Y510644D01*
G01X-1304904Y504144D02*
X-1306269Y505184D01*
X-1307439Y505444D01*
X-1308999Y504924D01*
X-1310169Y503884D01*
X-1310949Y502064D01*
X-1311144Y500244D01*
X-1310949Y498424D01*
X-1310169Y496864D01*
X-1308999Y495564D01*
X-1307439Y495044D01*
X-1306074Y495564D01*
X-1304904Y496604D01*
G01X-1290124Y495044D02*
X-1291294Y495304D01*
X-1292464Y496344D01*
X-1293244Y498164D01*
X-1293634Y500244D01*
X-1293244Y502324D01*
X-1292464Y504144D01*
X-1291294Y505184D01*
X-1290124Y505444D01*
X-1288954Y505184D01*
X-1287784Y504144D01*
X-1287004Y502324D01*
X-1286809Y500244D01*
X-1287004Y498164D01*
X-1287784Y496344D01*
X-1288954Y495304D01*
X-1290124Y495044D01*
G01X-1278074D02*
Y505444D01*
G01Y502584D02*
X-1277489Y503884D01*
X-1276514Y504924D01*
X-1275149Y505444D01*
X-1273784Y504924D01*
X-1272809Y503884D01*
X-1272224Y502584D01*
Y495044D01*
G01Y502584D02*
X-1271639Y503884D01*
X-1270664Y504924D01*
X-1269299Y505444D01*
X-1267934Y504924D01*
X-1266959Y503884D01*
X-1266374Y502324D01*
Y495044D01*
G01X-1257834Y489844D02*
Y505444D01*
G01Y503104D02*
X-1256859Y504404D01*
X-1255884Y505184D01*
X-1254324Y505444D01*
X-1252959Y505184D01*
X-1251594Y503884D01*
X-1251009Y502064D01*
X-1250814Y500244D01*
X-1251009Y498424D01*
X-1251594Y496604D01*
X-1252764Y495564D01*
X-1254324Y495044D01*
X-1255689Y495304D01*
X-1257054Y496084D01*
X-1257834Y497124D01*
G01X-1236424Y495044D02*
Y510644D01*
G01X-1218524Y505444D02*
Y495044D01*
G01Y509604D02*
X-1218914Y509864D01*
Y510384D01*
X-1218524Y510644D01*
X-1218134Y510384D01*
Y509864D01*
X-1218524Y509604D01*
G01X-1197114Y495044D02*
Y505444D01*
G01Y503624D02*
X-1197894Y504664D01*
X-1199064Y505184D01*
X-1200429Y505444D01*
X-1201794Y504924D01*
X-1202964Y503884D01*
X-1203744Y502324D01*
X-1204134Y500244D01*
X-1203744Y498164D01*
X-1202964Y496604D01*
X-1201794Y495564D01*
X-1200429Y495044D01*
X-1199064Y495304D01*
X-1197894Y496084D01*
X-1197114Y497124D01*
G01X-1186039Y495044D02*
Y505444D01*
G01Y502844D02*
X-1185259Y504144D01*
X-1184089Y505184D01*
X-1182529Y505444D01*
X-1181164Y505184D01*
X-1179994Y504144D01*
X-1179409Y502324D01*
Y495044D01*
G01X-1164824Y510644D02*
Y495044D01*
G01X-1167554Y505444D02*
X-1162094D01*
G01X-1125514Y495044D02*
Y505444D01*
G01Y503624D02*
X-1126294Y504664D01*
X-1127464Y505184D01*
X-1128829Y505444D01*
X-1130194Y504924D01*
X-1131364Y503884D01*
X-1132144Y502324D01*
X-1132534Y500244D01*
X-1132144Y498164D01*
X-1131364Y496604D01*
X-1130194Y495564D01*
X-1128829Y495044D01*
X-1127464Y495304D01*
X-1126294Y496084D01*
X-1125514Y497124D01*
G01X-1114439Y495044D02*
Y505444D01*
G01Y502844D02*
X-1113659Y504144D01*
X-1112489Y505184D01*
X-1110929Y505444D01*
X-1109564Y505184D01*
X-1108394Y504144D01*
X-1107809Y502324D01*
Y495044D01*
G01X-1089714Y510644D02*
Y495044D01*
G01Y497384D02*
X-1090494Y496084D01*
X-1091664Y495304D01*
X-1093029Y495044D01*
X-1094589Y495564D01*
X-1095759Y496864D01*
X-1096539Y498424D01*
X-1096734Y500244D01*
X-1096539Y502064D01*
X-1095759Y503624D01*
X-1094589Y504924D01*
X-1093029Y505444D01*
X-1091664Y505184D01*
X-1090689Y504664D01*
X-1089714Y503624D01*
G01X-1060934Y495044D02*
Y510644D01*
G01Y502844D02*
X-1059959Y504404D01*
X-1058789Y505184D01*
X-1057619Y505444D01*
X-1055864Y504924D01*
X-1054694Y503884D01*
X-1053914Y502064D01*
Y499984D01*
X-1054304Y497904D01*
X-1055084Y496344D01*
X-1056449Y495304D01*
X-1057619Y495044D01*
X-1058789Y495304D01*
X-1059959Y496084D01*
X-1060934Y497384D01*
G01X-1042449Y502064D02*
X-1036209D01*
X-1036794Y503884D01*
X-1037769Y504924D01*
X-1039134Y505444D01*
X-1040499Y505184D01*
X-1041669Y504404D01*
X-1042449Y502584D01*
X-1042839Y501024D01*
Y499464D01*
X-1042449Y497904D01*
X-1041474Y496344D01*
X-1040304Y495304D01*
X-1038939Y495044D01*
X-1037574Y495564D01*
X-1036209Y497124D01*
G01X-1007624Y495044D02*
Y510644D01*
X-1002749D01*
X-1001189Y509864D01*
X-1000214Y508824D01*
X-999824Y506744D01*
X-1000214Y504664D01*
X-1001384Y503364D01*
X-1002749Y502584D01*
X-1007624D01*
G01X-1002749D02*
X-999824Y495044D01*
G01X-985824D02*
X-986994Y495304D01*
X-988164Y496344D01*
X-988944Y498164D01*
X-989334Y500244D01*
X-988944Y502324D01*
X-988164Y504144D01*
X-986994Y505184D01*
X-985824Y505444D01*
X-984654Y505184D01*
X-983484Y504144D01*
X-982704Y502324D01*
X-982509Y500244D01*
X-982704Y498164D01*
X-983484Y496344D01*
X-984654Y495304D01*
X-985824Y495044D01*
G01X-972019D02*
Y510644D01*
G01X-963829D02*
Y495044D01*
G01Y502844D02*
X-972019D01*
G01X-954119Y497124D02*
X-952559Y495824D01*
X-950804Y495044D01*
X-949244D01*
X-947684Y495824D01*
X-946514Y497124D01*
X-945929Y498944D01*
X-946319Y500764D01*
X-947294Y502324D01*
X-949049Y503364D01*
X-951389Y503884D01*
X-952754Y504924D01*
X-953339Y506744D01*
X-952949Y508564D01*
X-951974Y509864D01*
X-950609Y510644D01*
X-949244D01*
X-947879Y510124D01*
X-946709Y508824D01*
G01X-917929Y501544D02*
X-916564Y503364D01*
X-915394Y504404D01*
X-913834Y504924D01*
X-912469Y504404D01*
X-911494Y503364D01*
X-910714Y501804D01*
X-910519Y499984D01*
X-910714Y498424D01*
X-911494Y496864D01*
X-912664Y495564D01*
X-914029Y495044D01*
X-915589Y495564D01*
X-916954Y497124D01*
X-917734Y499464D01*
X-917929Y502064D01*
X-917539Y505444D01*
X-916954Y507264D01*
X-915979Y509084D01*
X-914614Y510384D01*
X-913249Y510644D01*
X-911884Y510124D01*
X-910909Y508824D01*
G01X-875304Y504144D02*
X-876669Y505184D01*
X-877839Y505444D01*
X-879399Y504924D01*
X-880569Y503884D01*
X-881349Y502064D01*
X-881544Y500244D01*
X-881349Y498424D01*
X-880569Y496864D01*
X-879399Y495564D01*
X-877839Y495044D01*
X-876474Y495564D01*
X-875304Y496604D01*
G01X-860524Y495044D02*
X-861694Y495304D01*
X-862864Y496344D01*
X-863644Y498164D01*
X-864034Y500244D01*
X-863644Y502324D01*
X-862864Y504144D01*
X-861694Y505184D01*
X-860524Y505444D01*
X-859354Y505184D01*
X-858184Y504144D01*
X-857404Y502324D01*
X-857209Y500244D01*
X-857404Y498164D01*
X-858184Y496344D01*
X-859354Y495304D01*
X-860524Y495044D01*
G01X-848474D02*
Y505444D01*
G01Y502584D02*
X-847889Y503884D01*
X-846914Y504924D01*
X-845549Y505444D01*
X-844184Y504924D01*
X-843209Y503884D01*
X-842624Y502584D01*
Y495044D01*
G01Y502584D02*
X-842039Y503884D01*
X-841064Y504924D01*
X-839699Y505444D01*
X-838334Y504924D01*
X-837359Y503884D01*
X-836774Y502324D01*
Y495044D01*
G01X-828234Y489844D02*
Y505444D01*
G01Y503104D02*
X-827259Y504404D01*
X-826284Y505184D01*
X-824724Y505444D01*
X-823359Y505184D01*
X-821994Y503884D01*
X-821409Y502064D01*
X-821214Y500244D01*
X-821409Y498424D01*
X-821994Y496604D01*
X-823164Y495564D01*
X-824724Y495044D01*
X-826089Y495304D01*
X-827454Y496084D01*
X-828234Y497124D01*
G01X-806824Y495044D02*
Y510644D01*
G01X-788924Y505444D02*
Y495044D01*
G01Y509604D02*
X-789314Y509864D01*
Y510384D01*
X-788924Y510644D01*
X-788534Y510384D01*
Y509864D01*
X-788924Y509604D01*
G01X-767514Y495044D02*
Y505444D01*
G01Y503624D02*
X-768294Y504664D01*
X-769464Y505184D01*
X-770829Y505444D01*
X-772194Y504924D01*
X-773364Y503884D01*
X-774144Y502324D01*
X-774534Y500244D01*
X-774144Y498164D01*
X-773364Y496604D01*
X-772194Y495564D01*
X-770829Y495044D01*
X-769464Y495304D01*
X-768294Y496084D01*
X-767514Y497124D01*
G01X-756439Y495044D02*
Y505444D01*
G01Y502844D02*
X-755659Y504144D01*
X-754489Y505184D01*
X-752929Y505444D01*
X-751564Y505184D01*
X-750394Y504144D01*
X-749809Y502324D01*
Y495044D01*
G01X-735224Y510644D02*
Y495044D01*
G01X-737954Y505444D02*
X-732494D01*
G01X-717324Y494524D02*
X-717714Y494784D01*
Y495304D01*
X-717324Y495564D01*
X-716934Y495304D01*
Y494784D01*
X-717324Y494524D01*
G01X-2077724Y539444D02*
Y529044D01*
G01Y543604D02*
X-2078114Y543864D01*
Y544384D01*
X-2077724Y544644D01*
X-2077334Y544384D01*
Y543864D01*
X-2077724Y543604D01*
G01X-2059824Y528524D02*
X-2060214Y528784D01*
Y529304D01*
X-2059824Y529564D01*
X-2059434Y529304D01*
Y528784D01*
X-2059824Y528524D01*
G01X-2028509Y529044D02*
Y544644D01*
X-2019539Y529044D01*
Y544644D01*
G01X-2006124Y529044D02*
X-2007294Y529304D01*
X-2008464Y530344D01*
X-2009244Y532164D01*
X-2009634Y534244D01*
X-2009244Y536324D01*
X-2008464Y538144D01*
X-2007294Y539184D01*
X-2006124Y539444D01*
X-2004954Y539184D01*
X-2003784Y538144D01*
X-2003004Y536324D01*
X-2002809Y534244D01*
X-2003004Y532164D01*
X-2003784Y530344D01*
X-2004954Y529304D01*
X-2006124Y529044D01*
G01X-1991539D02*
Y539444D01*
G01Y536844D02*
X-1990759Y538144D01*
X-1989589Y539184D01*
X-1988029Y539444D01*
X-1986664Y539184D01*
X-1985494Y538144D01*
X-1984909Y536324D01*
Y529044D01*
G01X-1953594D02*
Y542304D01*
X-1953204Y543604D01*
X-1952424Y544384D01*
X-1951254Y544644D01*
X-1950084Y544124D01*
X-1949499Y542824D01*
G01X-1951839Y538404D02*
X-1955739D01*
G01X-1937839Y539444D02*
Y532164D01*
X-1937059Y530344D01*
X-1935889Y529304D01*
X-1934524Y529044D01*
X-1933159Y529304D01*
X-1931989Y530344D01*
X-1931209Y532164D01*
G01Y529044D02*
Y539444D01*
G01X-1919939Y529044D02*
Y539444D01*
G01Y536844D02*
X-1919159Y538144D01*
X-1917989Y539184D01*
X-1916429Y539444D01*
X-1915064Y539184D01*
X-1913894Y538144D01*
X-1913309Y536324D01*
Y529044D01*
G01X-1895604Y538144D02*
X-1896969Y539184D01*
X-1898139Y539444D01*
X-1899699Y538924D01*
X-1900869Y537884D01*
X-1901649Y536064D01*
X-1901844Y534244D01*
X-1901649Y532424D01*
X-1900869Y530864D01*
X-1899699Y529564D01*
X-1898139Y529044D01*
X-1896774Y529564D01*
X-1895604Y530604D01*
G01X-1880824Y544644D02*
Y529044D01*
G01X-1883554Y539444D02*
X-1878094D01*
G01X-1862924D02*
Y529044D01*
G01Y543604D02*
X-1863314Y543864D01*
Y544384D01*
X-1862924Y544644D01*
X-1862534Y544384D01*
Y543864D01*
X-1862924Y543604D01*
G01X-1845024Y529044D02*
X-1846194Y529304D01*
X-1847364Y530344D01*
X-1848144Y532164D01*
X-1848534Y534244D01*
X-1848144Y536324D01*
X-1847364Y538144D01*
X-1846194Y539184D01*
X-1845024Y539444D01*
X-1843854Y539184D01*
X-1842684Y538144D01*
X-1841904Y536324D01*
X-1841709Y534244D01*
X-1841904Y532164D01*
X-1842684Y530344D01*
X-1843854Y529304D01*
X-1845024Y529044D01*
G01X-1830439D02*
Y539444D01*
G01Y536844D02*
X-1829659Y538144D01*
X-1828489Y539184D01*
X-1826929Y539444D01*
X-1825564Y539184D01*
X-1824394Y538144D01*
X-1823809Y536324D01*
Y529044D01*
G01X-1805714D02*
Y539444D01*
G01Y537624D02*
X-1806494Y538664D01*
X-1807664Y539184D01*
X-1809029Y539444D01*
X-1810394Y538924D01*
X-1811564Y537884D01*
X-1812344Y536324D01*
X-1812734Y534244D01*
X-1812344Y532164D01*
X-1811564Y530604D01*
X-1810394Y529564D01*
X-1809029Y529044D01*
X-1807664Y529304D01*
X-1806494Y530084D01*
X-1805714Y531124D01*
G01X-1791324Y529044D02*
Y544644D01*
G01X-1759034Y523844D02*
Y539444D01*
G01Y537104D02*
X-1758059Y538404D01*
X-1757084Y539184D01*
X-1755524Y539444D01*
X-1754159Y539184D01*
X-1752794Y537884D01*
X-1752209Y536064D01*
X-1752014Y534244D01*
X-1752209Y532424D01*
X-1752794Y530604D01*
X-1753964Y529564D01*
X-1755524Y529044D01*
X-1756889Y529304D01*
X-1758254Y530084D01*
X-1759034Y531124D01*
G01X-1734114Y529044D02*
Y539444D01*
G01Y537624D02*
X-1734894Y538664D01*
X-1736064Y539184D01*
X-1737429Y539444D01*
X-1738794Y538924D01*
X-1739964Y537884D01*
X-1740744Y536324D01*
X-1741134Y534244D01*
X-1740744Y532164D01*
X-1739964Y530604D01*
X-1738794Y529564D01*
X-1737429Y529044D01*
X-1736064Y529304D01*
X-1734894Y530084D01*
X-1734114Y531124D01*
G01X-1716214Y544644D02*
Y529044D01*
G01Y531384D02*
X-1716994Y530084D01*
X-1718164Y529304D01*
X-1719529Y529044D01*
X-1721089Y529564D01*
X-1722259Y530864D01*
X-1723039Y532424D01*
X-1723234Y534244D01*
X-1723039Y536064D01*
X-1722259Y537624D01*
X-1721089Y538924D01*
X-1719529Y539444D01*
X-1718164Y539184D01*
X-1717189Y538664D01*
X-1716214Y537624D01*
G01X-1704749Y530864D02*
X-1703774Y529824D01*
X-1702409Y529044D01*
X-1701239D01*
X-1700069Y529564D01*
X-1699289Y530344D01*
X-1698899Y531384D01*
X-1699094Y532944D01*
X-1699874Y533724D01*
X-1703384Y535284D01*
X-1704164Y537104D01*
X-1703774Y538404D01*
X-1702994Y539184D01*
X-1701824Y539444D01*
X-1700654Y539184D01*
X-1699484Y538404D01*
G01X-1671874Y529044D02*
Y539444D01*
G01Y536584D02*
X-1671289Y537884D01*
X-1670314Y538924D01*
X-1668949Y539444D01*
X-1667584Y538924D01*
X-1666609Y537884D01*
X-1666024Y536584D01*
Y529044D01*
G01Y536584D02*
X-1665439Y537884D01*
X-1664464Y538924D01*
X-1663099Y539444D01*
X-1661734Y538924D01*
X-1660759Y537884D01*
X-1660174Y536324D01*
Y529044D01*
G01X-1644614D02*
Y539444D01*
G01Y537624D02*
X-1645394Y538664D01*
X-1646564Y539184D01*
X-1647929Y539444D01*
X-1649294Y538924D01*
X-1650464Y537884D01*
X-1651244Y536324D01*
X-1651634Y534244D01*
X-1651244Y532164D01*
X-1650464Y530604D01*
X-1649294Y529564D01*
X-1647929Y529044D01*
X-1646564Y529304D01*
X-1645394Y530084D01*
X-1644614Y531124D01*
G01X-1634319Y524364D02*
X-1633149Y523844D01*
X-1631589Y524364D01*
X-1630614Y525404D01*
X-1629834Y526704D01*
X-1628664Y530864D01*
X-1626129Y539444D01*
G01X-1632369D02*
X-1628664Y530864D01*
G01X-1597934Y529044D02*
Y544644D01*
G01Y536844D02*
X-1596959Y538404D01*
X-1595789Y539184D01*
X-1594619Y539444D01*
X-1592864Y538924D01*
X-1591694Y537884D01*
X-1590914Y536064D01*
Y533984D01*
X-1591304Y531904D01*
X-1592084Y530344D01*
X-1593449Y529304D01*
X-1594619Y529044D01*
X-1595789Y529304D01*
X-1596959Y530084D01*
X-1597934Y531384D01*
G01X-1579449Y536064D02*
X-1573209D01*
X-1573794Y537884D01*
X-1574769Y538924D01*
X-1576134Y539444D01*
X-1577499Y539184D01*
X-1578669Y538404D01*
X-1579449Y536584D01*
X-1579839Y535024D01*
Y533464D01*
X-1579449Y531904D01*
X-1578474Y530344D01*
X-1577304Y529304D01*
X-1575939Y529044D01*
X-1574574Y529564D01*
X-1573209Y531124D01*
G01X-1543454Y529044D02*
Y539444D01*
G01Y537364D02*
X-1542479Y538404D01*
X-1541504Y539184D01*
X-1540139Y539444D01*
X-1539164Y539184D01*
X-1537994Y538404D01*
G01X-1525749Y536064D02*
X-1519509D01*
X-1520094Y537884D01*
X-1521069Y538924D01*
X-1522434Y539444D01*
X-1523799Y539184D01*
X-1524969Y538404D01*
X-1525749Y536584D01*
X-1526139Y535024D01*
Y533464D01*
X-1525749Y531904D01*
X-1524774Y530344D01*
X-1523604Y529304D01*
X-1522239Y529044D01*
X-1520874Y529564D01*
X-1519509Y531124D01*
G01X-1510774Y529044D02*
Y539444D01*
G01Y536584D02*
X-1510189Y537884D01*
X-1509214Y538924D01*
X-1507849Y539444D01*
X-1506484Y538924D01*
X-1505509Y537884D01*
X-1504924Y536584D01*
Y529044D01*
G01Y536584D02*
X-1504339Y537884D01*
X-1503364Y538924D01*
X-1501999Y539444D01*
X-1500634Y538924D01*
X-1499659Y537884D01*
X-1499074Y536324D01*
Y529044D01*
G01X-1487024D02*
X-1488194Y529304D01*
X-1489364Y530344D01*
X-1490144Y532164D01*
X-1490534Y534244D01*
X-1490144Y536324D01*
X-1489364Y538144D01*
X-1488194Y539184D01*
X-1487024Y539444D01*
X-1485854Y539184D01*
X-1484684Y538144D01*
X-1483904Y536324D01*
X-1483709Y534244D01*
X-1483904Y532164D01*
X-1484684Y530344D01*
X-1485854Y529304D01*
X-1487024Y529044D01*
G01X-1472634Y539444D02*
X-1469124Y529044D01*
X-1465614Y539444D01*
G01X-1454149Y536064D02*
X-1447909D01*
X-1448494Y537884D01*
X-1449469Y538924D01*
X-1450834Y539444D01*
X-1452199Y539184D01*
X-1453369Y538404D01*
X-1454149Y536584D01*
X-1454539Y535024D01*
Y533464D01*
X-1454149Y531904D01*
X-1453174Y530344D01*
X-1452004Y529304D01*
X-1450639Y529044D01*
X-1449274Y529564D01*
X-1447909Y531124D01*
G01X-1429814Y544644D02*
Y529044D01*
G01Y531384D02*
X-1430594Y530084D01*
X-1431764Y529304D01*
X-1433129Y529044D01*
X-1434689Y529564D01*
X-1435859Y530864D01*
X-1436639Y532424D01*
X-1436834Y534244D01*
X-1436639Y536064D01*
X-1435859Y537624D01*
X-1434689Y538924D01*
X-1433129Y539444D01*
X-1431764Y539184D01*
X-1430789Y538664D01*
X-1429814Y537624D01*
G01X-1398694Y529044D02*
Y542304D01*
X-1398304Y543604D01*
X-1397524Y544384D01*
X-1396354Y544644D01*
X-1395184Y544124D01*
X-1394599Y542824D01*
G01X-1396939Y538404D02*
X-1400839D01*
G01X-1382354Y529044D02*
Y539444D01*
G01Y537364D02*
X-1381379Y538404D01*
X-1380404Y539184D01*
X-1379039Y539444D01*
X-1378064Y539184D01*
X-1376894Y538404D01*
G01X-1361724Y529044D02*
X-1362894Y529304D01*
X-1364064Y530344D01*
X-1364844Y532164D01*
X-1365234Y534244D01*
X-1364844Y536324D01*
X-1364064Y538144D01*
X-1362894Y539184D01*
X-1361724Y539444D01*
X-1360554Y539184D01*
X-1359384Y538144D01*
X-1358604Y536324D01*
X-1358409Y534244D01*
X-1358604Y532164D01*
X-1359384Y530344D01*
X-1360554Y529304D01*
X-1361724Y529044D01*
G01X-1349674D02*
Y539444D01*
G01Y536584D02*
X-1349089Y537884D01*
X-1348114Y538924D01*
X-1346749Y539444D01*
X-1345384Y538924D01*
X-1344409Y537884D01*
X-1343824Y536584D01*
Y529044D01*
G01Y536584D02*
X-1343239Y537884D01*
X-1342264Y538924D01*
X-1340899Y539444D01*
X-1339534Y538924D01*
X-1338559Y537884D01*
X-1337974Y536324D01*
Y529044D01*
G01X-1308024Y539444D02*
Y529044D01*
G01Y543604D02*
X-1308414Y543864D01*
Y544384D01*
X-1308024Y544644D01*
X-1307634Y544384D01*
Y543864D01*
X-1308024Y543604D01*
G01X-1293439Y529044D02*
Y539444D01*
G01Y536844D02*
X-1292659Y538144D01*
X-1291489Y539184D01*
X-1289929Y539444D01*
X-1288564Y539184D01*
X-1287394Y538144D01*
X-1286809Y536324D01*
Y529044D01*
G01X-1272224Y544644D02*
Y529044D01*
G01X-1274954Y539444D02*
X-1269494D01*
G01X-1257249Y536064D02*
X-1251009D01*
X-1251594Y537884D01*
X-1252569Y538924D01*
X-1253934Y539444D01*
X-1255299Y539184D01*
X-1256469Y538404D01*
X-1257249Y536584D01*
X-1257639Y535024D01*
Y533464D01*
X-1257249Y531904D01*
X-1256274Y530344D01*
X-1255104Y529304D01*
X-1253739Y529044D01*
X-1252374Y529564D01*
X-1251009Y531124D01*
G01X-1239154Y529044D02*
Y539444D01*
G01Y537364D02*
X-1238179Y538404D01*
X-1237204Y539184D01*
X-1235839Y539444D01*
X-1234864Y539184D01*
X-1233694Y538404D01*
G01X-1221839Y529044D02*
Y539444D01*
G01Y536844D02*
X-1221059Y538144D01*
X-1219889Y539184D01*
X-1218329Y539444D01*
X-1216964Y539184D01*
X-1215794Y538144D01*
X-1215209Y536324D01*
Y529044D01*
G01X-1197114D02*
Y539444D01*
G01Y537624D02*
X-1197894Y538664D01*
X-1199064Y539184D01*
X-1200429Y539444D01*
X-1201794Y538924D01*
X-1202964Y537884D01*
X-1203744Y536324D01*
X-1204134Y534244D01*
X-1203744Y532164D01*
X-1202964Y530604D01*
X-1201794Y529564D01*
X-1200429Y529044D01*
X-1199064Y529304D01*
X-1197894Y530084D01*
X-1197114Y531124D01*
G01X-1182724Y529044D02*
Y544644D01*
G01X-1146924Y529044D02*
Y544644D01*
G01X-1125514Y529044D02*
Y539444D01*
G01Y537624D02*
X-1126294Y538664D01*
X-1127464Y539184D01*
X-1128829Y539444D01*
X-1130194Y538924D01*
X-1131364Y537884D01*
X-1132144Y536324D01*
X-1132534Y534244D01*
X-1132144Y532164D01*
X-1131364Y530604D01*
X-1130194Y529564D01*
X-1128829Y529044D01*
X-1127464Y529304D01*
X-1126294Y530084D01*
X-1125514Y531124D01*
G01X-1115219Y524364D02*
X-1114049Y523844D01*
X-1112489Y524364D01*
X-1111514Y525404D01*
X-1110734Y526704D01*
X-1109564Y530864D01*
X-1107029Y539444D01*
G01X-1113269D02*
X-1109564Y530864D01*
G01X-1096149Y536064D02*
X-1089909D01*
X-1090494Y537884D01*
X-1091469Y538924D01*
X-1092834Y539444D01*
X-1094199Y539184D01*
X-1095369Y538404D01*
X-1096149Y536584D01*
X-1096539Y535024D01*
Y533464D01*
X-1096149Y531904D01*
X-1095174Y530344D01*
X-1094004Y529304D01*
X-1092639Y529044D01*
X-1091274Y529564D01*
X-1089909Y531124D01*
G01X-1078054Y529044D02*
Y539444D01*
G01Y537364D02*
X-1077079Y538404D01*
X-1076104Y539184D01*
X-1074739Y539444D01*
X-1073764Y539184D01*
X-1072594Y538404D01*
G01X-1060349Y530864D02*
X-1059374Y529824D01*
X-1058009Y529044D01*
X-1056839D01*
X-1055669Y529564D01*
X-1054889Y530344D01*
X-1054499Y531384D01*
X-1054694Y532944D01*
X-1055474Y533724D01*
X-1058984Y535284D01*
X-1059764Y537104D01*
X-1059374Y538404D01*
X-1058594Y539184D01*
X-1057424Y539444D01*
X-1056254Y539184D01*
X-1055084Y538404D01*
G01X-1039524Y528524D02*
X-1039914Y528784D01*
Y529304D01*
X-1039524Y529564D01*
X-1039134Y529304D01*
Y528784D01*
X-1039524Y528524D01*
G01X-2081039Y631044D02*
Y646644D01*
G01Y639104D02*
X-2080064Y640404D01*
X-2079089Y641184D01*
X-2077529Y641444D01*
X-2076359Y641184D01*
X-2074994Y640144D01*
X-2074409Y638584D01*
Y631044D01*
G01X-2059824Y630524D02*
X-2060214Y630784D01*
Y631304D01*
X-2059824Y631564D01*
X-2059434Y631304D01*
Y630784D01*
X-2059824Y630524D01*
G01X-2028314Y646644D02*
Y635464D01*
X-2027534Y633124D01*
X-2025974Y631564D01*
X-2024024Y631044D01*
X-2022074Y631564D01*
X-2020514Y633124D01*
X-2019734Y635464D01*
Y646644D01*
G01X-2009439Y631044D02*
Y641444D01*
G01Y638844D02*
X-2008659Y640144D01*
X-2007489Y641184D01*
X-2005929Y641444D01*
X-2004564Y641184D01*
X-2003394Y640144D01*
X-2002809Y638324D01*
Y631044D01*
G01X-1988224D02*
Y646644D01*
G01X-1973249Y638064D02*
X-1967009D01*
X-1967594Y639884D01*
X-1968569Y640924D01*
X-1969934Y641444D01*
X-1971299Y641184D01*
X-1972469Y640404D01*
X-1973249Y638584D01*
X-1973639Y637024D01*
Y635464D01*
X-1973249Y633904D01*
X-1972274Y632344D01*
X-1971104Y631304D01*
X-1969739Y631044D01*
X-1968374Y631564D01*
X-1967009Y633124D01*
G01X-1955349Y632864D02*
X-1954374Y631824D01*
X-1953009Y631044D01*
X-1951839D01*
X-1950669Y631564D01*
X-1949889Y632344D01*
X-1949499Y633384D01*
X-1949694Y634944D01*
X-1950474Y635724D01*
X-1953984Y637284D01*
X-1954764Y639104D01*
X-1954374Y640404D01*
X-1953594Y641184D01*
X-1952424Y641444D01*
X-1951254Y641184D01*
X-1950084Y640404D01*
G01X-1937449Y632864D02*
X-1936474Y631824D01*
X-1935109Y631044D01*
X-1933939D01*
X-1932769Y631564D01*
X-1931989Y632344D01*
X-1931599Y633384D01*
X-1931794Y634944D01*
X-1932574Y635724D01*
X-1936084Y637284D01*
X-1936864Y639104D01*
X-1936474Y640404D01*
X-1935694Y641184D01*
X-1934524Y641444D01*
X-1933354Y641184D01*
X-1932184Y640404D01*
G01X-1901649Y632864D02*
X-1900674Y631824D01*
X-1899309Y631044D01*
X-1898139D01*
X-1896969Y631564D01*
X-1896189Y632344D01*
X-1895799Y633384D01*
X-1895994Y634944D01*
X-1896774Y635724D01*
X-1900284Y637284D01*
X-1901064Y639104D01*
X-1900674Y640404D01*
X-1899894Y641184D01*
X-1898724Y641444D01*
X-1897554Y641184D01*
X-1896384Y640404D01*
G01X-1884334Y625844D02*
Y641444D01*
G01Y639104D02*
X-1883359Y640404D01*
X-1882384Y641184D01*
X-1880824Y641444D01*
X-1879459Y641184D01*
X-1878094Y639884D01*
X-1877509Y638064D01*
X-1877314Y636244D01*
X-1877509Y634424D01*
X-1878094Y632604D01*
X-1879264Y631564D01*
X-1880824Y631044D01*
X-1882189Y631304D01*
X-1883554Y632084D01*
X-1884334Y633124D01*
G01X-1865849Y638064D02*
X-1859609D01*
X-1860194Y639884D01*
X-1861169Y640924D01*
X-1862534Y641444D01*
X-1863899Y641184D01*
X-1865069Y640404D01*
X-1865849Y638584D01*
X-1866239Y637024D01*
Y635464D01*
X-1865849Y633904D01*
X-1864874Y632344D01*
X-1863704Y631304D01*
X-1862339Y631044D01*
X-1860974Y631564D01*
X-1859609Y633124D01*
G01X-1841904Y640144D02*
X-1843269Y641184D01*
X-1844439Y641444D01*
X-1845999Y640924D01*
X-1847169Y639884D01*
X-1847949Y638064D01*
X-1848144Y636244D01*
X-1847949Y634424D01*
X-1847169Y632864D01*
X-1845999Y631564D01*
X-1844439Y631044D01*
X-1843074Y631564D01*
X-1841904Y632604D01*
G01X-1827124Y641444D02*
Y631044D01*
G01Y645604D02*
X-1827514Y645864D01*
Y646384D01*
X-1827124Y646644D01*
X-1826734Y646384D01*
Y645864D01*
X-1827124Y645604D01*
G01X-1810394Y631044D02*
Y644304D01*
X-1810004Y645604D01*
X-1809224Y646384D01*
X-1808054Y646644D01*
X-1806884Y646124D01*
X-1806299Y644824D01*
G01X-1808639Y640404D02*
X-1812539D01*
G01X-1791324Y641444D02*
Y631044D01*
G01Y645604D02*
X-1791714Y645864D01*
Y646384D01*
X-1791324Y646644D01*
X-1790934Y646384D01*
Y645864D01*
X-1791324Y645604D01*
G01X-1776349Y638064D02*
X-1770109D01*
X-1770694Y639884D01*
X-1771669Y640924D01*
X-1773034Y641444D01*
X-1774399Y641184D01*
X-1775569Y640404D01*
X-1776349Y638584D01*
X-1776739Y637024D01*
Y635464D01*
X-1776349Y633904D01*
X-1775374Y632344D01*
X-1774204Y631304D01*
X-1772839Y631044D01*
X-1771474Y631564D01*
X-1770109Y633124D01*
G01X-1752014Y646644D02*
Y631044D01*
G01Y633384D02*
X-1752794Y632084D01*
X-1753964Y631304D01*
X-1755329Y631044D01*
X-1756889Y631564D01*
X-1758059Y632864D01*
X-1758839Y634424D01*
X-1759034Y636244D01*
X-1758839Y638064D01*
X-1758059Y639624D01*
X-1756889Y640924D01*
X-1755329Y641444D01*
X-1753964Y641184D01*
X-1752989Y640664D01*
X-1752014Y639624D01*
G01X-1719724Y631044D02*
X-1720894Y631304D01*
X-1722064Y632344D01*
X-1722844Y634164D01*
X-1723234Y636244D01*
X-1722844Y638324D01*
X-1722064Y640144D01*
X-1720894Y641184D01*
X-1719724Y641444D01*
X-1718554Y641184D01*
X-1717384Y640144D01*
X-1716604Y638324D01*
X-1716409Y636244D01*
X-1716604Y634164D01*
X-1717384Y632344D01*
X-1718554Y631304D01*
X-1719724Y631044D01*
G01X-1701824Y646644D02*
Y631044D01*
G01X-1704554Y641444D02*
X-1699094D01*
G01X-1687239Y631044D02*
Y646644D01*
G01Y639104D02*
X-1686264Y640404D01*
X-1685289Y641184D01*
X-1683729Y641444D01*
X-1682559Y641184D01*
X-1681194Y640144D01*
X-1680609Y638584D01*
Y631044D01*
G01X-1668949Y638064D02*
X-1662709D01*
X-1663294Y639884D01*
X-1664269Y640924D01*
X-1665634Y641444D01*
X-1666999Y641184D01*
X-1668169Y640404D01*
X-1668949Y638584D01*
X-1669339Y637024D01*
Y635464D01*
X-1668949Y633904D01*
X-1667974Y632344D01*
X-1666804Y631304D01*
X-1665439Y631044D01*
X-1664074Y631564D01*
X-1662709Y633124D01*
G01X-1650854Y631044D02*
Y641444D01*
G01Y639364D02*
X-1649879Y640404D01*
X-1648904Y641184D01*
X-1647539Y641444D01*
X-1646564Y641184D01*
X-1645394Y640404D01*
G01X-1635099Y641444D02*
X-1632759Y631044D01*
X-1630224Y641444D01*
X-1627689Y631044D01*
X-1625349Y641444D01*
G01X-1612324D02*
Y631044D01*
G01Y645604D02*
X-1612714Y645864D01*
Y646384D01*
X-1612324Y646644D01*
X-1611934Y646384D01*
Y645864D01*
X-1612324Y645604D01*
G01X-1597349Y632864D02*
X-1596374Y631824D01*
X-1595009Y631044D01*
X-1593839D01*
X-1592669Y631564D01*
X-1591889Y632344D01*
X-1591499Y633384D01*
X-1591694Y634944D01*
X-1592474Y635724D01*
X-1595984Y637284D01*
X-1596764Y639104D01*
X-1596374Y640404D01*
X-1595594Y641184D01*
X-1594424Y641444D01*
X-1593254Y641184D01*
X-1592084Y640404D01*
G01X-1579449Y638064D02*
X-1573209D01*
X-1573794Y639884D01*
X-1574769Y640924D01*
X-1576134Y641444D01*
X-1577499Y641184D01*
X-1578669Y640404D01*
X-1579449Y638584D01*
X-1579839Y637024D01*
Y635464D01*
X-1579449Y633904D01*
X-1578474Y632344D01*
X-1577304Y631304D01*
X-1575939Y631044D01*
X-1574574Y631564D01*
X-1573209Y633124D01*
G01X-1559014Y628184D02*
X-1558234Y631564D01*
G01X-1519314Y631044D02*
Y641444D01*
G01Y639624D02*
X-1520094Y640664D01*
X-1521264Y641184D01*
X-1522629Y641444D01*
X-1523994Y640924D01*
X-1525164Y639884D01*
X-1525944Y638324D01*
X-1526334Y636244D01*
X-1525944Y634164D01*
X-1525164Y632604D01*
X-1523994Y631564D01*
X-1522629Y631044D01*
X-1521264Y631304D01*
X-1520094Y632084D01*
X-1519314Y633124D01*
G01X-1508434Y641444D02*
X-1504924Y631044D01*
X-1501414Y641444D01*
G01X-1489949Y638064D02*
X-1483709D01*
X-1484294Y639884D01*
X-1485269Y640924D01*
X-1486634Y641444D01*
X-1487999Y641184D01*
X-1489169Y640404D01*
X-1489949Y638584D01*
X-1490339Y637024D01*
Y635464D01*
X-1489949Y633904D01*
X-1488974Y632344D01*
X-1487804Y631304D01*
X-1486439Y631044D01*
X-1485074Y631564D01*
X-1483709Y633124D01*
G01X-1471854Y631044D02*
Y641444D01*
G01Y639364D02*
X-1470879Y640404D01*
X-1469904Y641184D01*
X-1468539Y641444D01*
X-1467564Y641184D01*
X-1466394Y640404D01*
G01X-1447714Y631044D02*
Y641444D01*
G01Y639624D02*
X-1448494Y640664D01*
X-1449664Y641184D01*
X-1451029Y641444D01*
X-1452394Y640924D01*
X-1453564Y639884D01*
X-1454344Y638324D01*
X-1454734Y636244D01*
X-1454344Y634164D01*
X-1453564Y632604D01*
X-1452394Y631564D01*
X-1451029Y631044D01*
X-1449664Y631304D01*
X-1448494Y632084D01*
X-1447714Y633124D01*
G01X-1436054Y627144D02*
X-1434689Y626104D01*
X-1433129Y625844D01*
X-1431764Y626104D01*
X-1430594Y627404D01*
X-1429814Y629224D01*
Y641444D01*
G01Y639364D02*
X-1430594Y640404D01*
X-1431764Y641184D01*
X-1433129Y641444D01*
X-1434689Y640924D01*
X-1435664Y639884D01*
X-1436444Y638064D01*
X-1436834Y636244D01*
X-1436639Y634684D01*
X-1435859Y632864D01*
X-1434689Y631564D01*
X-1433129Y631044D01*
X-1431959Y631304D01*
X-1430594Y632344D01*
X-1429814Y633384D01*
G01X-1418349Y638064D02*
X-1412109D01*
X-1412694Y639884D01*
X-1413669Y640924D01*
X-1415034Y641444D01*
X-1416399Y641184D01*
X-1417569Y640404D01*
X-1418349Y638584D01*
X-1418739Y637024D01*
Y635464D01*
X-1418349Y633904D01*
X-1417374Y632344D01*
X-1416204Y631304D01*
X-1414839Y631044D01*
X-1413474Y631564D01*
X-1412109Y633124D01*
G01X-1376504Y640144D02*
X-1377869Y641184D01*
X-1379039Y641444D01*
X-1380599Y640924D01*
X-1381769Y639884D01*
X-1382549Y638064D01*
X-1382744Y636244D01*
X-1382549Y634424D01*
X-1381769Y632864D01*
X-1380599Y631564D01*
X-1379039Y631044D01*
X-1377674Y631564D01*
X-1376504Y632604D01*
G01X-1361724Y631044D02*
X-1362894Y631304D01*
X-1364064Y632344D01*
X-1364844Y634164D01*
X-1365234Y636244D01*
X-1364844Y638324D01*
X-1364064Y640144D01*
X-1362894Y641184D01*
X-1361724Y641444D01*
X-1360554Y641184D01*
X-1359384Y640144D01*
X-1358604Y638324D01*
X-1358409Y636244D01*
X-1358604Y634164D01*
X-1359384Y632344D01*
X-1360554Y631304D01*
X-1361724Y631044D01*
G01X-1347334Y625844D02*
Y641444D01*
G01Y639104D02*
X-1346359Y640404D01*
X-1345384Y641184D01*
X-1343824Y641444D01*
X-1342459Y641184D01*
X-1341094Y639884D01*
X-1340509Y638064D01*
X-1340314Y636244D01*
X-1340509Y634424D01*
X-1341094Y632604D01*
X-1342264Y631564D01*
X-1343824Y631044D01*
X-1345189Y631304D01*
X-1346554Y632084D01*
X-1347334Y633124D01*
G01X-1329434Y625844D02*
Y641444D01*
G01Y639104D02*
X-1328459Y640404D01*
X-1327484Y641184D01*
X-1325924Y641444D01*
X-1324559Y641184D01*
X-1323194Y639884D01*
X-1322609Y638064D01*
X-1322414Y636244D01*
X-1322609Y634424D01*
X-1323194Y632604D01*
X-1324364Y631564D01*
X-1325924Y631044D01*
X-1327289Y631304D01*
X-1328654Y632084D01*
X-1329434Y633124D01*
G01X-1310949Y638064D02*
X-1304709D01*
X-1305294Y639884D01*
X-1306269Y640924D01*
X-1307634Y641444D01*
X-1308999Y641184D01*
X-1310169Y640404D01*
X-1310949Y638584D01*
X-1311339Y637024D01*
Y635464D01*
X-1310949Y633904D01*
X-1309974Y632344D01*
X-1308804Y631304D01*
X-1307439Y631044D01*
X-1306074Y631564D01*
X-1304709Y633124D01*
G01X-1292854Y631044D02*
Y641444D01*
G01Y639364D02*
X-1291879Y640404D01*
X-1290904Y641184D01*
X-1289539Y641444D01*
X-1288564Y641184D01*
X-1287394Y640404D01*
G01X-1254324Y646644D02*
Y631044D01*
G01X-1257054Y641444D02*
X-1251594D01*
G01X-1239739Y631044D02*
Y646644D01*
G01Y639104D02*
X-1238764Y640404D01*
X-1237789Y641184D01*
X-1236229Y641444D01*
X-1235059Y641184D01*
X-1233694Y640144D01*
X-1233109Y638584D01*
Y631044D01*
G01X-1218524Y641444D02*
Y631044D01*
G01Y645604D02*
X-1218914Y645864D01*
Y646384D01*
X-1218524Y646644D01*
X-1218134Y646384D01*
Y645864D01*
X-1218524Y645604D01*
G01X-1197504Y640144D02*
X-1198869Y641184D01*
X-1200039Y641444D01*
X-1201599Y640924D01*
X-1202769Y639884D01*
X-1203549Y638064D01*
X-1203744Y636244D01*
X-1203549Y634424D01*
X-1202769Y632864D01*
X-1201599Y631564D01*
X-1200039Y631044D01*
X-1198674Y631564D01*
X-1197504Y632604D01*
G01X-1186039Y631044D02*
Y646644D01*
G01X-1179799Y641444D02*
X-1186039Y635464D01*
G01X-1183504Y637804D02*
X-1179409Y631044D01*
G01X-1168139D02*
Y641444D01*
G01Y638844D02*
X-1167359Y640144D01*
X-1166189Y641184D01*
X-1164629Y641444D01*
X-1163264Y641184D01*
X-1162094Y640144D01*
X-1161509Y638324D01*
Y631044D01*
G01X-1149849Y638064D02*
X-1143609D01*
X-1144194Y639884D01*
X-1145169Y640924D01*
X-1146534Y641444D01*
X-1147899Y641184D01*
X-1149069Y640404D01*
X-1149849Y638584D01*
X-1150239Y637024D01*
Y635464D01*
X-1149849Y633904D01*
X-1148874Y632344D01*
X-1147704Y631304D01*
X-1146339Y631044D01*
X-1144974Y631564D01*
X-1143609Y633124D01*
G01X-1131949Y632864D02*
X-1130974Y631824D01*
X-1129609Y631044D01*
X-1128439D01*
X-1127269Y631564D01*
X-1126489Y632344D01*
X-1126099Y633384D01*
X-1126294Y634944D01*
X-1127074Y635724D01*
X-1130584Y637284D01*
X-1131364Y639104D01*
X-1130974Y640404D01*
X-1130194Y641184D01*
X-1129024Y641444D01*
X-1127854Y641184D01*
X-1126684Y640404D01*
G01X-1114049Y632864D02*
X-1113074Y631824D01*
X-1111709Y631044D01*
X-1110539D01*
X-1109369Y631564D01*
X-1108589Y632344D01*
X-1108199Y633384D01*
X-1108394Y634944D01*
X-1109174Y635724D01*
X-1112684Y637284D01*
X-1113464Y639104D01*
X-1113074Y640404D01*
X-1112294Y641184D01*
X-1111124Y641444D01*
X-1109954Y641184D01*
X-1108784Y640404D01*
G01X-1075324Y641444D02*
Y631044D01*
G01Y645604D02*
X-1075714Y645864D01*
Y646384D01*
X-1075324Y646644D01*
X-1074934Y646384D01*
Y645864D01*
X-1075324Y645604D01*
G01X-1060739Y631044D02*
Y641444D01*
G01Y638844D02*
X-1059959Y640144D01*
X-1058789Y641184D01*
X-1057229Y641444D01*
X-1055864Y641184D01*
X-1054694Y640144D01*
X-1054109Y638324D01*
Y631044D01*
G01X-1025134Y625844D02*
Y641444D01*
G01Y639104D02*
X-1024159Y640404D01*
X-1023184Y641184D01*
X-1021624Y641444D01*
X-1020259Y641184D01*
X-1018894Y639884D01*
X-1018309Y638064D01*
X-1018114Y636244D01*
X-1018309Y634424D01*
X-1018894Y632604D01*
X-1020064Y631564D01*
X-1021624Y631044D01*
X-1022989Y631304D01*
X-1024354Y632084D01*
X-1025134Y633124D01*
G01X-1003724Y631044D02*
Y646644D01*
G01X-982314Y631044D02*
Y641444D01*
G01Y639624D02*
X-983094Y640664D01*
X-984264Y641184D01*
X-985629Y641444D01*
X-986994Y640924D01*
X-988164Y639884D01*
X-988944Y638324D01*
X-989334Y636244D01*
X-988944Y634164D01*
X-988164Y632604D01*
X-986994Y631564D01*
X-985629Y631044D01*
X-984264Y631304D01*
X-983094Y632084D01*
X-982314Y633124D01*
G01X-967924Y646644D02*
Y631044D01*
G01X-970654Y641444D02*
X-965194D01*
G01X-952949Y638064D02*
X-946709D01*
X-947294Y639884D01*
X-948269Y640924D01*
X-949634Y641444D01*
X-950999Y641184D01*
X-952169Y640404D01*
X-952949Y638584D01*
X-953339Y637024D01*
Y635464D01*
X-952949Y633904D01*
X-951974Y632344D01*
X-950804Y631304D01*
X-949439Y631044D01*
X-948074Y631564D01*
X-946709Y633124D01*
G01X-928614Y646644D02*
Y631044D01*
G01Y633384D02*
X-929394Y632084D01*
X-930564Y631304D01*
X-931929Y631044D01*
X-933489Y631564D01*
X-934659Y632864D01*
X-935439Y634424D01*
X-935634Y636244D01*
X-935439Y638064D01*
X-934659Y639624D01*
X-933489Y640924D01*
X-931929Y641444D01*
X-930564Y641184D01*
X-929589Y640664D01*
X-928614Y639624D01*
G01X-896324Y646644D02*
Y631044D01*
G01X-899054Y641444D02*
X-893594D01*
G01X-881739Y631044D02*
Y646644D01*
G01Y639104D02*
X-880764Y640404D01*
X-879789Y641184D01*
X-878229Y641444D01*
X-877059Y641184D01*
X-875694Y640144D01*
X-875109Y638584D01*
Y631044D01*
G01X-863254D02*
Y641444D01*
G01Y639364D02*
X-862279Y640404D01*
X-861304Y641184D01*
X-859939Y641444D01*
X-858964Y641184D01*
X-857794Y640404D01*
G01X-842624Y631044D02*
X-843794Y631304D01*
X-844964Y632344D01*
X-845744Y634164D01*
X-846134Y636244D01*
X-845744Y638324D01*
X-844964Y640144D01*
X-843794Y641184D01*
X-842624Y641444D01*
X-841454Y641184D01*
X-840284Y640144D01*
X-839504Y638324D01*
X-839309Y636244D01*
X-839504Y634164D01*
X-840284Y632344D01*
X-841454Y631304D01*
X-842624Y631044D01*
G01X-828039Y641444D02*
Y634164D01*
X-827259Y632344D01*
X-826089Y631304D01*
X-824724Y631044D01*
X-823359Y631304D01*
X-822189Y632344D01*
X-821409Y634164D01*
G01Y631044D02*
Y641444D01*
G01X-809554Y627144D02*
X-808189Y626104D01*
X-806629Y625844D01*
X-805264Y626104D01*
X-804094Y627404D01*
X-803314Y629224D01*
Y641444D01*
G01Y639364D02*
X-804094Y640404D01*
X-805264Y641184D01*
X-806629Y641444D01*
X-808189Y640924D01*
X-809164Y639884D01*
X-809944Y638064D01*
X-810334Y636244D01*
X-810139Y634684D01*
X-809359Y632864D01*
X-808189Y631564D01*
X-806629Y631044D01*
X-805459Y631304D01*
X-804094Y632344D01*
X-803314Y633384D01*
G01X-792239Y631044D02*
Y646644D01*
G01Y639104D02*
X-791264Y640404D01*
X-790289Y641184D01*
X-788729Y641444D01*
X-787559Y641184D01*
X-786194Y640144D01*
X-785609Y638584D01*
Y631044D01*
G01X-756439D02*
Y646644D01*
G01Y639104D02*
X-755464Y640404D01*
X-754489Y641184D01*
X-752929Y641444D01*
X-751759Y641184D01*
X-750394Y640144D01*
X-749809Y638584D01*
Y631044D01*
G01X-735224D02*
X-736394Y631304D01*
X-737564Y632344D01*
X-738344Y634164D01*
X-738734Y636244D01*
X-738344Y638324D01*
X-737564Y640144D01*
X-736394Y641184D01*
X-735224Y641444D01*
X-734054Y641184D01*
X-732884Y640144D01*
X-732104Y638324D01*
X-731909Y636244D01*
X-732104Y634164D01*
X-732884Y632344D01*
X-734054Y631304D01*
X-735224Y631044D01*
G01X-717324D02*
Y646644D01*
G01X-702349Y638064D02*
X-696109D01*
X-696694Y639884D01*
X-697669Y640924D01*
X-699034Y641444D01*
X-700399Y641184D01*
X-701569Y640404D01*
X-702349Y638584D01*
X-702739Y637024D01*
Y635464D01*
X-702349Y633904D01*
X-701374Y632344D01*
X-700204Y631304D01*
X-698839Y631044D01*
X-697474Y631564D01*
X-696109Y633124D01*
G01X-684449Y632864D02*
X-683474Y631824D01*
X-682109Y631044D01*
X-680939D01*
X-679769Y631564D01*
X-678989Y632344D01*
X-678599Y633384D01*
X-678794Y634944D01*
X-679574Y635724D01*
X-683084Y637284D01*
X-683864Y639104D01*
X-683474Y640404D01*
X-682694Y641184D01*
X-681524Y641444D01*
X-680354Y641184D01*
X-679184Y640404D01*
G01X-648649Y632864D02*
X-647674Y631824D01*
X-646309Y631044D01*
X-645139D01*
X-643969Y631564D01*
X-643189Y632344D01*
X-642799Y633384D01*
X-642994Y634944D01*
X-643774Y635724D01*
X-647284Y637284D01*
X-648064Y639104D01*
X-647674Y640404D01*
X-646894Y641184D01*
X-645724Y641444D01*
X-644554Y641184D01*
X-643384Y640404D01*
G01X-631139Y631044D02*
Y646644D01*
G01Y639104D02*
X-630164Y640404D01*
X-629189Y641184D01*
X-627629Y641444D01*
X-626459Y641184D01*
X-625094Y640144D01*
X-624509Y638584D01*
Y631044D01*
G01X-606414D02*
Y641444D01*
G01Y639624D02*
X-607194Y640664D01*
X-608364Y641184D01*
X-609729Y641444D01*
X-611094Y640924D01*
X-612264Y639884D01*
X-613044Y638324D01*
X-613434Y636244D01*
X-613044Y634164D01*
X-612264Y632604D01*
X-611094Y631564D01*
X-609729Y631044D01*
X-608364Y631304D01*
X-607194Y632084D01*
X-606414Y633124D01*
G01X-592024Y631044D02*
Y646644D01*
G01X-574124Y631044D02*
Y646644D01*
G01X-2080454Y695144D02*
X-2079089Y694104D01*
X-2077529Y693844D01*
X-2076164Y694104D01*
X-2074994Y695404D01*
X-2074214Y697224D01*
Y709444D01*
G01Y707364D02*
X-2074994Y708404D01*
X-2076164Y709184D01*
X-2077529Y709444D01*
X-2079089Y708924D01*
X-2080064Y707884D01*
X-2080844Y706064D01*
X-2081234Y704244D01*
X-2081039Y702684D01*
X-2080259Y700864D01*
X-2079089Y699564D01*
X-2077529Y699044D01*
X-2076359Y699304D01*
X-2074994Y700344D01*
X-2074214Y701384D01*
G01X-2059824Y698524D02*
X-2060214Y698784D01*
Y699304D01*
X-2059824Y699564D01*
X-2059434Y699304D01*
Y698784D01*
X-2059824Y698524D01*
G01X-2024024Y714644D02*
Y699044D01*
G01X-2028509Y714644D02*
X-2019539D01*
G01X-2009439Y699044D02*
Y714644D01*
G01Y707104D02*
X-2008464Y708404D01*
X-2007489Y709184D01*
X-2005929Y709444D01*
X-2004759Y709184D01*
X-2003394Y708144D01*
X-2002809Y706584D01*
Y699044D01*
G01X-1988224Y709444D02*
Y699044D01*
G01Y713604D02*
X-1988614Y713864D01*
Y714384D01*
X-1988224Y714644D01*
X-1987834Y714384D01*
Y713864D01*
X-1988224Y713604D01*
G01X-1973249Y706064D02*
X-1967009D01*
X-1967594Y707884D01*
X-1968569Y708924D01*
X-1969934Y709444D01*
X-1971299Y709184D01*
X-1972469Y708404D01*
X-1973249Y706584D01*
X-1973639Y705024D01*
Y703464D01*
X-1973249Y701904D01*
X-1972274Y700344D01*
X-1971104Y699304D01*
X-1969739Y699044D01*
X-1968374Y699564D01*
X-1967009Y701124D01*
G01X-1955934Y709444D02*
X-1952424Y699044D01*
X-1948914Y709444D01*
G01X-1934524D02*
Y699044D01*
G01Y713604D02*
X-1934914Y713864D01*
Y714384D01*
X-1934524Y714644D01*
X-1934134Y714384D01*
Y713864D01*
X-1934524Y713604D01*
G01X-1919939Y699044D02*
Y709444D01*
G01Y706844D02*
X-1919159Y708144D01*
X-1917989Y709184D01*
X-1916429Y709444D01*
X-1915064Y709184D01*
X-1913894Y708144D01*
X-1913309Y706324D01*
Y699044D01*
G01X-1901454Y695144D02*
X-1900089Y694104D01*
X-1898529Y693844D01*
X-1897164Y694104D01*
X-1895994Y695404D01*
X-1895214Y697224D01*
Y709444D01*
G01Y707364D02*
X-1895994Y708404D01*
X-1897164Y709184D01*
X-1898529Y709444D01*
X-1900089Y708924D01*
X-1901064Y707884D01*
X-1901844Y706064D01*
X-1902234Y704244D01*
X-1902039Y702684D01*
X-1901259Y700864D01*
X-1900089Y699564D01*
X-1898529Y699044D01*
X-1897359Y699304D01*
X-1895994Y700344D01*
X-1895214Y701384D01*
G01X-1862924Y709444D02*
Y699044D01*
G01Y713604D02*
X-1863314Y713864D01*
Y714384D01*
X-1862924Y714644D01*
X-1862534Y714384D01*
Y713864D01*
X-1862924Y713604D01*
G01X-1847949Y700864D02*
X-1846974Y699824D01*
X-1845609Y699044D01*
X-1844439D01*
X-1843269Y699564D01*
X-1842489Y700344D01*
X-1842099Y701384D01*
X-1842294Y702944D01*
X-1843074Y703724D01*
X-1846584Y705284D01*
X-1847364Y707104D01*
X-1846974Y708404D01*
X-1846194Y709184D01*
X-1845024Y709444D01*
X-1843854Y709184D01*
X-1842684Y708404D01*
G01X-1805714Y699044D02*
Y709444D01*
G01Y707624D02*
X-1806494Y708664D01*
X-1807664Y709184D01*
X-1809029Y709444D01*
X-1810394Y708924D01*
X-1811564Y707884D01*
X-1812344Y706324D01*
X-1812734Y704244D01*
X-1812344Y702164D01*
X-1811564Y700604D01*
X-1810394Y699564D01*
X-1809029Y699044D01*
X-1807664Y699304D01*
X-1806494Y700084D01*
X-1805714Y701124D01*
G01X-1791324Y699044D02*
Y714644D01*
G01X-1773424Y699044D02*
Y714644D01*
G01X-1755524Y699044D02*
X-1756694Y699304D01*
X-1757864Y700344D01*
X-1758644Y702164D01*
X-1759034Y704244D01*
X-1758644Y706324D01*
X-1757864Y708144D01*
X-1756694Y709184D01*
X-1755524Y709444D01*
X-1754354Y709184D01*
X-1753184Y708144D01*
X-1752404Y706324D01*
X-1752209Y704244D01*
X-1752404Y702164D01*
X-1753184Y700344D01*
X-1754354Y699304D01*
X-1755524Y699044D01*
G01X-1742499Y709444D02*
X-1740159Y699044D01*
X-1737624Y709444D01*
X-1735089Y699044D01*
X-1732749Y709444D01*
G01X-1722649Y706064D02*
X-1716409D01*
X-1716994Y707884D01*
X-1717969Y708924D01*
X-1719334Y709444D01*
X-1720699Y709184D01*
X-1721869Y708404D01*
X-1722649Y706584D01*
X-1723039Y705024D01*
Y703464D01*
X-1722649Y701904D01*
X-1721674Y700344D01*
X-1720504Y699304D01*
X-1719139Y699044D01*
X-1717774Y699564D01*
X-1716409Y701124D01*
G01X-1698314Y714644D02*
Y699044D01*
G01Y701384D02*
X-1699094Y700084D01*
X-1700264Y699304D01*
X-1701629Y699044D01*
X-1703189Y699564D01*
X-1704359Y700864D01*
X-1705139Y702424D01*
X-1705334Y704244D01*
X-1705139Y706064D01*
X-1704359Y707624D01*
X-1703189Y708924D01*
X-1701629Y709444D01*
X-1700264Y709184D01*
X-1699289Y708664D01*
X-1698314Y707624D01*
G01X-1662514Y699044D02*
Y709444D01*
G01Y707624D02*
X-1663294Y708664D01*
X-1664464Y709184D01*
X-1665829Y709444D01*
X-1667194Y708924D01*
X-1668364Y707884D01*
X-1669144Y706324D01*
X-1669534Y704244D01*
X-1669144Y702164D01*
X-1668364Y700604D01*
X-1667194Y699564D01*
X-1665829Y699044D01*
X-1664464Y699304D01*
X-1663294Y700084D01*
X-1662514Y701124D01*
G01X-1648124Y699044D02*
Y714644D01*
G01X-1630224Y699044D02*
Y714644D01*
G01X-1594424Y699044D02*
Y714644D01*
G01X-1573014Y699044D02*
Y709444D01*
G01Y707624D02*
X-1573794Y708664D01*
X-1574964Y709184D01*
X-1576329Y709444D01*
X-1577694Y708924D01*
X-1578864Y707884D01*
X-1579644Y706324D01*
X-1580034Y704244D01*
X-1579644Y702164D01*
X-1578864Y700604D01*
X-1577694Y699564D01*
X-1576329Y699044D01*
X-1574964Y699304D01*
X-1573794Y700084D01*
X-1573014Y701124D01*
G01X-1562719Y694364D02*
X-1561549Y693844D01*
X-1559989Y694364D01*
X-1559014Y695404D01*
X-1558234Y696704D01*
X-1557064Y700864D01*
X-1554529Y709444D01*
G01X-1560769D02*
X-1557064Y700864D01*
G01X-1543649Y706064D02*
X-1537409D01*
X-1537994Y707884D01*
X-1538969Y708924D01*
X-1540334Y709444D01*
X-1541699Y709184D01*
X-1542869Y708404D01*
X-1543649Y706584D01*
X-1544039Y705024D01*
Y703464D01*
X-1543649Y701904D01*
X-1542674Y700344D01*
X-1541504Y699304D01*
X-1540139Y699044D01*
X-1538774Y699564D01*
X-1537409Y701124D01*
G01X-1525554Y699044D02*
Y709444D01*
G01Y707364D02*
X-1524579Y708404D01*
X-1523604Y709184D01*
X-1522239Y709444D01*
X-1521264Y709184D01*
X-1520094Y708404D01*
G01X-1507849Y700864D02*
X-1506874Y699824D01*
X-1505509Y699044D01*
X-1504339D01*
X-1503169Y699564D01*
X-1502389Y700344D01*
X-1501999Y701384D01*
X-1502194Y702944D01*
X-1502974Y703724D01*
X-1506484Y705284D01*
X-1507264Y707104D01*
X-1506874Y708404D01*
X-1506094Y709184D01*
X-1504924Y709444D01*
X-1503754Y709184D01*
X-1502584Y708404D01*
G01X-1473999Y709444D02*
X-1471659Y699044D01*
X-1469124Y709444D01*
X-1466589Y699044D01*
X-1464249Y709444D01*
G01X-1451224D02*
Y699044D01*
G01Y713604D02*
X-1451614Y713864D01*
Y714384D01*
X-1451224Y714644D01*
X-1450834Y714384D01*
Y713864D01*
X-1451224Y713604D01*
G01X-1433324Y714644D02*
Y699044D01*
G01X-1436054Y709444D02*
X-1430594D01*
G01X-1418739Y699044D02*
Y714644D01*
G01Y707104D02*
X-1417764Y708404D01*
X-1416789Y709184D01*
X-1415229Y709444D01*
X-1414059Y709184D01*
X-1412694Y708144D01*
X-1412109Y706584D01*
Y699044D01*
G01X-1379624Y714644D02*
X-1381184Y714124D01*
X-1382354Y712824D01*
X-1383134Y711264D01*
X-1383719Y709184D01*
X-1383914Y706844D01*
X-1383719Y704504D01*
X-1383134Y702424D01*
X-1382354Y700864D01*
X-1381184Y699564D01*
X-1379624Y699044D01*
X-1378064Y699564D01*
X-1376894Y700864D01*
X-1376114Y702424D01*
X-1375529Y704504D01*
X-1375334Y706844D01*
X-1375529Y709184D01*
X-1376114Y711264D01*
X-1376894Y712824D01*
X-1378064Y714124D01*
X-1379624Y714644D01*
G01X-1361724Y698524D02*
X-1362114Y698784D01*
Y699304D01*
X-1361724Y699564D01*
X-1361334Y699304D01*
Y698784D01*
X-1361724Y698524D01*
G01X-1343824Y714644D02*
X-1345384Y714124D01*
X-1346554Y712824D01*
X-1347334Y711264D01*
X-1347919Y709184D01*
X-1348114Y706844D01*
X-1347919Y704504D01*
X-1347334Y702424D01*
X-1346554Y700864D01*
X-1345384Y699564D01*
X-1343824Y699044D01*
X-1342264Y699564D01*
X-1341094Y700864D01*
X-1340314Y702424D01*
X-1339729Y704504D01*
X-1339534Y706844D01*
X-1339729Y709184D01*
X-1340314Y711264D01*
X-1341094Y712824D01*
X-1342264Y714124D01*
X-1343824Y714644D01*
G01X-1330214Y701384D02*
X-1329044Y700084D01*
X-1327679Y699304D01*
X-1325924Y699044D01*
X-1324169Y699564D01*
X-1322804Y700604D01*
X-1321829Y702424D01*
X-1321634Y704504D01*
X-1322024Y706584D01*
X-1322999Y707884D01*
X-1324364Y708924D01*
X-1325729Y709184D01*
X-1327094Y708924D01*
X-1328849Y707884D01*
X-1328264Y714644D01*
X-1322999D01*
G01X-1308024D02*
X-1309584Y714124D01*
X-1310754Y712824D01*
X-1311534Y711264D01*
X-1312119Y709184D01*
X-1312314Y706844D01*
X-1312119Y704504D01*
X-1311534Y702424D01*
X-1310754Y700864D01*
X-1309584Y699564D01*
X-1308024Y699044D01*
X-1306464Y699564D01*
X-1305294Y700864D01*
X-1304514Y702424D01*
X-1303929Y704504D01*
X-1303734Y706844D01*
X-1303929Y709184D01*
X-1304514Y711264D01*
X-1305294Y712824D01*
X-1306464Y714124D01*
X-1308024Y714644D01*
G01X-1291879Y711264D02*
X-1290904Y714644D01*
G01X-1288369D02*
X-1289344Y711264D01*
G01X-1257249Y700864D02*
X-1256274Y699824D01*
X-1254909Y699044D01*
X-1253739D01*
X-1252569Y699564D01*
X-1251789Y700344D01*
X-1251399Y701384D01*
X-1251594Y702944D01*
X-1252374Y703724D01*
X-1255884Y705284D01*
X-1256664Y707104D01*
X-1256274Y708404D01*
X-1255494Y709184D01*
X-1254324Y709444D01*
X-1253154Y709184D01*
X-1251984Y708404D01*
G01X-1232914Y693844D02*
Y709444D01*
G01Y707104D02*
X-1233889Y708404D01*
X-1235059Y709184D01*
X-1236424Y709444D01*
X-1237594Y709184D01*
X-1238959Y707884D01*
X-1239739Y706064D01*
X-1239934Y704244D01*
X-1239739Y702424D01*
X-1238959Y700604D01*
X-1237594Y699304D01*
X-1236424Y699044D01*
X-1235059Y699304D01*
X-1233889Y700084D01*
X-1232914Y701384D01*
G01X-1221839Y709444D02*
Y702164D01*
X-1221059Y700344D01*
X-1219889Y699304D01*
X-1218524Y699044D01*
X-1217159Y699304D01*
X-1215989Y700344D01*
X-1215209Y702164D01*
G01Y699044D02*
Y709444D01*
G01X-1197114Y699044D02*
Y709444D01*
G01Y707624D02*
X-1197894Y708664D01*
X-1199064Y709184D01*
X-1200429Y709444D01*
X-1201794Y708924D01*
X-1202964Y707884D01*
X-1203744Y706324D01*
X-1204134Y704244D01*
X-1203744Y702164D01*
X-1202964Y700604D01*
X-1201794Y699564D01*
X-1200429Y699044D01*
X-1199064Y699304D01*
X-1197894Y700084D01*
X-1197114Y701124D01*
G01X-1185454Y699044D02*
Y709444D01*
G01Y707364D02*
X-1184479Y708404D01*
X-1183504Y709184D01*
X-1182139Y709444D01*
X-1181164Y709184D01*
X-1179994Y708404D01*
G01X-1167749Y706064D02*
X-1161509D01*
X-1162094Y707884D01*
X-1163069Y708924D01*
X-1164434Y709444D01*
X-1165799Y709184D01*
X-1166969Y708404D01*
X-1167749Y706584D01*
X-1168139Y705024D01*
Y703464D01*
X-1167749Y701904D01*
X-1166774Y700344D01*
X-1165604Y699304D01*
X-1164239Y699044D01*
X-1162874Y699564D01*
X-1161509Y701124D01*
G01X-1149849Y700864D02*
X-1148874Y699824D01*
X-1147509Y699044D01*
X-1146339D01*
X-1145169Y699564D01*
X-1144389Y700344D01*
X-1143999Y701384D01*
X-1144194Y702944D01*
X-1144974Y703724D01*
X-1148484Y705284D01*
X-1149264Y707104D01*
X-1148874Y708404D01*
X-1148094Y709184D01*
X-1146924Y709444D01*
X-1145754Y709184D01*
X-1144584Y708404D01*
G01X-1111124Y699044D02*
X-1112294Y699304D01*
X-1113464Y700344D01*
X-1114244Y702164D01*
X-1114634Y704244D01*
X-1114244Y706324D01*
X-1113464Y708144D01*
X-1112294Y709184D01*
X-1111124Y709444D01*
X-1109954Y709184D01*
X-1108784Y708144D01*
X-1108004Y706324D01*
X-1107809Y704244D01*
X-1108004Y702164D01*
X-1108784Y700344D01*
X-1109954Y699304D01*
X-1111124Y699044D01*
G01X-1096539D02*
Y709444D01*
G01Y706844D02*
X-1095759Y708144D01*
X-1094589Y709184D01*
X-1093029Y709444D01*
X-1091664Y709184D01*
X-1090494Y708144D01*
X-1089909Y706324D01*
Y699044D01*
G01X-1057424Y714644D02*
X-1058984Y714124D01*
X-1060154Y712824D01*
X-1060934Y711264D01*
X-1061519Y709184D01*
X-1061714Y706844D01*
X-1061519Y704504D01*
X-1060934Y702424D01*
X-1060154Y700864D01*
X-1058984Y699564D01*
X-1057424Y699044D01*
X-1055864Y699564D01*
X-1054694Y700864D01*
X-1053914Y702424D01*
X-1053329Y704504D01*
X-1053134Y706844D01*
X-1053329Y709184D01*
X-1053914Y711264D01*
X-1054694Y712824D01*
X-1055864Y714124D01*
X-1057424Y714644D01*
G01X-1039524Y698524D02*
X-1039914Y698784D01*
Y699304D01*
X-1039524Y699564D01*
X-1039134Y699304D01*
Y698784D01*
X-1039524Y698524D01*
G01X-1021624Y699044D02*
Y714644D01*
X-1023964Y711524D01*
G01Y699044D02*
X-1019284D01*
G01X-1003724Y714644D02*
X-1005284Y714124D01*
X-1006454Y712824D01*
X-1007234Y711264D01*
X-1007819Y709184D01*
X-1008014Y706844D01*
X-1007819Y704504D01*
X-1007234Y702424D01*
X-1006454Y700864D01*
X-1005284Y699564D01*
X-1003724Y699044D01*
X-1002164Y699564D01*
X-1000994Y700864D01*
X-1000214Y702424D01*
X-999629Y704504D01*
X-999434Y706844D01*
X-999629Y709184D01*
X-1000214Y711264D01*
X-1000994Y712824D01*
X-1002164Y714124D01*
X-1003724Y714644D01*
G01X-985824D02*
X-987384Y714124D01*
X-988554Y712824D01*
X-989334Y711264D01*
X-989919Y709184D01*
X-990114Y706844D01*
X-989919Y704504D01*
X-989334Y702424D01*
X-988554Y700864D01*
X-987384Y699564D01*
X-985824Y699044D01*
X-984264Y699564D01*
X-983094Y700864D01*
X-982314Y702424D01*
X-981729Y704504D01*
X-981534Y706844D01*
X-981729Y709184D01*
X-982314Y711264D01*
X-983094Y712824D01*
X-984264Y714124D01*
X-985824Y714644D01*
G01X-969679Y711264D02*
X-968704Y714644D01*
G01X-966169D02*
X-967144Y711264D01*
G01X-935634Y693844D02*
Y709444D01*
G01Y707104D02*
X-934659Y708404D01*
X-933684Y709184D01*
X-932124Y709444D01*
X-930759Y709184D01*
X-929394Y707884D01*
X-928809Y706064D01*
X-928614Y704244D01*
X-928809Y702424D01*
X-929394Y700604D01*
X-930564Y699564D01*
X-932124Y699044D01*
X-933489Y699304D01*
X-934854Y700084D01*
X-935634Y701124D01*
G01X-914224Y709444D02*
Y699044D01*
G01Y713604D02*
X-914614Y713864D01*
Y714384D01*
X-914224Y714644D01*
X-913834Y714384D01*
Y713864D01*
X-914224Y713604D01*
G01X-896324Y714644D02*
Y699044D01*
G01X-899054Y709444D02*
X-893594D01*
G01X-875304Y708144D02*
X-876669Y709184D01*
X-877839Y709444D01*
X-879399Y708924D01*
X-880569Y707884D01*
X-881349Y706064D01*
X-881544Y704244D01*
X-881349Y702424D01*
X-880569Y700864D01*
X-879399Y699564D01*
X-877839Y699044D01*
X-876474Y699564D01*
X-875304Y700604D01*
G01X-863839Y699044D02*
Y714644D01*
G01Y707104D02*
X-862864Y708404D01*
X-861889Y709184D01*
X-860329Y709444D01*
X-859159Y709184D01*
X-857794Y708144D01*
X-857209Y706584D01*
Y699044D01*
G01X-821214D02*
Y709444D01*
G01Y707624D02*
X-821994Y708664D01*
X-823164Y709184D01*
X-824529Y709444D01*
X-825894Y708924D01*
X-827064Y707884D01*
X-827844Y706324D01*
X-828234Y704244D01*
X-827844Y702164D01*
X-827064Y700604D01*
X-825894Y699564D01*
X-824529Y699044D01*
X-823164Y699304D01*
X-821994Y700084D01*
X-821214Y701124D01*
G01X-810139Y699044D02*
Y709444D01*
G01Y706844D02*
X-809359Y708144D01*
X-808189Y709184D01*
X-806629Y709444D01*
X-805264Y709184D01*
X-804094Y708144D01*
X-803509Y706324D01*
Y699044D01*
G01X-785414Y714644D02*
Y699044D01*
G01Y701384D02*
X-786194Y700084D01*
X-787364Y699304D01*
X-788729Y699044D01*
X-790289Y699564D01*
X-791459Y700864D01*
X-792239Y702424D01*
X-792434Y704244D01*
X-792239Y706064D01*
X-791459Y707624D01*
X-790289Y708924D01*
X-788729Y709444D01*
X-787364Y709184D01*
X-786389Y708664D01*
X-785414Y707624D01*
G01X-753124Y714644D02*
X-754684Y714124D01*
X-755854Y712824D01*
X-756634Y711264D01*
X-757219Y709184D01*
X-757414Y706844D01*
X-757219Y704504D01*
X-756634Y702424D01*
X-755854Y700864D01*
X-754684Y699564D01*
X-753124Y699044D01*
X-751564Y699564D01*
X-750394Y700864D01*
X-749614Y702424D01*
X-749029Y704504D01*
X-748834Y706844D01*
X-749029Y709184D01*
X-749614Y711264D01*
X-750394Y712824D01*
X-751564Y714124D01*
X-753124Y714644D01*
G01X-735614Y696184D02*
X-734834Y699564D01*
G01X-717324Y699044D02*
Y714644D01*
X-719664Y711524D01*
G01Y699044D02*
X-714984D01*
G01X-699424Y714644D02*
X-700984Y714124D01*
X-702154Y712824D01*
X-702934Y711264D01*
X-703519Y709184D01*
X-703714Y706844D01*
X-703519Y704504D01*
X-702934Y702424D01*
X-702154Y700864D01*
X-700984Y699564D01*
X-699424Y699044D01*
X-697864Y699564D01*
X-696694Y700864D01*
X-695914Y702424D01*
X-695329Y704504D01*
X-695134Y706844D01*
X-695329Y709184D01*
X-695914Y711264D01*
X-696694Y712824D01*
X-697864Y714124D01*
X-699424Y714644D01*
G01X-681524D02*
X-683084Y714124D01*
X-684254Y712824D01*
X-685034Y711264D01*
X-685619Y709184D01*
X-685814Y706844D01*
X-685619Y704504D01*
X-685034Y702424D01*
X-684254Y700864D01*
X-683084Y699564D01*
X-681524Y699044D01*
X-679964Y699564D01*
X-678794Y700864D01*
X-678014Y702424D01*
X-677429Y704504D01*
X-677234Y706844D01*
X-677429Y709184D01*
X-678014Y711264D01*
X-678794Y712824D01*
X-679964Y714124D01*
X-681524Y714644D01*
G01X-665379Y711264D02*
X-664404Y714644D01*
G01X-661869D02*
X-662844Y711264D01*
G01X-651574Y699044D02*
Y709444D01*
G01Y706584D02*
X-650989Y707884D01*
X-650014Y708924D01*
X-648649Y709444D01*
X-647284Y708924D01*
X-646309Y707884D01*
X-645724Y706584D01*
Y699044D01*
G01Y706584D02*
X-645139Y707884D01*
X-644164Y708924D01*
X-642799Y709444D01*
X-641434Y708924D01*
X-640459Y707884D01*
X-639874Y706324D01*
Y699044D01*
G01X-627824Y709444D02*
Y699044D01*
G01Y713604D02*
X-628214Y713864D01*
Y714384D01*
X-627824Y714644D01*
X-627434Y714384D01*
Y713864D01*
X-627824Y713604D01*
G01X-613239Y699044D02*
Y709444D01*
G01Y706844D02*
X-612459Y708144D01*
X-611289Y709184D01*
X-609729Y709444D01*
X-608364Y709184D01*
X-607194Y708144D01*
X-606609Y706324D01*
Y699044D01*
G01X-2078894Y767044D02*
Y780304D01*
X-2078504Y781604D01*
X-2077724Y782384D01*
X-2076554Y782644D01*
X-2075384Y782124D01*
X-2074799Y780824D01*
G01X-2077139Y776404D02*
X-2081039D01*
G01X-2059824Y766524D02*
X-2060214Y766784D01*
Y767304D01*
X-2059824Y767564D01*
X-2059434Y767304D01*
Y766784D01*
X-2059824Y766524D01*
G01X-2027924Y767044D02*
Y782644D01*
X-2023244D01*
X-2021684Y781864D01*
X-2020514Y780044D01*
X-2020124Y777964D01*
X-2020514Y775884D01*
X-2021489Y774324D01*
X-2023244Y773544D01*
X-2027924D01*
G01X-2001834Y781344D02*
X-2003004Y782124D01*
X-2004369Y782644D01*
X-2005929D01*
X-2007684Y781864D01*
X-2009049Y780564D01*
X-2010024Y779004D01*
X-2010804Y776404D01*
X-2010999Y774064D01*
X-2010609Y771724D01*
X-2010024Y770164D01*
X-2008854Y768604D01*
X-2007489Y767564D01*
X-2006124Y767044D01*
X-2004759D01*
X-2003394Y767564D01*
X-2002224Y768344D01*
X-2001249Y769384D01*
G01X-1986664Y775364D02*
X-1985884Y776144D01*
X-1985299Y777444D01*
X-1984909Y779264D01*
X-1985299Y780824D01*
X-1986079Y781864D01*
X-1987444Y782644D01*
X-1992709D01*
Y767044D01*
X-1986274D01*
X-1984909Y768084D01*
X-1984129Y769644D01*
X-1983739Y771464D01*
X-1984129Y773284D01*
X-1985299Y774844D01*
X-1986664Y775364D01*
X-1992709D01*
G01X-1953594Y767044D02*
Y780304D01*
X-1953204Y781604D01*
X-1952424Y782384D01*
X-1951254Y782644D01*
X-1950084Y782124D01*
X-1949499Y780824D01*
G01X-1951839Y776404D02*
X-1955739D01*
G01X-1931014Y767044D02*
Y777444D01*
G01Y775624D02*
X-1931794Y776664D01*
X-1932964Y777184D01*
X-1934329Y777444D01*
X-1935694Y776924D01*
X-1936864Y775884D01*
X-1937644Y774324D01*
X-1938034Y772244D01*
X-1937644Y770164D01*
X-1936864Y768604D01*
X-1935694Y767564D01*
X-1934329Y767044D01*
X-1932964Y767304D01*
X-1931794Y768084D01*
X-1931014Y769124D01*
G01X-1920134Y767044D02*
Y782644D01*
G01Y774844D02*
X-1919159Y776404D01*
X-1917989Y777184D01*
X-1916819Y777444D01*
X-1915064Y776924D01*
X-1913894Y775884D01*
X-1913114Y774064D01*
Y771984D01*
X-1913504Y769904D01*
X-1914284Y768344D01*
X-1915649Y767304D01*
X-1916819Y767044D01*
X-1917989Y767304D01*
X-1919159Y768084D01*
X-1920134Y769384D01*
G01X-1901454Y767044D02*
Y777444D01*
G01Y775364D02*
X-1900479Y776404D01*
X-1899504Y777184D01*
X-1898139Y777444D01*
X-1897164Y777184D01*
X-1895994Y776404D01*
G01X-1880824Y777444D02*
Y767044D01*
G01Y781604D02*
X-1881214Y781864D01*
Y782384D01*
X-1880824Y782644D01*
X-1880434Y782384D01*
Y781864D01*
X-1880824Y781604D01*
G01X-1859804Y776144D02*
X-1861169Y777184D01*
X-1862339Y777444D01*
X-1863899Y776924D01*
X-1865069Y775884D01*
X-1865849Y774064D01*
X-1866044Y772244D01*
X-1865849Y770424D01*
X-1865069Y768864D01*
X-1863899Y767564D01*
X-1862339Y767044D01*
X-1860974Y767564D01*
X-1859804Y768604D01*
G01X-1841514Y767044D02*
Y777444D01*
G01Y775624D02*
X-1842294Y776664D01*
X-1843464Y777184D01*
X-1844829Y777444D01*
X-1846194Y776924D01*
X-1847364Y775884D01*
X-1848144Y774324D01*
X-1848534Y772244D01*
X-1848144Y770164D01*
X-1847364Y768604D01*
X-1846194Y767564D01*
X-1844829Y767044D01*
X-1843464Y767304D01*
X-1842294Y768084D01*
X-1841514Y769124D01*
G01X-1827124Y782644D02*
Y767044D01*
G01X-1829854Y777444D02*
X-1824394D01*
G01X-1809224D02*
Y767044D01*
G01Y781604D02*
X-1809614Y781864D01*
Y782384D01*
X-1809224Y782644D01*
X-1808834Y782384D01*
Y781864D01*
X-1809224Y781604D01*
G01X-1791324Y767044D02*
X-1792494Y767304D01*
X-1793664Y768344D01*
X-1794444Y770164D01*
X-1794834Y772244D01*
X-1794444Y774324D01*
X-1793664Y776144D01*
X-1792494Y777184D01*
X-1791324Y777444D01*
X-1790154Y777184D01*
X-1788984Y776144D01*
X-1788204Y774324D01*
X-1788009Y772244D01*
X-1788204Y770164D01*
X-1788984Y768344D01*
X-1790154Y767304D01*
X-1791324Y767044D01*
G01X-1776739D02*
Y777444D01*
G01Y774844D02*
X-1775959Y776144D01*
X-1774789Y777184D01*
X-1773229Y777444D01*
X-1771864Y777184D01*
X-1770694Y776144D01*
X-1770109Y774324D01*
Y767044D01*
G01X-1741134Y761844D02*
Y777444D01*
G01Y775104D02*
X-1740159Y776404D01*
X-1739184Y777184D01*
X-1737624Y777444D01*
X-1736259Y777184D01*
X-1734894Y775884D01*
X-1734309Y774064D01*
X-1734114Y772244D01*
X-1734309Y770424D01*
X-1734894Y768604D01*
X-1736064Y767564D01*
X-1737624Y767044D01*
X-1738989Y767304D01*
X-1740354Y768084D01*
X-1741134Y769124D01*
G01X-1722454Y767044D02*
Y777444D01*
G01Y775364D02*
X-1721479Y776404D01*
X-1720504Y777184D01*
X-1719139Y777444D01*
X-1718164Y777184D01*
X-1716994Y776404D01*
G01X-1701824Y767044D02*
X-1702994Y767304D01*
X-1704164Y768344D01*
X-1704944Y770164D01*
X-1705334Y772244D01*
X-1704944Y774324D01*
X-1704164Y776144D01*
X-1702994Y777184D01*
X-1701824Y777444D01*
X-1700654Y777184D01*
X-1699484Y776144D01*
X-1698704Y774324D01*
X-1698509Y772244D01*
X-1698704Y770164D01*
X-1699484Y768344D01*
X-1700654Y767304D01*
X-1701824Y767044D01*
G01X-1680804Y776144D02*
X-1682169Y777184D01*
X-1683339Y777444D01*
X-1684899Y776924D01*
X-1686069Y775884D01*
X-1686849Y774064D01*
X-1687044Y772244D01*
X-1686849Y770424D01*
X-1686069Y768864D01*
X-1684899Y767564D01*
X-1683339Y767044D01*
X-1681974Y767564D01*
X-1680804Y768604D01*
G01X-1668949Y774064D02*
X-1662709D01*
X-1663294Y775884D01*
X-1664269Y776924D01*
X-1665634Y777444D01*
X-1666999Y777184D01*
X-1668169Y776404D01*
X-1668949Y774584D01*
X-1669339Y773024D01*
Y771464D01*
X-1668949Y769904D01*
X-1667974Y768344D01*
X-1666804Y767304D01*
X-1665439Y767044D01*
X-1664074Y767564D01*
X-1662709Y769124D01*
G01X-1651049Y768864D02*
X-1650074Y767824D01*
X-1648709Y767044D01*
X-1647539D01*
X-1646369Y767564D01*
X-1645589Y768344D01*
X-1645199Y769384D01*
X-1645394Y770944D01*
X-1646174Y771724D01*
X-1649684Y773284D01*
X-1650464Y775104D01*
X-1650074Y776404D01*
X-1649294Y777184D01*
X-1648124Y777444D01*
X-1646954Y777184D01*
X-1645784Y776404D01*
G01X-1633149Y768864D02*
X-1632174Y767824D01*
X-1630809Y767044D01*
X-1629639D01*
X-1628469Y767564D01*
X-1627689Y768344D01*
X-1627299Y769384D01*
X-1627494Y770944D01*
X-1628274Y771724D01*
X-1631784Y773284D01*
X-1632564Y775104D01*
X-1632174Y776404D01*
X-1631394Y777184D01*
X-1630224Y777444D01*
X-1629054Y777184D01*
X-1627884Y776404D01*
G01X-1590914Y767044D02*
Y777444D01*
G01Y775624D02*
X-1591694Y776664D01*
X-1592864Y777184D01*
X-1594229Y777444D01*
X-1595594Y776924D01*
X-1596764Y775884D01*
X-1597544Y774324D01*
X-1597934Y772244D01*
X-1597544Y770164D01*
X-1596764Y768604D01*
X-1595594Y767564D01*
X-1594229Y767044D01*
X-1592864Y767304D01*
X-1591694Y768084D01*
X-1590914Y769124D01*
G01X-1579839Y767044D02*
Y777444D01*
G01Y774844D02*
X-1579059Y776144D01*
X-1577889Y777184D01*
X-1576329Y777444D01*
X-1574964Y777184D01*
X-1573794Y776144D01*
X-1573209Y774324D01*
Y767044D01*
G01X-1555114Y782644D02*
Y767044D01*
G01Y769384D02*
X-1555894Y768084D01*
X-1557064Y767304D01*
X-1558429Y767044D01*
X-1559989Y767564D01*
X-1561159Y768864D01*
X-1561939Y770424D01*
X-1562134Y772244D01*
X-1561939Y774064D01*
X-1561159Y775624D01*
X-1559989Y776924D01*
X-1558429Y777444D01*
X-1557064Y777184D01*
X-1556089Y776664D01*
X-1555114Y775624D01*
G01X-1528674Y767044D02*
Y777444D01*
G01Y774584D02*
X-1528089Y775884D01*
X-1527114Y776924D01*
X-1525749Y777444D01*
X-1524384Y776924D01*
X-1523409Y775884D01*
X-1522824Y774584D01*
Y767044D01*
G01Y774584D02*
X-1522239Y775884D01*
X-1521264Y776924D01*
X-1519899Y777444D01*
X-1518534Y776924D01*
X-1517559Y775884D01*
X-1516974Y774324D01*
Y767044D01*
G01X-1501414D02*
Y777444D01*
G01Y775624D02*
X-1502194Y776664D01*
X-1503364Y777184D01*
X-1504729Y777444D01*
X-1506094Y776924D01*
X-1507264Y775884D01*
X-1508044Y774324D01*
X-1508434Y772244D01*
X-1508044Y770164D01*
X-1507264Y768604D01*
X-1506094Y767564D01*
X-1504729Y767044D01*
X-1503364Y767304D01*
X-1502194Y768084D01*
X-1501414Y769124D01*
G01X-1487024Y782644D02*
Y767044D01*
G01X-1489754Y777444D02*
X-1484294D01*
G01X-1472049Y774064D02*
X-1465809D01*
X-1466394Y775884D01*
X-1467369Y776924D01*
X-1468734Y777444D01*
X-1470099Y777184D01*
X-1471269Y776404D01*
X-1472049Y774584D01*
X-1472439Y773024D01*
Y771464D01*
X-1472049Y769904D01*
X-1471074Y768344D01*
X-1469904Y767304D01*
X-1468539Y767044D01*
X-1467174Y767564D01*
X-1465809Y769124D01*
G01X-1453954Y767044D02*
Y777444D01*
G01Y775364D02*
X-1452979Y776404D01*
X-1452004Y777184D01*
X-1450639Y777444D01*
X-1449664Y777184D01*
X-1448494Y776404D01*
G01X-1433324Y777444D02*
Y767044D01*
G01Y781604D02*
X-1433714Y781864D01*
Y782384D01*
X-1433324Y782644D01*
X-1432934Y782384D01*
Y781864D01*
X-1433324Y781604D01*
G01X-1411914Y767044D02*
Y777444D01*
G01Y775624D02*
X-1412694Y776664D01*
X-1413864Y777184D01*
X-1415229Y777444D01*
X-1416594Y776924D01*
X-1417764Y775884D01*
X-1418544Y774324D01*
X-1418934Y772244D01*
X-1418544Y770164D01*
X-1417764Y768604D01*
X-1416594Y767564D01*
X-1415229Y767044D01*
X-1413864Y767304D01*
X-1412694Y768084D01*
X-1411914Y769124D01*
G01X-1397524Y767044D02*
Y782644D01*
G01X-1382549Y768864D02*
X-1381574Y767824D01*
X-1380209Y767044D01*
X-1379039D01*
X-1377869Y767564D01*
X-1377089Y768344D01*
X-1376699Y769384D01*
X-1376894Y770944D01*
X-1377674Y771724D01*
X-1381184Y773284D01*
X-1381964Y775104D01*
X-1381574Y776404D01*
X-1380794Y777184D01*
X-1379624Y777444D01*
X-1378454Y777184D01*
X-1377284Y776404D01*
G01X-1349674Y767044D02*
Y777444D01*
G01Y774584D02*
X-1349089Y775884D01*
X-1348114Y776924D01*
X-1346749Y777444D01*
X-1345384Y776924D01*
X-1344409Y775884D01*
X-1343824Y774584D01*
Y767044D01*
G01Y774584D02*
X-1343239Y775884D01*
X-1342264Y776924D01*
X-1340899Y777444D01*
X-1339534Y776924D01*
X-1338559Y775884D01*
X-1337974Y774324D01*
Y767044D01*
G01X-1329239Y777444D02*
Y770164D01*
X-1328459Y768344D01*
X-1327289Y767304D01*
X-1325924Y767044D01*
X-1324559Y767304D01*
X-1323389Y768344D01*
X-1322609Y770164D01*
G01Y767044D02*
Y777444D01*
G01X-1310949Y768864D02*
X-1309974Y767824D01*
X-1308609Y767044D01*
X-1307439D01*
X-1306269Y767564D01*
X-1305489Y768344D01*
X-1305099Y769384D01*
X-1305294Y770944D01*
X-1306074Y771724D01*
X-1309584Y773284D01*
X-1310364Y775104D01*
X-1309974Y776404D01*
X-1309194Y777184D01*
X-1308024Y777444D01*
X-1306854Y777184D01*
X-1305684Y776404D01*
G01X-1290124Y782644D02*
Y767044D01*
G01X-1292854Y777444D02*
X-1287394D01*
G01X-1257834Y767044D02*
Y782644D01*
G01Y774844D02*
X-1256859Y776404D01*
X-1255689Y777184D01*
X-1254519Y777444D01*
X-1252764Y776924D01*
X-1251594Y775884D01*
X-1250814Y774064D01*
Y771984D01*
X-1251204Y769904D01*
X-1251984Y768344D01*
X-1253349Y767304D01*
X-1254519Y767044D01*
X-1255689Y767304D01*
X-1256859Y768084D01*
X-1257834Y769384D01*
G01X-1239349Y774064D02*
X-1233109D01*
X-1233694Y775884D01*
X-1234669Y776924D01*
X-1236034Y777444D01*
X-1237399Y777184D01*
X-1238569Y776404D01*
X-1239349Y774584D01*
X-1239739Y773024D01*
Y771464D01*
X-1239349Y769904D01*
X-1238374Y768344D01*
X-1237204Y767304D01*
X-1235839Y767044D01*
X-1234474Y767564D01*
X-1233109Y769124D01*
G01X-1197504Y776144D02*
X-1198869Y777184D01*
X-1200039Y777444D01*
X-1201599Y776924D01*
X-1202769Y775884D01*
X-1203549Y774064D01*
X-1203744Y772244D01*
X-1203549Y770424D01*
X-1202769Y768864D01*
X-1201599Y767564D01*
X-1200039Y767044D01*
X-1198674Y767564D01*
X-1197504Y768604D01*
G01X-1182724Y767044D02*
X-1183894Y767304D01*
X-1185064Y768344D01*
X-1185844Y770164D01*
X-1186234Y772244D01*
X-1185844Y774324D01*
X-1185064Y776144D01*
X-1183894Y777184D01*
X-1182724Y777444D01*
X-1181554Y777184D01*
X-1180384Y776144D01*
X-1179604Y774324D01*
X-1179409Y772244D01*
X-1179604Y770164D01*
X-1180384Y768344D01*
X-1181554Y767304D01*
X-1182724Y767044D01*
G01X-1170674D02*
Y777444D01*
G01Y774584D02*
X-1170089Y775884D01*
X-1169114Y776924D01*
X-1167749Y777444D01*
X-1166384Y776924D01*
X-1165409Y775884D01*
X-1164824Y774584D01*
Y767044D01*
G01Y774584D02*
X-1164239Y775884D01*
X-1163264Y776924D01*
X-1161899Y777444D01*
X-1160534Y776924D01*
X-1159559Y775884D01*
X-1158974Y774324D01*
Y767044D01*
G01X-1150434Y761844D02*
Y777444D01*
G01Y775104D02*
X-1149459Y776404D01*
X-1148484Y777184D01*
X-1146924Y777444D01*
X-1145559Y777184D01*
X-1144194Y775884D01*
X-1143609Y774064D01*
X-1143414Y772244D01*
X-1143609Y770424D01*
X-1144194Y768604D01*
X-1145364Y767564D01*
X-1146924Y767044D01*
X-1148289Y767304D01*
X-1149654Y768084D01*
X-1150434Y769124D01*
G01X-1129024Y767044D02*
Y782644D01*
G01X-1111124Y777444D02*
Y767044D01*
G01Y781604D02*
X-1111514Y781864D01*
Y782384D01*
X-1111124Y782644D01*
X-1110734Y782384D01*
Y781864D01*
X-1111124Y781604D01*
G01X-1089714Y767044D02*
Y777444D01*
G01Y775624D02*
X-1090494Y776664D01*
X-1091664Y777184D01*
X-1093029Y777444D01*
X-1094394Y776924D01*
X-1095564Y775884D01*
X-1096344Y774324D01*
X-1096734Y772244D01*
X-1096344Y770164D01*
X-1095564Y768604D01*
X-1094394Y767564D01*
X-1093029Y767044D01*
X-1091664Y767304D01*
X-1090494Y768084D01*
X-1089714Y769124D01*
G01X-1078639Y767044D02*
Y777444D01*
G01Y774844D02*
X-1077859Y776144D01*
X-1076689Y777184D01*
X-1075129Y777444D01*
X-1073764Y777184D01*
X-1072594Y776144D01*
X-1072009Y774324D01*
Y767044D01*
G01X-1057424Y782644D02*
Y767044D01*
G01X-1060154Y777444D02*
X-1054694D01*
G01X-1026499D02*
X-1024159Y767044D01*
X-1021624Y777444D01*
X-1019089Y767044D01*
X-1016749Y777444D01*
G01X-1003724D02*
Y767044D01*
G01Y781604D02*
X-1004114Y781864D01*
Y782384D01*
X-1003724Y782644D01*
X-1003334Y782384D01*
Y781864D01*
X-1003724Y781604D01*
G01X-985824Y782644D02*
Y767044D01*
G01X-988554Y777444D02*
X-983094D01*
G01X-971239Y767044D02*
Y782644D01*
G01Y775104D02*
X-970264Y776404D01*
X-969289Y777184D01*
X-967729Y777444D01*
X-966559Y777184D01*
X-965194Y776144D01*
X-964609Y774584D01*
Y767044D01*
G01X-932124Y782644D02*
Y767044D01*
G01X-934854Y777444D02*
X-929394D01*
G01X-917539Y767044D02*
Y782644D01*
G01Y775104D02*
X-916564Y776404D01*
X-915589Y777184D01*
X-914029Y777444D01*
X-912859Y777184D01*
X-911494Y776144D01*
X-910909Y774584D01*
Y767044D01*
G01X-899249Y774064D02*
X-893009D01*
X-893594Y775884D01*
X-894569Y776924D01*
X-895934Y777444D01*
X-897299Y777184D01*
X-898469Y776404D01*
X-899249Y774584D01*
X-899639Y773024D01*
Y771464D01*
X-899249Y769904D01*
X-898274Y768344D01*
X-897104Y767304D01*
X-895739Y767044D01*
X-894374Y767564D01*
X-893009Y769124D01*
G01X-864619Y767044D02*
Y782644D01*
G01X-856429D02*
Y767044D01*
G01Y774844D02*
X-864619D01*
G01X-839114Y767044D02*
Y777444D01*
G01Y775624D02*
X-839894Y776664D01*
X-841064Y777184D01*
X-842429Y777444D01*
X-843794Y776924D01*
X-844964Y775884D01*
X-845744Y774324D01*
X-846134Y772244D01*
X-845744Y770164D01*
X-844964Y768604D01*
X-843794Y767564D01*
X-842429Y767044D01*
X-841064Y767304D01*
X-839894Y768084D01*
X-839114Y769124D01*
G01X-827649Y777444D02*
X-821799D01*
X-827649Y767044D01*
X-821799D01*
G01X-803314D02*
Y777444D01*
G01Y775624D02*
X-804094Y776664D01*
X-805264Y777184D01*
X-806629Y777444D01*
X-807994Y776924D01*
X-809164Y775884D01*
X-809944Y774324D01*
X-810334Y772244D01*
X-809944Y770164D01*
X-809164Y768604D01*
X-807994Y767564D01*
X-806629Y767044D01*
X-805264Y767304D01*
X-804094Y768084D01*
X-803314Y769124D01*
G01X-791654Y767044D02*
Y777444D01*
G01Y775364D02*
X-790679Y776404D01*
X-789704Y777184D01*
X-788339Y777444D01*
X-787364Y777184D01*
X-786194Y776404D01*
G01X-767514Y782644D02*
Y767044D01*
G01Y769384D02*
X-768294Y768084D01*
X-769464Y767304D01*
X-770829Y767044D01*
X-772389Y767564D01*
X-773559Y768864D01*
X-774339Y770424D01*
X-774534Y772244D01*
X-774339Y774064D01*
X-773559Y775624D01*
X-772389Y776924D01*
X-770829Y777444D01*
X-769464Y777184D01*
X-768489Y776664D01*
X-767514Y775624D01*
G01X-753124Y767044D02*
X-754294Y767304D01*
X-755464Y768344D01*
X-756244Y770164D01*
X-756634Y772244D01*
X-756244Y774324D01*
X-755464Y776144D01*
X-754294Y777184D01*
X-753124Y777444D01*
X-751954Y777184D01*
X-750784Y776144D01*
X-750004Y774324D01*
X-749809Y772244D01*
X-750004Y770164D01*
X-750784Y768344D01*
X-751954Y767304D01*
X-753124Y767044D01*
G01X-738539Y777444D02*
Y770164D01*
X-737759Y768344D01*
X-736589Y767304D01*
X-735224Y767044D01*
X-733859Y767304D01*
X-732689Y768344D01*
X-731909Y770164D01*
G01Y767044D02*
Y777444D01*
G01X-720249Y768864D02*
X-719274Y767824D01*
X-717909Y767044D01*
X-716739D01*
X-715569Y767564D01*
X-714789Y768344D01*
X-714399Y769384D01*
X-714594Y770944D01*
X-715374Y771724D01*
X-718884Y773284D01*
X-719664Y775104D01*
X-719274Y776404D01*
X-718494Y777184D01*
X-717324Y777444D01*
X-716154Y777184D01*
X-714984Y776404D01*
G01X-2080649Y842064D02*
X-2074409D01*
X-2074994Y843884D01*
X-2075969Y844924D01*
X-2077334Y845444D01*
X-2078699Y845184D01*
X-2079869Y844404D01*
X-2080649Y842584D01*
X-2081039Y841024D01*
Y839464D01*
X-2080649Y837904D01*
X-2079674Y836344D01*
X-2078504Y835304D01*
X-2077139Y835044D01*
X-2075774Y835564D01*
X-2074409Y837124D01*
G01X-2059824Y834524D02*
X-2060214Y834784D01*
Y835304D01*
X-2059824Y835564D01*
X-2059434Y835304D01*
Y834784D01*
X-2059824Y834524D01*
G01X-2027729Y835044D02*
Y850644D01*
X-2020319D01*
G01X-2023049Y843104D02*
X-2027729D01*
G01X-2002614Y835044D02*
Y845444D01*
G01Y843624D02*
X-2003394Y844664D01*
X-2004564Y845184D01*
X-2005929Y845444D01*
X-2007294Y844924D01*
X-2008464Y843884D01*
X-2009244Y842324D01*
X-2009634Y840244D01*
X-2009244Y838164D01*
X-2008464Y836604D01*
X-2007294Y835564D01*
X-2005929Y835044D01*
X-2004564Y835304D01*
X-2003394Y836084D01*
X-2002614Y837124D01*
G01X-1991734Y835044D02*
Y850644D01*
G01Y842844D02*
X-1990759Y844404D01*
X-1989589Y845184D01*
X-1988419Y845444D01*
X-1986664Y844924D01*
X-1985494Y843884D01*
X-1984714Y842064D01*
Y839984D01*
X-1985104Y837904D01*
X-1985884Y836344D01*
X-1987249Y835304D01*
X-1988419Y835044D01*
X-1989589Y835304D01*
X-1990759Y836084D01*
X-1991734Y837384D01*
G01X-1973054Y835044D02*
Y845444D01*
G01Y843364D02*
X-1972079Y844404D01*
X-1971104Y845184D01*
X-1969739Y845444D01*
X-1968764Y845184D01*
X-1967594Y844404D01*
G01X-1952424Y845444D02*
Y835044D01*
G01Y849604D02*
X-1952814Y849864D01*
Y850384D01*
X-1952424Y850644D01*
X-1952034Y850384D01*
Y849864D01*
X-1952424Y849604D01*
G01X-1931404Y844144D02*
X-1932769Y845184D01*
X-1933939Y845444D01*
X-1935499Y844924D01*
X-1936669Y843884D01*
X-1937449Y842064D01*
X-1937644Y840244D01*
X-1937449Y838424D01*
X-1936669Y836864D01*
X-1935499Y835564D01*
X-1933939Y835044D01*
X-1932574Y835564D01*
X-1931404Y836604D01*
G01X-1913114Y835044D02*
Y845444D01*
G01Y843624D02*
X-1913894Y844664D01*
X-1915064Y845184D01*
X-1916429Y845444D01*
X-1917794Y844924D01*
X-1918964Y843884D01*
X-1919744Y842324D01*
X-1920134Y840244D01*
X-1919744Y838164D01*
X-1918964Y836604D01*
X-1917794Y835564D01*
X-1916429Y835044D01*
X-1915064Y835304D01*
X-1913894Y836084D01*
X-1913114Y837124D01*
G01X-1898724Y850644D02*
Y835044D01*
G01X-1901454Y845444D02*
X-1895994D01*
G01X-1880824D02*
Y835044D01*
G01Y849604D02*
X-1881214Y849864D01*
Y850384D01*
X-1880824Y850644D01*
X-1880434Y850384D01*
Y849864D01*
X-1880824Y849604D01*
G01X-1862924Y835044D02*
X-1864094Y835304D01*
X-1865264Y836344D01*
X-1866044Y838164D01*
X-1866434Y840244D01*
X-1866044Y842324D01*
X-1865264Y844144D01*
X-1864094Y845184D01*
X-1862924Y845444D01*
X-1861754Y845184D01*
X-1860584Y844144D01*
X-1859804Y842324D01*
X-1859609Y840244D01*
X-1859804Y838164D01*
X-1860584Y836344D01*
X-1861754Y835304D01*
X-1862924Y835044D01*
G01X-1848339D02*
Y845444D01*
G01Y842844D02*
X-1847559Y844144D01*
X-1846389Y845184D01*
X-1844829Y845444D01*
X-1843464Y845184D01*
X-1842294Y844144D01*
X-1841709Y842324D01*
Y835044D01*
G01X-1809224Y850644D02*
Y835044D01*
G01X-1813709Y850644D02*
X-1804739D01*
G01X-1791324Y835044D02*
X-1792494Y835304D01*
X-1793664Y836344D01*
X-1794444Y838164D01*
X-1794834Y840244D01*
X-1794444Y842324D01*
X-1793664Y844144D01*
X-1792494Y845184D01*
X-1791324Y845444D01*
X-1790154Y845184D01*
X-1788984Y844144D01*
X-1788204Y842324D01*
X-1788009Y840244D01*
X-1788204Y838164D01*
X-1788984Y836344D01*
X-1790154Y835304D01*
X-1791324Y835044D01*
G01X-1773424D02*
Y850644D01*
G01X-1758449Y842064D02*
X-1752209D01*
X-1752794Y843884D01*
X-1753769Y844924D01*
X-1755134Y845444D01*
X-1756499Y845184D01*
X-1757669Y844404D01*
X-1758449Y842584D01*
X-1758839Y841024D01*
Y839464D01*
X-1758449Y837904D01*
X-1757474Y836344D01*
X-1756304Y835304D01*
X-1754939Y835044D01*
X-1753574Y835564D01*
X-1752209Y837124D01*
G01X-1740354Y835044D02*
Y845444D01*
G01Y843364D02*
X-1739379Y844404D01*
X-1738404Y845184D01*
X-1737039Y845444D01*
X-1736064Y845184D01*
X-1734894Y844404D01*
G01X-1716214Y835044D02*
Y845444D01*
G01Y843624D02*
X-1716994Y844664D01*
X-1718164Y845184D01*
X-1719529Y845444D01*
X-1720894Y844924D01*
X-1722064Y843884D01*
X-1722844Y842324D01*
X-1723234Y840244D01*
X-1722844Y838164D01*
X-1722064Y836604D01*
X-1720894Y835564D01*
X-1719529Y835044D01*
X-1718164Y835304D01*
X-1716994Y836084D01*
X-1716214Y837124D01*
G01X-1705139Y835044D02*
Y845444D01*
G01Y842844D02*
X-1704359Y844144D01*
X-1703189Y845184D01*
X-1701629Y845444D01*
X-1700264Y845184D01*
X-1699094Y844144D01*
X-1698509Y842324D01*
Y835044D01*
G01X-1680804Y844144D02*
X-1682169Y845184D01*
X-1683339Y845444D01*
X-1684899Y844924D01*
X-1686069Y843884D01*
X-1686849Y842064D01*
X-1687044Y840244D01*
X-1686849Y838424D01*
X-1686069Y836864D01*
X-1684899Y835564D01*
X-1683339Y835044D01*
X-1681974Y835564D01*
X-1680804Y836604D01*
G01X-1668949Y842064D02*
X-1662709D01*
X-1663294Y843884D01*
X-1664269Y844924D01*
X-1665634Y845444D01*
X-1666999Y845184D01*
X-1668169Y844404D01*
X-1668949Y842584D01*
X-1669339Y841024D01*
Y839464D01*
X-1668949Y837904D01*
X-1667974Y836344D01*
X-1666804Y835304D01*
X-1665439Y835044D01*
X-1664074Y835564D01*
X-1662709Y837124D01*
G01X-1651049Y836864D02*
X-1650074Y835824D01*
X-1648709Y835044D01*
X-1647539D01*
X-1646369Y835564D01*
X-1645589Y836344D01*
X-1645199Y837384D01*
X-1645394Y838944D01*
X-1646174Y839724D01*
X-1649684Y841284D01*
X-1650464Y843104D01*
X-1650074Y844404D01*
X-1649294Y845184D01*
X-1648124Y845444D01*
X-1646954Y845184D01*
X-1645784Y844404D01*
G01X-1630224Y834524D02*
X-1630614Y834784D01*
Y835304D01*
X-1630224Y835564D01*
X-1629834Y835304D01*
Y834784D01*
X-1630224Y834524D01*
G01Y841544D02*
X-1630614Y841804D01*
Y842324D01*
X-1630224Y842584D01*
X-1629834Y842324D01*
Y841804D01*
X-1630224Y841544D01*
G01X-1597349Y842064D02*
X-1591109D01*
X-1591694Y843884D01*
X-1592669Y844924D01*
X-1594034Y845444D01*
X-1595399Y845184D01*
X-1596569Y844404D01*
X-1597349Y842584D01*
X-1597739Y841024D01*
Y839464D01*
X-1597349Y837904D01*
X-1596374Y836344D01*
X-1595204Y835304D01*
X-1593839Y835044D01*
X-1592474Y835564D01*
X-1591109Y837124D01*
G01X-1579839Y835044D02*
Y845444D01*
G01Y842844D02*
X-1579059Y844144D01*
X-1577889Y845184D01*
X-1576329Y845444D01*
X-1574964Y845184D01*
X-1573794Y844144D01*
X-1573209Y842324D01*
Y835044D01*
G01X-1555114Y850644D02*
Y835044D01*
G01Y837384D02*
X-1555894Y836084D01*
X-1557064Y835304D01*
X-1558429Y835044D01*
X-1559989Y835564D01*
X-1561159Y836864D01*
X-1561939Y838424D01*
X-1562134Y840244D01*
X-1561939Y842064D01*
X-1561159Y843624D01*
X-1559989Y844924D01*
X-1558429Y845444D01*
X-1557064Y845184D01*
X-1556089Y844664D01*
X-1555114Y843624D01*
G01X-1526334Y829844D02*
Y845444D01*
G01Y843104D02*
X-1525359Y844404D01*
X-1524384Y845184D01*
X-1522824Y845444D01*
X-1521459Y845184D01*
X-1520094Y843884D01*
X-1519509Y842064D01*
X-1519314Y840244D01*
X-1519509Y838424D01*
X-1520094Y836604D01*
X-1521264Y835564D01*
X-1522824Y835044D01*
X-1524189Y835304D01*
X-1525554Y836084D01*
X-1526334Y837124D01*
G01X-1507654Y835044D02*
Y845444D01*
G01Y843364D02*
X-1506679Y844404D01*
X-1505704Y845184D01*
X-1504339Y845444D01*
X-1503364Y845184D01*
X-1502194Y844404D01*
G01X-1487024Y835044D02*
X-1488194Y835304D01*
X-1489364Y836344D01*
X-1490144Y838164D01*
X-1490534Y840244D01*
X-1490144Y842324D01*
X-1489364Y844144D01*
X-1488194Y845184D01*
X-1487024Y845444D01*
X-1485854Y845184D01*
X-1484684Y844144D01*
X-1483904Y842324D01*
X-1483709Y840244D01*
X-1483904Y838164D01*
X-1484684Y836344D01*
X-1485854Y835304D01*
X-1487024Y835044D01*
G01X-1465614Y850644D02*
Y835044D01*
G01Y837384D02*
X-1466394Y836084D01*
X-1467564Y835304D01*
X-1468929Y835044D01*
X-1470489Y835564D01*
X-1471659Y836864D01*
X-1472439Y838424D01*
X-1472634Y840244D01*
X-1472439Y842064D01*
X-1471659Y843624D01*
X-1470489Y844924D01*
X-1468929Y845444D01*
X-1467564Y845184D01*
X-1466589Y844664D01*
X-1465614Y843624D01*
G01X-1454539Y845444D02*
Y838164D01*
X-1453759Y836344D01*
X-1452589Y835304D01*
X-1451224Y835044D01*
X-1449859Y835304D01*
X-1448689Y836344D01*
X-1447909Y838164D01*
G01Y835044D02*
Y845444D01*
G01X-1430204Y844144D02*
X-1431569Y845184D01*
X-1432739Y845444D01*
X-1434299Y844924D01*
X-1435469Y843884D01*
X-1436249Y842064D01*
X-1436444Y840244D01*
X-1436249Y838424D01*
X-1435469Y836864D01*
X-1434299Y835564D01*
X-1432739Y835044D01*
X-1431374Y835564D01*
X-1430204Y836604D01*
G01X-1415424Y850644D02*
Y835044D01*
G01X-1418154Y845444D02*
X-1412694D01*
G01X-1379624Y850644D02*
Y835044D01*
G01X-1382354Y845444D02*
X-1376894D01*
G01X-1364454Y835044D02*
Y845444D01*
G01Y843364D02*
X-1363479Y844404D01*
X-1362504Y845184D01*
X-1361139Y845444D01*
X-1360164Y845184D01*
X-1358994Y844404D01*
G01X-1340314Y835044D02*
Y845444D01*
G01Y843624D02*
X-1341094Y844664D01*
X-1342264Y845184D01*
X-1343629Y845444D01*
X-1344994Y844924D01*
X-1346164Y843884D01*
X-1346944Y842324D01*
X-1347334Y840244D01*
X-1346944Y838164D01*
X-1346164Y836604D01*
X-1344994Y835564D01*
X-1343629Y835044D01*
X-1342264Y835304D01*
X-1341094Y836084D01*
X-1340314Y837124D01*
G01X-1322804Y844144D02*
X-1324169Y845184D01*
X-1325339Y845444D01*
X-1326899Y844924D01*
X-1328069Y843884D01*
X-1328849Y842064D01*
X-1329044Y840244D01*
X-1328849Y838424D01*
X-1328069Y836864D01*
X-1326899Y835564D01*
X-1325339Y835044D01*
X-1323974Y835564D01*
X-1322804Y836604D01*
G01X-1310949Y842064D02*
X-1304709D01*
X-1305294Y843884D01*
X-1306269Y844924D01*
X-1307634Y845444D01*
X-1308999Y845184D01*
X-1310169Y844404D01*
X-1310949Y842584D01*
X-1311339Y841024D01*
Y839464D01*
X-1310949Y837904D01*
X-1309974Y836344D01*
X-1308804Y835304D01*
X-1307439Y835044D01*
X-1306074Y835564D01*
X-1304709Y837124D01*
G01X-1277099Y845444D02*
X-1274759Y835044D01*
X-1272224Y845444D01*
X-1269689Y835044D01*
X-1267349Y845444D01*
G01X-1254324D02*
Y835044D01*
G01Y849604D02*
X-1254714Y849864D01*
Y850384D01*
X-1254324Y850644D01*
X-1253934Y850384D01*
Y849864D01*
X-1254324Y849604D01*
G01X-1232914Y850644D02*
Y835044D01*
G01Y837384D02*
X-1233694Y836084D01*
X-1234864Y835304D01*
X-1236229Y835044D01*
X-1237789Y835564D01*
X-1238959Y836864D01*
X-1239739Y838424D01*
X-1239934Y840244D01*
X-1239739Y842064D01*
X-1238959Y843624D01*
X-1237789Y844924D01*
X-1236229Y845444D01*
X-1234864Y845184D01*
X-1233889Y844664D01*
X-1232914Y843624D01*
G01X-1218524Y850644D02*
Y835044D01*
G01X-1221254Y845444D02*
X-1215794D01*
G01X-1203939Y835044D02*
Y850644D01*
G01Y843104D02*
X-1202964Y844404D01*
X-1201989Y845184D01*
X-1200429Y845444D01*
X-1199259Y845184D01*
X-1197894Y844144D01*
X-1197309Y842584D01*
Y835044D01*
G01X-1185649Y836864D02*
X-1184674Y835824D01*
X-1183309Y835044D01*
X-1182139D01*
X-1180969Y835564D01*
X-1180189Y836344D01*
X-1179799Y837384D01*
X-1179994Y838944D01*
X-1180774Y839724D01*
X-1184284Y841284D01*
X-1185064Y843104D01*
X-1184674Y844404D01*
X-1183894Y845184D01*
X-1182724Y845444D01*
X-1181554Y845184D01*
X-1180384Y844404D01*
G01X-1143414Y835044D02*
Y845444D01*
G01Y843624D02*
X-1144194Y844664D01*
X-1145364Y845184D01*
X-1146729Y845444D01*
X-1148094Y844924D01*
X-1149264Y843884D01*
X-1150044Y842324D01*
X-1150434Y840244D01*
X-1150044Y838164D01*
X-1149264Y836604D01*
X-1148094Y835564D01*
X-1146729Y835044D01*
X-1145364Y835304D01*
X-1144194Y836084D01*
X-1143414Y837124D01*
G01X-1132339Y835044D02*
Y845444D01*
G01Y842844D02*
X-1131559Y844144D01*
X-1130389Y845184D01*
X-1128829Y845444D01*
X-1127464Y845184D01*
X-1126294Y844144D01*
X-1125709Y842324D01*
Y835044D01*
G01X-1107614Y850644D02*
Y835044D01*
G01Y837384D02*
X-1108394Y836084D01*
X-1109564Y835304D01*
X-1110929Y835044D01*
X-1112489Y835564D01*
X-1113659Y836864D01*
X-1114439Y838424D01*
X-1114634Y840244D01*
X-1114439Y842064D01*
X-1113659Y843624D01*
X-1112489Y844924D01*
X-1110929Y845444D01*
X-1109564Y845184D01*
X-1108589Y844664D01*
X-1107614Y843624D01*
G01X-1075324Y835044D02*
Y850644D01*
G01X-1053914Y835044D02*
Y845444D01*
G01Y843624D02*
X-1054694Y844664D01*
X-1055864Y845184D01*
X-1057229Y845444D01*
X-1058594Y844924D01*
X-1059764Y843884D01*
X-1060544Y842324D01*
X-1060934Y840244D01*
X-1060544Y838164D01*
X-1059764Y836604D01*
X-1058594Y835564D01*
X-1057229Y835044D01*
X-1055864Y835304D01*
X-1054694Y836084D01*
X-1053914Y837124D01*
G01X-1042839Y835044D02*
Y845444D01*
G01Y842844D02*
X-1042059Y844144D01*
X-1040889Y845184D01*
X-1039329Y845444D01*
X-1037964Y845184D01*
X-1036794Y844144D01*
X-1036209Y842324D01*
Y835044D01*
G01X-1018114Y850644D02*
Y835044D01*
G01Y837384D02*
X-1018894Y836084D01*
X-1020064Y835304D01*
X-1021429Y835044D01*
X-1022989Y835564D01*
X-1024159Y836864D01*
X-1024939Y838424D01*
X-1025134Y840244D01*
X-1024939Y842064D01*
X-1024159Y843624D01*
X-1022989Y844924D01*
X-1021429Y845444D01*
X-1020064Y845184D01*
X-1019089Y844664D01*
X-1018114Y843624D01*
G01X-1006649Y836864D02*
X-1005674Y835824D01*
X-1004309Y835044D01*
X-1003139D01*
X-1001969Y835564D01*
X-1001189Y836344D01*
X-1000799Y837384D01*
X-1000994Y838944D01*
X-1001774Y839724D01*
X-1005284Y841284D01*
X-1006064Y843104D01*
X-1005674Y844404D01*
X-1004894Y845184D01*
X-1003724Y845444D01*
X-1002554Y845184D01*
X-1001384Y844404D01*
G01X-970849Y836864D02*
X-969874Y835824D01*
X-968509Y835044D01*
X-967339D01*
X-966169Y835564D01*
X-965389Y836344D01*
X-964999Y837384D01*
X-965194Y838944D01*
X-965974Y839724D01*
X-969484Y841284D01*
X-970264Y843104D01*
X-969874Y844404D01*
X-969094Y845184D01*
X-967924Y845444D01*
X-966754Y845184D01*
X-965584Y844404D01*
G01X-953339Y835044D02*
Y850644D01*
G01Y843104D02*
X-952364Y844404D01*
X-951389Y845184D01*
X-949829Y845444D01*
X-948659Y845184D01*
X-947294Y844144D01*
X-946709Y842584D01*
Y835044D01*
G01X-928614D02*
Y845444D01*
G01Y843624D02*
X-929394Y844664D01*
X-930564Y845184D01*
X-931929Y845444D01*
X-933294Y844924D01*
X-934464Y843884D01*
X-935244Y842324D01*
X-935634Y840244D01*
X-935244Y838164D01*
X-934464Y836604D01*
X-933294Y835564D01*
X-931929Y835044D01*
X-930564Y835304D01*
X-929394Y836084D01*
X-928614Y837124D01*
G01X-914224Y835044D02*
Y850644D01*
G01X-896324Y835044D02*
Y850644D01*
G01X-863839Y835044D02*
Y845444D01*
G01Y842844D02*
X-863059Y844144D01*
X-861889Y845184D01*
X-860329Y845444D01*
X-858964Y845184D01*
X-857794Y844144D01*
X-857209Y842324D01*
Y835044D01*
G01X-842624D02*
X-843794Y835304D01*
X-844964Y836344D01*
X-845744Y838164D01*
X-846134Y840244D01*
X-845744Y842324D01*
X-844964Y844144D01*
X-843794Y845184D01*
X-842624Y845444D01*
X-841454Y845184D01*
X-840284Y844144D01*
X-839504Y842324D01*
X-839309Y840244D01*
X-839504Y838164D01*
X-840284Y836344D01*
X-841454Y835304D01*
X-842624Y835044D01*
G01X-824724Y850644D02*
Y835044D01*
G01X-827454Y845444D02*
X-821994D01*
G01X-792434D02*
X-788924Y835044D01*
X-785414Y845444D01*
G01X-767514Y835044D02*
Y845444D01*
G01Y843624D02*
X-768294Y844664D01*
X-769464Y845184D01*
X-770829Y845444D01*
X-772194Y844924D01*
X-773364Y843884D01*
X-774144Y842324D01*
X-774534Y840244D01*
X-774144Y838164D01*
X-773364Y836604D01*
X-772194Y835564D01*
X-770829Y835044D01*
X-769464Y835304D01*
X-768294Y836084D01*
X-767514Y837124D01*
G01X-755854Y835044D02*
Y845444D01*
G01Y843364D02*
X-754879Y844404D01*
X-753904Y845184D01*
X-752539Y845444D01*
X-751564Y845184D01*
X-750394Y844404D01*
G01X-739319Y830364D02*
X-738149Y829844D01*
X-736589Y830364D01*
X-735614Y831404D01*
X-734834Y832704D01*
X-733664Y836864D01*
X-731129Y845444D01*
G01X-737369D02*
X-733664Y836864D01*
G01X-705274Y835044D02*
Y845444D01*
G01Y842584D02*
X-704689Y843884D01*
X-703714Y844924D01*
X-702349Y845444D01*
X-700984Y844924D01*
X-700009Y843884D01*
X-699424Y842584D01*
Y835044D01*
G01Y842584D02*
X-698839Y843884D01*
X-697864Y844924D01*
X-696499Y845444D01*
X-695134Y844924D01*
X-694159Y843884D01*
X-693574Y842324D01*
Y835044D01*
G01X-681524D02*
X-682694Y835304D01*
X-683864Y836344D01*
X-684644Y838164D01*
X-685034Y840244D01*
X-684644Y842324D01*
X-683864Y844144D01*
X-682694Y845184D01*
X-681524Y845444D01*
X-680354Y845184D01*
X-679184Y844144D01*
X-678404Y842324D01*
X-678209Y840244D01*
X-678404Y838164D01*
X-679184Y836344D01*
X-680354Y835304D01*
X-681524Y835044D01*
G01X-666354D02*
Y845444D01*
G01Y843364D02*
X-665379Y844404D01*
X-664404Y845184D01*
X-663039Y845444D01*
X-662064Y845184D01*
X-660894Y844404D01*
G01X-648649Y842064D02*
X-642409D01*
X-642994Y843884D01*
X-643969Y844924D01*
X-645334Y845444D01*
X-646699Y845184D01*
X-647869Y844404D01*
X-648649Y842584D01*
X-649039Y841024D01*
Y839464D01*
X-648649Y837904D01*
X-647674Y836344D01*
X-646504Y835304D01*
X-645139Y835044D01*
X-643774Y835564D01*
X-642409Y837124D01*
G01X-2074214Y884644D02*
Y869044D01*
G01Y871384D02*
X-2074994Y870084D01*
X-2076164Y869304D01*
X-2077529Y869044D01*
X-2079089Y869564D01*
X-2080259Y870864D01*
X-2081039Y872424D01*
X-2081234Y874244D01*
X-2081039Y876064D01*
X-2080259Y877624D01*
X-2079089Y878924D01*
X-2077529Y879444D01*
X-2076164Y879184D01*
X-2075189Y878664D01*
X-2074214Y877624D01*
G01X-2059824Y868524D02*
X-2060214Y868784D01*
Y869304D01*
X-2059824Y869564D01*
X-2059434Y869304D01*
Y868784D01*
X-2059824Y868524D01*
G01X-2022464Y877364D02*
X-2021684Y878144D01*
X-2021099Y879444D01*
X-2020709Y881264D01*
X-2021099Y882824D01*
X-2021879Y883864D01*
X-2023244Y884644D01*
X-2028509D01*
Y869044D01*
X-2022074D01*
X-2020709Y870084D01*
X-2019929Y871644D01*
X-2019539Y873464D01*
X-2019929Y875284D01*
X-2021099Y876844D01*
X-2022464Y877364D01*
X-2028509D01*
G01X-2006124Y869044D02*
X-2007294Y869304D01*
X-2008464Y870344D01*
X-2009244Y872164D01*
X-2009634Y874244D01*
X-2009244Y876324D01*
X-2008464Y878144D01*
X-2007294Y879184D01*
X-2006124Y879444D01*
X-2004954Y879184D01*
X-2003784Y878144D01*
X-2003004Y876324D01*
X-2002809Y874244D01*
X-2003004Y872164D01*
X-2003784Y870344D01*
X-2004954Y869304D01*
X-2006124Y869044D01*
G01X-1993099Y879444D02*
X-1990759Y869044D01*
X-1988224Y879444D01*
X-1985689Y869044D01*
X-1983349Y879444D01*
G01X-1948914Y869044D02*
Y879444D01*
G01Y877624D02*
X-1949694Y878664D01*
X-1950864Y879184D01*
X-1952229Y879444D01*
X-1953594Y878924D01*
X-1954764Y877884D01*
X-1955544Y876324D01*
X-1955934Y874244D01*
X-1955544Y872164D01*
X-1954764Y870604D01*
X-1953594Y869564D01*
X-1952229Y869044D01*
X-1950864Y869304D01*
X-1949694Y870084D01*
X-1948914Y871124D01*
G01X-1937839Y869044D02*
Y879444D01*
G01Y876844D02*
X-1937059Y878144D01*
X-1935889Y879184D01*
X-1934329Y879444D01*
X-1932964Y879184D01*
X-1931794Y878144D01*
X-1931209Y876324D01*
Y869044D01*
G01X-1913114Y884644D02*
Y869044D01*
G01Y871384D02*
X-1913894Y870084D01*
X-1915064Y869304D01*
X-1916429Y869044D01*
X-1917989Y869564D01*
X-1919159Y870864D01*
X-1919939Y872424D01*
X-1920134Y874244D01*
X-1919939Y876064D01*
X-1919159Y877624D01*
X-1917989Y878924D01*
X-1916429Y879444D01*
X-1915064Y879184D01*
X-1914089Y878664D01*
X-1913114Y877624D01*
G01X-1880824Y884644D02*
Y869044D01*
G01X-1885309Y884644D02*
X-1876339D01*
G01X-1867799Y879444D02*
X-1865459Y869044D01*
X-1862924Y879444D01*
X-1860389Y869044D01*
X-1858049Y879444D01*
G01X-1845024D02*
Y869044D01*
G01Y883604D02*
X-1845414Y883864D01*
Y884384D01*
X-1845024Y884644D01*
X-1844634Y884384D01*
Y883864D01*
X-1845024Y883604D01*
G01X-1830049Y870864D02*
X-1829074Y869824D01*
X-1827709Y869044D01*
X-1826539D01*
X-1825369Y869564D01*
X-1824589Y870344D01*
X-1824199Y871384D01*
X-1824394Y872944D01*
X-1825174Y873724D01*
X-1828684Y875284D01*
X-1829464Y877104D01*
X-1829074Y878404D01*
X-1828294Y879184D01*
X-1827124Y879444D01*
X-1825954Y879184D01*
X-1824784Y878404D01*
G01X-1809224Y884644D02*
Y869044D01*
G01X-1811954Y879444D02*
X-1806494D01*
G01X-1791324Y868524D02*
X-1791714Y868784D01*
Y869304D01*
X-1791324Y869564D01*
X-1790934Y869304D01*
Y868784D01*
X-1791324Y868524D01*
G01Y875544D02*
X-1791714Y875804D01*
Y876324D01*
X-1791324Y876584D01*
X-1790934Y876324D01*
Y875804D01*
X-1791324Y875544D01*
G01X-1758449Y870864D02*
X-1757474Y869824D01*
X-1756109Y869044D01*
X-1754939D01*
X-1753769Y869564D01*
X-1752989Y870344D01*
X-1752599Y871384D01*
X-1752794Y872944D01*
X-1753574Y873724D01*
X-1757084Y875284D01*
X-1757864Y877104D01*
X-1757474Y878404D01*
X-1756694Y879184D01*
X-1755524Y879444D01*
X-1754354Y879184D01*
X-1753184Y878404D01*
G01X-1740939Y869044D02*
Y884644D01*
G01Y877104D02*
X-1739964Y878404D01*
X-1738989Y879184D01*
X-1737429Y879444D01*
X-1736259Y879184D01*
X-1734894Y878144D01*
X-1734309Y876584D01*
Y869044D01*
G01X-1716214D02*
Y879444D01*
G01Y877624D02*
X-1716994Y878664D01*
X-1718164Y879184D01*
X-1719529Y879444D01*
X-1720894Y878924D01*
X-1722064Y877884D01*
X-1722844Y876324D01*
X-1723234Y874244D01*
X-1722844Y872164D01*
X-1722064Y870604D01*
X-1720894Y869564D01*
X-1719529Y869044D01*
X-1718164Y869304D01*
X-1716994Y870084D01*
X-1716214Y871124D01*
G01X-1701824Y869044D02*
Y884644D01*
G01X-1683924Y869044D02*
Y884644D01*
G01X-1651439Y869044D02*
Y879444D01*
G01Y876844D02*
X-1650659Y878144D01*
X-1649489Y879184D01*
X-1647929Y879444D01*
X-1646564Y879184D01*
X-1645394Y878144D01*
X-1644809Y876324D01*
Y869044D01*
G01X-1630224D02*
X-1631394Y869304D01*
X-1632564Y870344D01*
X-1633344Y872164D01*
X-1633734Y874244D01*
X-1633344Y876324D01*
X-1632564Y878144D01*
X-1631394Y879184D01*
X-1630224Y879444D01*
X-1629054Y879184D01*
X-1627884Y878144D01*
X-1627104Y876324D01*
X-1626909Y874244D01*
X-1627104Y872164D01*
X-1627884Y870344D01*
X-1629054Y869304D01*
X-1630224Y869044D01*
G01X-1612324Y884644D02*
Y869044D01*
G01X-1615054Y879444D02*
X-1609594D01*
G01X-1579449Y876064D02*
X-1573209D01*
X-1573794Y877884D01*
X-1574769Y878924D01*
X-1576134Y879444D01*
X-1577499Y879184D01*
X-1578669Y878404D01*
X-1579449Y876584D01*
X-1579839Y875024D01*
Y873464D01*
X-1579449Y871904D01*
X-1578474Y870344D01*
X-1577304Y869304D01*
X-1575939Y869044D01*
X-1574574Y869564D01*
X-1573209Y871124D01*
G01X-1561549Y879444D02*
X-1555699Y869044D01*
G01Y879444D02*
X-1561549Y869044D01*
G01X-1537604Y878144D02*
X-1538969Y879184D01*
X-1540139Y879444D01*
X-1541699Y878924D01*
X-1542869Y877884D01*
X-1543649Y876064D01*
X-1543844Y874244D01*
X-1543649Y872424D01*
X-1542869Y870864D01*
X-1541699Y869564D01*
X-1540139Y869044D01*
X-1538774Y869564D01*
X-1537604Y870604D01*
G01X-1525749Y876064D02*
X-1519509D01*
X-1520094Y877884D01*
X-1521069Y878924D01*
X-1522434Y879444D01*
X-1523799Y879184D01*
X-1524969Y878404D01*
X-1525749Y876584D01*
X-1526139Y875024D01*
Y873464D01*
X-1525749Y871904D01*
X-1524774Y870344D01*
X-1523604Y869304D01*
X-1522239Y869044D01*
X-1520874Y869564D01*
X-1519509Y871124D01*
G01X-1507849Y876064D02*
X-1501609D01*
X-1502194Y877884D01*
X-1503169Y878924D01*
X-1504534Y879444D01*
X-1505899Y879184D01*
X-1507069Y878404D01*
X-1507849Y876584D01*
X-1508239Y875024D01*
Y873464D01*
X-1507849Y871904D01*
X-1506874Y870344D01*
X-1505704Y869304D01*
X-1504339Y869044D01*
X-1502974Y869564D01*
X-1501609Y871124D01*
G01X-1483514Y884644D02*
Y869044D01*
G01Y871384D02*
X-1484294Y870084D01*
X-1485464Y869304D01*
X-1486829Y869044D01*
X-1488389Y869564D01*
X-1489559Y870864D01*
X-1490339Y872424D01*
X-1490534Y874244D01*
X-1490339Y876064D01*
X-1489559Y877624D01*
X-1488389Y878924D01*
X-1486829Y879444D01*
X-1485464Y879184D01*
X-1484489Y878664D01*
X-1483514Y877624D01*
G01X-1451224Y868524D02*
X-1451614Y868784D01*
Y869304D01*
X-1451224Y869564D01*
X-1450834Y869304D01*
Y868784D01*
X-1451224Y868524D01*
G01X-1433324Y884644D02*
X-1434884Y884124D01*
X-1436054Y882824D01*
X-1436834Y881264D01*
X-1437419Y879184D01*
X-1437614Y876844D01*
X-1437419Y874504D01*
X-1436834Y872424D01*
X-1436054Y870864D01*
X-1434884Y869564D01*
X-1433324Y869044D01*
X-1431764Y869564D01*
X-1430594Y870864D01*
X-1429814Y872424D01*
X-1429229Y874504D01*
X-1429034Y876844D01*
X-1429229Y879184D01*
X-1429814Y881264D01*
X-1430594Y882824D01*
X-1431764Y884124D01*
X-1433324Y884644D01*
G01X-1415424D02*
X-1416984Y884124D01*
X-1418154Y882824D01*
X-1418934Y881264D01*
X-1419519Y879184D01*
X-1419714Y876844D01*
X-1419519Y874504D01*
X-1418934Y872424D01*
X-1418154Y870864D01*
X-1416984Y869564D01*
X-1415424Y869044D01*
X-1413864Y869564D01*
X-1412694Y870864D01*
X-1411914Y872424D01*
X-1411329Y874504D01*
X-1411134Y876844D01*
X-1411329Y879184D01*
X-1411914Y881264D01*
X-1412694Y882824D01*
X-1413864Y884124D01*
X-1415424Y884644D01*
G01X-1397914Y869044D02*
X-1397524Y872424D01*
X-1396939Y875284D01*
X-1396159Y877884D01*
X-1395184Y880744D01*
X-1393624Y884644D01*
X-1401424D01*
G01X-1381379Y881264D02*
X-1380404Y884644D01*
G01X-1377869D02*
X-1378844Y881264D01*
G01X-1347334Y863844D02*
Y879444D01*
G01Y877104D02*
X-1346359Y878404D01*
X-1345384Y879184D01*
X-1343824Y879444D01*
X-1342459Y879184D01*
X-1341094Y877884D01*
X-1340509Y876064D01*
X-1340314Y874244D01*
X-1340509Y872424D01*
X-1341094Y870604D01*
X-1342264Y869564D01*
X-1343824Y869044D01*
X-1345189Y869304D01*
X-1346554Y870084D01*
X-1347334Y871124D01*
G01X-1328849Y876064D02*
X-1322609D01*
X-1323194Y877884D01*
X-1324169Y878924D01*
X-1325534Y879444D01*
X-1326899Y879184D01*
X-1328069Y878404D01*
X-1328849Y876584D01*
X-1329239Y875024D01*
Y873464D01*
X-1328849Y871904D01*
X-1327874Y870344D01*
X-1326704Y869304D01*
X-1325339Y869044D01*
X-1323974Y869564D01*
X-1322609Y871124D01*
G01X-1310754Y869044D02*
Y879444D01*
G01Y877364D02*
X-1309779Y878404D01*
X-1308804Y879184D01*
X-1307439Y879444D01*
X-1306464Y879184D01*
X-1305294Y878404D01*
G01X-1272224Y879444D02*
Y869044D01*
G01Y883604D02*
X-1272614Y883864D01*
Y884384D01*
X-1272224Y884644D01*
X-1271834Y884384D01*
Y883864D01*
X-1272224Y883604D01*
G01X-1257639Y869044D02*
Y879444D01*
G01Y876844D02*
X-1256859Y878144D01*
X-1255689Y879184D01*
X-1254129Y879444D01*
X-1252764Y879184D01*
X-1251594Y878144D01*
X-1251009Y876324D01*
Y869044D01*
G01X-1233304Y878144D02*
X-1234669Y879184D01*
X-1235839Y879444D01*
X-1237399Y878924D01*
X-1238569Y877884D01*
X-1239349Y876064D01*
X-1239544Y874244D01*
X-1239349Y872424D01*
X-1238569Y870864D01*
X-1237399Y869564D01*
X-1235839Y869044D01*
X-1234474Y869564D01*
X-1233304Y870604D01*
G01X-1221839Y869044D02*
Y884644D01*
G01Y877104D02*
X-1220864Y878404D01*
X-1219889Y879184D01*
X-1218329Y879444D01*
X-1217159Y879184D01*
X-1215794Y878144D01*
X-1215209Y876584D01*
Y869044D01*
G01X-1200624Y868524D02*
X-1201014Y868784D01*
Y869304D01*
X-1200624Y869564D01*
X-1200234Y869304D01*
Y868784D01*
X-1200624Y868524D01*
G01X-2074604Y946144D02*
X-2075969Y947184D01*
X-2077139Y947444D01*
X-2078699Y946924D01*
X-2079869Y945884D01*
X-2080649Y944064D01*
X-2080844Y942244D01*
X-2080649Y940424D01*
X-2079869Y938864D01*
X-2078699Y937564D01*
X-2077139Y937044D01*
X-2075774Y937564D01*
X-2074604Y938604D01*
G01X-2059824Y936524D02*
X-2060214Y936784D01*
Y937304D01*
X-2059824Y937564D01*
X-2059434Y937304D01*
Y936784D01*
X-2059824Y936524D01*
G01X-2019734Y951344D02*
X-2020904Y952124D01*
X-2022269Y952644D01*
X-2023829D01*
X-2025584Y951864D01*
X-2026949Y950564D01*
X-2027924Y949004D01*
X-2028704Y946404D01*
X-2028899Y944064D01*
X-2028509Y941724D01*
X-2027924Y940164D01*
X-2026754Y938604D01*
X-2025389Y937564D01*
X-2024024Y937044D01*
X-2022659D01*
X-2021294Y937564D01*
X-2020124Y938344D01*
X-2019149Y939384D01*
G01X-2006124Y937044D02*
X-2007294Y937304D01*
X-2008464Y938344D01*
X-2009244Y940164D01*
X-2009634Y942244D01*
X-2009244Y944324D01*
X-2008464Y946144D01*
X-2007294Y947184D01*
X-2006124Y947444D01*
X-2004954Y947184D01*
X-2003784Y946144D01*
X-2003004Y944324D01*
X-2002809Y942244D01*
X-2003004Y940164D01*
X-2003784Y938344D01*
X-2004954Y937304D01*
X-2006124Y937044D01*
G01X-1991539D02*
Y947444D01*
G01Y944844D02*
X-1990759Y946144D01*
X-1989589Y947184D01*
X-1988029Y947444D01*
X-1986664Y947184D01*
X-1985494Y946144D01*
X-1984909Y944324D01*
Y937044D01*
G01X-1971494D02*
Y950304D01*
X-1971104Y951604D01*
X-1970324Y952384D01*
X-1969154Y952644D01*
X-1967984Y952124D01*
X-1967399Y950824D01*
G01X-1969739Y946404D02*
X-1973639D01*
G01X-1952424Y947444D02*
Y937044D01*
G01Y951604D02*
X-1952814Y951864D01*
Y952384D01*
X-1952424Y952644D01*
X-1952034Y952384D01*
Y951864D01*
X-1952424Y951604D01*
G01X-1937254Y933144D02*
X-1935889Y932104D01*
X-1934329Y931844D01*
X-1932964Y932104D01*
X-1931794Y933404D01*
X-1931014Y935224D01*
Y947444D01*
G01Y945364D02*
X-1931794Y946404D01*
X-1932964Y947184D01*
X-1934329Y947444D01*
X-1935889Y946924D01*
X-1936864Y945884D01*
X-1937644Y944064D01*
X-1938034Y942244D01*
X-1937839Y940684D01*
X-1937059Y938864D01*
X-1935889Y937564D01*
X-1934329Y937044D01*
X-1933159Y937304D01*
X-1931794Y938344D01*
X-1931014Y939384D01*
G01X-1919939Y947444D02*
Y940164D01*
X-1919159Y938344D01*
X-1917989Y937304D01*
X-1916624Y937044D01*
X-1915259Y937304D01*
X-1914089Y938344D01*
X-1913309Y940164D01*
G01Y937044D02*
Y947444D01*
G01X-1901454Y937044D02*
Y947444D01*
G01Y945364D02*
X-1900479Y946404D01*
X-1899504Y947184D01*
X-1898139Y947444D01*
X-1897164Y947184D01*
X-1895994Y946404D01*
G01X-1877314Y937044D02*
Y947444D01*
G01Y945624D02*
X-1878094Y946664D01*
X-1879264Y947184D01*
X-1880629Y947444D01*
X-1881994Y946924D01*
X-1883164Y945884D01*
X-1883944Y944324D01*
X-1884334Y942244D01*
X-1883944Y940164D01*
X-1883164Y938604D01*
X-1881994Y937564D01*
X-1880629Y937044D01*
X-1879264Y937304D01*
X-1878094Y938084D01*
X-1877314Y939124D01*
G01X-1862924Y952644D02*
Y937044D01*
G01X-1865654Y947444D02*
X-1860194D01*
G01X-1845024D02*
Y937044D01*
G01Y951604D02*
X-1845414Y951864D01*
Y952384D01*
X-1845024Y952644D01*
X-1844634Y952384D01*
Y951864D01*
X-1845024Y951604D01*
G01X-1827124Y937044D02*
X-1828294Y937304D01*
X-1829464Y938344D01*
X-1830244Y940164D01*
X-1830634Y942244D01*
X-1830244Y944324D01*
X-1829464Y946144D01*
X-1828294Y947184D01*
X-1827124Y947444D01*
X-1825954Y947184D01*
X-1824784Y946144D01*
X-1824004Y944324D01*
X-1823809Y942244D01*
X-1824004Y940164D01*
X-1824784Y938344D01*
X-1825954Y937304D01*
X-1827124Y937044D01*
G01X-1812539D02*
Y947444D01*
G01Y944844D02*
X-1811759Y946144D01*
X-1810589Y947184D01*
X-1809029Y947444D01*
X-1807664Y947184D01*
X-1806494Y946144D01*
X-1805909Y944324D01*
Y937044D01*
G01X-1773424D02*
X-1774594Y937304D01*
X-1775764Y938344D01*
X-1776544Y940164D01*
X-1776934Y942244D01*
X-1776544Y944324D01*
X-1775764Y946144D01*
X-1774594Y947184D01*
X-1773424Y947444D01*
X-1772254Y947184D01*
X-1771084Y946144D01*
X-1770304Y944324D01*
X-1770109Y942244D01*
X-1770304Y940164D01*
X-1771084Y938344D01*
X-1772254Y937304D01*
X-1773424Y937044D01*
G01X-1756694D02*
Y950304D01*
X-1756304Y951604D01*
X-1755524Y952384D01*
X-1754354Y952644D01*
X-1753184Y952124D01*
X-1752599Y950824D01*
G01X-1754939Y946404D02*
X-1758839D01*
G01X-1719724Y952644D02*
Y937044D01*
G01X-1722454Y947444D02*
X-1716994D01*
G01X-1705139Y937044D02*
Y952644D01*
G01Y945104D02*
X-1704164Y946404D01*
X-1703189Y947184D01*
X-1701629Y947444D01*
X-1700459Y947184D01*
X-1699094Y946144D01*
X-1698509Y944584D01*
Y937044D01*
G01X-1686849Y944064D02*
X-1680609D01*
X-1681194Y945884D01*
X-1682169Y946924D01*
X-1683534Y947444D01*
X-1684899Y947184D01*
X-1686069Y946404D01*
X-1686849Y944584D01*
X-1687239Y943024D01*
Y941464D01*
X-1686849Y939904D01*
X-1685874Y938344D01*
X-1684704Y937304D01*
X-1683339Y937044D01*
X-1681974Y937564D01*
X-1680609Y939124D01*
G01X-1651634Y931844D02*
Y947444D01*
G01Y945104D02*
X-1650659Y946404D01*
X-1649684Y947184D01*
X-1648124Y947444D01*
X-1646759Y947184D01*
X-1645394Y945884D01*
X-1644809Y944064D01*
X-1644614Y942244D01*
X-1644809Y940424D01*
X-1645394Y938604D01*
X-1646564Y937564D01*
X-1648124Y937044D01*
X-1649489Y937304D01*
X-1650854Y938084D01*
X-1651634Y939124D01*
G01X-1632954Y937044D02*
Y947444D01*
G01Y945364D02*
X-1631979Y946404D01*
X-1631004Y947184D01*
X-1629639Y947444D01*
X-1628664Y947184D01*
X-1627494Y946404D01*
G01X-1612324Y947444D02*
Y937044D01*
G01Y951604D02*
X-1612714Y951864D01*
Y952384D01*
X-1612324Y952644D01*
X-1611934Y952384D01*
Y951864D01*
X-1612324Y951604D01*
G01X-1597739Y937044D02*
Y947444D01*
G01Y944844D02*
X-1596959Y946144D01*
X-1595789Y947184D01*
X-1594229Y947444D01*
X-1592864Y947184D01*
X-1591694Y946144D01*
X-1591109Y944324D01*
Y937044D01*
G01X-1576524Y952644D02*
Y937044D01*
G01X-1579254Y947444D02*
X-1573794D01*
G01X-1561549Y944064D02*
X-1555309D01*
X-1555894Y945884D01*
X-1556869Y946924D01*
X-1558234Y947444D01*
X-1559599Y947184D01*
X-1560769Y946404D01*
X-1561549Y944584D01*
X-1561939Y943024D01*
Y941464D01*
X-1561549Y939904D01*
X-1560574Y938344D01*
X-1559404Y937304D01*
X-1558039Y937044D01*
X-1556674Y937564D01*
X-1555309Y939124D01*
G01X-1537214Y952644D02*
Y937044D01*
G01Y939384D02*
X-1537994Y938084D01*
X-1539164Y937304D01*
X-1540529Y937044D01*
X-1542089Y937564D01*
X-1543259Y938864D01*
X-1544039Y940424D01*
X-1544234Y942244D01*
X-1544039Y944064D01*
X-1543259Y945624D01*
X-1542089Y946924D01*
X-1540529Y947444D01*
X-1539164Y947184D01*
X-1538189Y946664D01*
X-1537214Y945624D01*
G01X-1501804Y946144D02*
X-1503169Y947184D01*
X-1504339Y947444D01*
X-1505899Y946924D01*
X-1507069Y945884D01*
X-1507849Y944064D01*
X-1508044Y942244D01*
X-1507849Y940424D01*
X-1507069Y938864D01*
X-1505899Y937564D01*
X-1504339Y937044D01*
X-1502974Y937564D01*
X-1501804Y938604D01*
G01X-1487024Y947444D02*
Y937044D01*
G01Y951604D02*
X-1487414Y951864D01*
Y952384D01*
X-1487024Y952644D01*
X-1486634Y952384D01*
Y951864D01*
X-1487024Y951604D01*
G01X-1471854Y937044D02*
Y947444D01*
G01Y945364D02*
X-1470879Y946404D01*
X-1469904Y947184D01*
X-1468539Y947444D01*
X-1467564Y947184D01*
X-1466394Y946404D01*
G01X-1448104Y946144D02*
X-1449469Y947184D01*
X-1450639Y947444D01*
X-1452199Y946924D01*
X-1453369Y945884D01*
X-1454149Y944064D01*
X-1454344Y942244D01*
X-1454149Y940424D01*
X-1453369Y938864D01*
X-1452199Y937564D01*
X-1450639Y937044D01*
X-1449274Y937564D01*
X-1448104Y938604D01*
G01X-1436639Y947444D02*
Y940164D01*
X-1435859Y938344D01*
X-1434689Y937304D01*
X-1433324Y937044D01*
X-1431959Y937304D01*
X-1430789Y938344D01*
X-1430009Y940164D01*
G01Y937044D02*
Y947444D01*
G01X-1415424D02*
Y937044D01*
G01Y951604D02*
X-1415814Y951864D01*
Y952384D01*
X-1415424Y952644D01*
X-1415034Y952384D01*
Y951864D01*
X-1415424Y951604D01*
G01X-1397524Y952644D02*
Y937044D01*
G01X-1400254Y947444D02*
X-1394794D01*
G01X-1365234Y937044D02*
Y952644D01*
G01Y944844D02*
X-1364259Y946404D01*
X-1363089Y947184D01*
X-1361919Y947444D01*
X-1360164Y946924D01*
X-1358994Y945884D01*
X-1358214Y944064D01*
Y941984D01*
X-1358604Y939904D01*
X-1359384Y938344D01*
X-1360749Y937304D01*
X-1361919Y937044D01*
X-1363089Y937304D01*
X-1364259Y938084D01*
X-1365234Y939384D01*
G01X-1343824Y937044D02*
X-1344994Y937304D01*
X-1346164Y938344D01*
X-1346944Y940164D01*
X-1347334Y942244D01*
X-1346944Y944324D01*
X-1346164Y946144D01*
X-1344994Y947184D01*
X-1343824Y947444D01*
X-1342654Y947184D01*
X-1341484Y946144D01*
X-1340704Y944324D01*
X-1340509Y942244D01*
X-1340704Y940164D01*
X-1341484Y938344D01*
X-1342654Y937304D01*
X-1343824Y937044D01*
G01X-1322414D02*
Y947444D01*
G01Y945624D02*
X-1323194Y946664D01*
X-1324364Y947184D01*
X-1325729Y947444D01*
X-1327094Y946924D01*
X-1328264Y945884D01*
X-1329044Y944324D01*
X-1329434Y942244D01*
X-1329044Y940164D01*
X-1328264Y938604D01*
X-1327094Y937564D01*
X-1325729Y937044D01*
X-1324364Y937304D01*
X-1323194Y938084D01*
X-1322414Y939124D01*
G01X-1310754Y937044D02*
Y947444D01*
G01Y945364D02*
X-1309779Y946404D01*
X-1308804Y947184D01*
X-1307439Y947444D01*
X-1306464Y947184D01*
X-1305294Y946404D01*
G01X-1286614Y952644D02*
Y937044D01*
G01Y939384D02*
X-1287394Y938084D01*
X-1288564Y937304D01*
X-1289929Y937044D01*
X-1291489Y937564D01*
X-1292659Y938864D01*
X-1293439Y940424D01*
X-1293634Y942244D01*
X-1293439Y944064D01*
X-1292659Y945624D01*
X-1291489Y946924D01*
X-1289929Y947444D01*
X-1288564Y947184D01*
X-1287589Y946664D01*
X-1286614Y945624D01*
G01X-1257639Y937044D02*
Y947444D01*
G01Y944844D02*
X-1256859Y946144D01*
X-1255689Y947184D01*
X-1254129Y947444D01*
X-1252764Y947184D01*
X-1251594Y946144D01*
X-1251009Y944324D01*
Y937044D01*
G01X-1236424D02*
X-1237594Y937304D01*
X-1238764Y938344D01*
X-1239544Y940164D01*
X-1239934Y942244D01*
X-1239544Y944324D01*
X-1238764Y946144D01*
X-1237594Y947184D01*
X-1236424Y947444D01*
X-1235254Y947184D01*
X-1234084Y946144D01*
X-1233304Y944324D01*
X-1233109Y942244D01*
X-1233304Y940164D01*
X-1234084Y938344D01*
X-1235254Y937304D01*
X-1236424Y937044D01*
G01X-1218524Y952644D02*
Y937044D01*
G01X-1221254Y947444D02*
X-1215794D01*
G01X-1185649Y938864D02*
X-1184674Y937824D01*
X-1183309Y937044D01*
X-1182139D01*
X-1180969Y937564D01*
X-1180189Y938344D01*
X-1179799Y939384D01*
X-1179994Y940944D01*
X-1180774Y941724D01*
X-1184284Y943284D01*
X-1185064Y945104D01*
X-1184674Y946404D01*
X-1183894Y947184D01*
X-1182724Y947444D01*
X-1181554Y947184D01*
X-1180384Y946404D01*
G01X-1168334Y931844D02*
Y947444D01*
G01Y945104D02*
X-1167359Y946404D01*
X-1166384Y947184D01*
X-1164824Y947444D01*
X-1163459Y947184D01*
X-1162094Y945884D01*
X-1161509Y944064D01*
X-1161314Y942244D01*
X-1161509Y940424D01*
X-1162094Y938604D01*
X-1163264Y937564D01*
X-1164824Y937044D01*
X-1166189Y937304D01*
X-1167554Y938084D01*
X-1168334Y939124D01*
G01X-1149849Y944064D02*
X-1143609D01*
X-1144194Y945884D01*
X-1145169Y946924D01*
X-1146534Y947444D01*
X-1147899Y947184D01*
X-1149069Y946404D01*
X-1149849Y944584D01*
X-1150239Y943024D01*
Y941464D01*
X-1149849Y939904D01*
X-1148874Y938344D01*
X-1147704Y937304D01*
X-1146339Y937044D01*
X-1144974Y937564D01*
X-1143609Y939124D01*
G01X-1125904Y946144D02*
X-1127269Y947184D01*
X-1128439Y947444D01*
X-1129999Y946924D01*
X-1131169Y945884D01*
X-1131949Y944064D01*
X-1132144Y942244D01*
X-1131949Y940424D01*
X-1131169Y938864D01*
X-1129999Y937564D01*
X-1128439Y937044D01*
X-1127074Y937564D01*
X-1125904Y938604D01*
G01X-1111124Y947444D02*
Y937044D01*
G01Y951604D02*
X-1111514Y951864D01*
Y952384D01*
X-1111124Y952644D01*
X-1110734Y952384D01*
Y951864D01*
X-1111124Y951604D01*
G01X-1094394Y937044D02*
Y950304D01*
X-1094004Y951604D01*
X-1093224Y952384D01*
X-1092054Y952644D01*
X-1090884Y952124D01*
X-1090299Y950824D01*
G01X-1092639Y946404D02*
X-1096539D01*
G01X-1075324Y947444D02*
Y937044D01*
G01Y951604D02*
X-1075714Y951864D01*
Y952384D01*
X-1075324Y952644D01*
X-1074934Y952384D01*
Y951864D01*
X-1075324Y951604D01*
G01X-1054304Y946144D02*
X-1055669Y947184D01*
X-1056839Y947444D01*
X-1058399Y946924D01*
X-1059569Y945884D01*
X-1060349Y944064D01*
X-1060544Y942244D01*
X-1060349Y940424D01*
X-1059569Y938864D01*
X-1058399Y937564D01*
X-1056839Y937044D01*
X-1055474Y937564D01*
X-1054304Y938604D01*
G01X-1036014Y937044D02*
Y947444D01*
G01Y945624D02*
X-1036794Y946664D01*
X-1037964Y947184D01*
X-1039329Y947444D01*
X-1040694Y946924D01*
X-1041864Y945884D01*
X-1042644Y944324D01*
X-1043034Y942244D01*
X-1042644Y940164D01*
X-1041864Y938604D01*
X-1040694Y937564D01*
X-1039329Y937044D01*
X-1037964Y937304D01*
X-1036794Y938084D01*
X-1036014Y939124D01*
G01X-1021624Y937044D02*
Y952644D01*
G01X-1003724Y937044D02*
Y952644D01*
G01X-989919Y932364D02*
X-988749Y931844D01*
X-987189Y932364D01*
X-986214Y933404D01*
X-985434Y934704D01*
X-984264Y938864D01*
X-981729Y947444D01*
G01X-987969D02*
X-984264Y938864D01*
G01X-946514Y952644D02*
Y937044D01*
G01Y939384D02*
X-947294Y938084D01*
X-948464Y937304D01*
X-949829Y937044D01*
X-951389Y937564D01*
X-952559Y938864D01*
X-953339Y940424D01*
X-953534Y942244D01*
X-953339Y944064D01*
X-952559Y945624D01*
X-951389Y946924D01*
X-949829Y947444D01*
X-948464Y947184D01*
X-947489Y946664D01*
X-946514Y945624D01*
G01X-932124Y947444D02*
Y937044D01*
G01Y951604D02*
X-932514Y951864D01*
Y952384D01*
X-932124Y952644D01*
X-931734Y952384D01*
Y951864D01*
X-932124Y951604D01*
G01X-920074Y937044D02*
Y947444D01*
G01Y944584D02*
X-919489Y945884D01*
X-918514Y946924D01*
X-917149Y947444D01*
X-915784Y946924D01*
X-914809Y945884D01*
X-914224Y944584D01*
Y937044D01*
G01Y944584D02*
X-913639Y945884D01*
X-912664Y946924D01*
X-911299Y947444D01*
X-909934Y946924D01*
X-908959Y945884D01*
X-908374Y944324D01*
Y937044D01*
G01X-899249Y944064D02*
X-893009D01*
X-893594Y945884D01*
X-894569Y946924D01*
X-895934Y947444D01*
X-897299Y947184D01*
X-898469Y946404D01*
X-899249Y944584D01*
X-899639Y943024D01*
Y941464D01*
X-899249Y939904D01*
X-898274Y938344D01*
X-897104Y937304D01*
X-895739Y937044D01*
X-894374Y937564D01*
X-893009Y939124D01*
G01X-881739Y937044D02*
Y947444D01*
G01Y944844D02*
X-880959Y946144D01*
X-879789Y947184D01*
X-878229Y947444D01*
X-876864Y947184D01*
X-875694Y946144D01*
X-875109Y944324D01*
Y937044D01*
G01X-863449Y938864D02*
X-862474Y937824D01*
X-861109Y937044D01*
X-859939D01*
X-858769Y937564D01*
X-857989Y938344D01*
X-857599Y939384D01*
X-857794Y940944D01*
X-858574Y941724D01*
X-862084Y943284D01*
X-862864Y945104D01*
X-862474Y946404D01*
X-861694Y947184D01*
X-860524Y947444D01*
X-859354Y947184D01*
X-858184Y946404D01*
G01X-842624Y947444D02*
Y937044D01*
G01Y951604D02*
X-843014Y951864D01*
Y952384D01*
X-842624Y952644D01*
X-842234Y952384D01*
Y951864D01*
X-842624Y951604D01*
G01X-824724Y937044D02*
X-825894Y937304D01*
X-827064Y938344D01*
X-827844Y940164D01*
X-828234Y942244D01*
X-827844Y944324D01*
X-827064Y946144D01*
X-825894Y947184D01*
X-824724Y947444D01*
X-823554Y947184D01*
X-822384Y946144D01*
X-821604Y944324D01*
X-821409Y942244D01*
X-821604Y940164D01*
X-822384Y938344D01*
X-823554Y937304D01*
X-824724Y937044D01*
G01X-810139D02*
Y947444D01*
G01Y944844D02*
X-809359Y946144D01*
X-808189Y947184D01*
X-806629Y947444D01*
X-805264Y947184D01*
X-804094Y946144D01*
X-803509Y944324D01*
Y937044D01*
G01X-791849Y944064D02*
X-785609D01*
X-786194Y945884D01*
X-787169Y946924D01*
X-788534Y947444D01*
X-789899Y947184D01*
X-791069Y946404D01*
X-791849Y944584D01*
X-792239Y943024D01*
Y941464D01*
X-791849Y939904D01*
X-790874Y938344D01*
X-789704Y937304D01*
X-788339Y937044D01*
X-786974Y937564D01*
X-785609Y939124D01*
G01X-767514Y952644D02*
Y937044D01*
G01Y939384D02*
X-768294Y938084D01*
X-769464Y937304D01*
X-770829Y937044D01*
X-772389Y937564D01*
X-773559Y938864D01*
X-774339Y940424D01*
X-774534Y942244D01*
X-774339Y944064D01*
X-773559Y945624D01*
X-772389Y946924D01*
X-770829Y947444D01*
X-769464Y947184D01*
X-768489Y946664D01*
X-767514Y945624D01*
G01X-735224Y937044D02*
X-736394Y937304D01*
X-737564Y938344D01*
X-738344Y940164D01*
X-738734Y942244D01*
X-738344Y944324D01*
X-737564Y946144D01*
X-736394Y947184D01*
X-735224Y947444D01*
X-734054Y947184D01*
X-732884Y946144D01*
X-732104Y944324D01*
X-731909Y942244D01*
X-732104Y940164D01*
X-732884Y938344D01*
X-734054Y937304D01*
X-735224Y937044D01*
G01X-720639D02*
Y947444D01*
G01Y944844D02*
X-719859Y946144D01*
X-718689Y947184D01*
X-717129Y947444D01*
X-715764Y947184D01*
X-714594Y946144D01*
X-714009Y944324D01*
Y937044D01*
G01X-681524Y952644D02*
Y937044D01*
G01X-684254Y947444D02*
X-678794D01*
G01X-666939Y937044D02*
Y952644D01*
G01Y945104D02*
X-665964Y946404D01*
X-664989Y947184D01*
X-663429Y947444D01*
X-662259Y947184D01*
X-660894Y946144D01*
X-660309Y944584D01*
Y937044D01*
G01X-648649Y944064D02*
X-642409D01*
X-642994Y945884D01*
X-643969Y946924D01*
X-645334Y947444D01*
X-646699Y947184D01*
X-647869Y946404D01*
X-648649Y944584D01*
X-649039Y943024D01*
Y941464D01*
X-648649Y939904D01*
X-647674Y938344D01*
X-646504Y937304D01*
X-645139Y937044D01*
X-643774Y937564D01*
X-642409Y939124D01*
G01X-2081234Y1141044D02*
Y1156644D01*
G01Y1148844D02*
X-2080259Y1150404D01*
X-2079089Y1151184D01*
X-2077919Y1151444D01*
X-2076164Y1150924D01*
X-2074994Y1149884D01*
X-2074214Y1148064D01*
Y1145984D01*
X-2074604Y1143904D01*
X-2075384Y1142344D01*
X-2076749Y1141304D01*
X-2077919Y1141044D01*
X-2079089Y1141304D01*
X-2080259Y1142084D01*
X-2081234Y1143384D01*
G01X-2059824Y1140524D02*
X-2060214Y1140784D01*
Y1141304D01*
X-2059824Y1141564D01*
X-2059434Y1141304D01*
Y1140784D01*
X-2059824Y1140524D01*
G01X-2022464Y1149364D02*
X-2021684Y1150144D01*
X-2021099Y1151444D01*
X-2020709Y1153264D01*
X-2021099Y1154824D01*
X-2021879Y1155864D01*
X-2023244Y1156644D01*
X-2028509D01*
Y1141044D01*
X-2022074D01*
X-2020709Y1142084D01*
X-2019929Y1143644D01*
X-2019539Y1145464D01*
X-2019929Y1147284D01*
X-2021099Y1148844D01*
X-2022464Y1149364D01*
X-2028509D01*
G01X-2006124Y1141044D02*
X-2007294Y1141304D01*
X-2008464Y1142344D01*
X-2009244Y1144164D01*
X-2009634Y1146244D01*
X-2009244Y1148324D01*
X-2008464Y1150144D01*
X-2007294Y1151184D01*
X-2006124Y1151444D01*
X-2004954Y1151184D01*
X-2003784Y1150144D01*
X-2003004Y1148324D01*
X-2002809Y1146244D01*
X-2003004Y1144164D01*
X-2003784Y1142344D01*
X-2004954Y1141304D01*
X-2006124Y1141044D01*
G01X-1984714D02*
Y1151444D01*
G01Y1149624D02*
X-1985494Y1150664D01*
X-1986664Y1151184D01*
X-1988029Y1151444D01*
X-1989394Y1150924D01*
X-1990564Y1149884D01*
X-1991344Y1148324D01*
X-1991734Y1146244D01*
X-1991344Y1144164D01*
X-1990564Y1142604D01*
X-1989394Y1141564D01*
X-1988029Y1141044D01*
X-1986664Y1141304D01*
X-1985494Y1142084D01*
X-1984714Y1143124D01*
G01X-1973054Y1141044D02*
Y1151444D01*
G01Y1149364D02*
X-1972079Y1150404D01*
X-1971104Y1151184D01*
X-1969739Y1151444D01*
X-1968764Y1151184D01*
X-1967594Y1150404D01*
G01X-1948914Y1156644D02*
Y1141044D01*
G01Y1143384D02*
X-1949694Y1142084D01*
X-1950864Y1141304D01*
X-1952229Y1141044D01*
X-1953789Y1141564D01*
X-1954959Y1142864D01*
X-1955739Y1144424D01*
X-1955934Y1146244D01*
X-1955739Y1148064D01*
X-1954959Y1149624D01*
X-1953789Y1150924D01*
X-1952229Y1151444D01*
X-1950864Y1151184D01*
X-1949889Y1150664D01*
X-1948914Y1149624D01*
G01X-1919549Y1142864D02*
X-1918574Y1141824D01*
X-1917209Y1141044D01*
X-1916039D01*
X-1914869Y1141564D01*
X-1914089Y1142344D01*
X-1913699Y1143384D01*
X-1913894Y1144944D01*
X-1914674Y1145724D01*
X-1918184Y1147284D01*
X-1918964Y1149104D01*
X-1918574Y1150404D01*
X-1917794Y1151184D01*
X-1916624Y1151444D01*
X-1915454Y1151184D01*
X-1914284Y1150404D01*
G01X-1902039Y1141044D02*
Y1156644D01*
G01Y1149104D02*
X-1901064Y1150404D01*
X-1900089Y1151184D01*
X-1898529Y1151444D01*
X-1897359Y1151184D01*
X-1895994Y1150144D01*
X-1895409Y1148584D01*
Y1141044D01*
G01X-1877314D02*
Y1151444D01*
G01Y1149624D02*
X-1878094Y1150664D01*
X-1879264Y1151184D01*
X-1880629Y1151444D01*
X-1881994Y1150924D01*
X-1883164Y1149884D01*
X-1883944Y1148324D01*
X-1884334Y1146244D01*
X-1883944Y1144164D01*
X-1883164Y1142604D01*
X-1881994Y1141564D01*
X-1880629Y1141044D01*
X-1879264Y1141304D01*
X-1878094Y1142084D01*
X-1877314Y1143124D01*
G01X-1862924Y1141044D02*
Y1156644D01*
G01X-1845024Y1141044D02*
Y1156644D01*
G01X-1812734Y1141044D02*
Y1156644D01*
G01Y1148844D02*
X-1811759Y1150404D01*
X-1810589Y1151184D01*
X-1809419Y1151444D01*
X-1807664Y1150924D01*
X-1806494Y1149884D01*
X-1805714Y1148064D01*
Y1145984D01*
X-1806104Y1143904D01*
X-1806884Y1142344D01*
X-1808249Y1141304D01*
X-1809419Y1141044D01*
X-1810589Y1141304D01*
X-1811759Y1142084D01*
X-1812734Y1143384D01*
G01X-1794249Y1148064D02*
X-1788009D01*
X-1788594Y1149884D01*
X-1789569Y1150924D01*
X-1790934Y1151444D01*
X-1792299Y1151184D01*
X-1793469Y1150404D01*
X-1794249Y1148584D01*
X-1794639Y1147024D01*
Y1145464D01*
X-1794249Y1143904D01*
X-1793274Y1142344D01*
X-1792104Y1141304D01*
X-1790739Y1141044D01*
X-1789374Y1141564D01*
X-1788009Y1143124D01*
G01X-1758449Y1148064D02*
X-1752209D01*
X-1752794Y1149884D01*
X-1753769Y1150924D01*
X-1755134Y1151444D01*
X-1756499Y1151184D01*
X-1757669Y1150404D01*
X-1758449Y1148584D01*
X-1758839Y1147024D01*
Y1145464D01*
X-1758449Y1143904D01*
X-1757474Y1142344D01*
X-1756304Y1141304D01*
X-1754939Y1141044D01*
X-1753574Y1141564D01*
X-1752209Y1143124D01*
G01X-1737624Y1141044D02*
Y1156644D01*
G01X-1722649Y1148064D02*
X-1716409D01*
X-1716994Y1149884D01*
X-1717969Y1150924D01*
X-1719334Y1151444D01*
X-1720699Y1151184D01*
X-1721869Y1150404D01*
X-1722649Y1148584D01*
X-1723039Y1147024D01*
Y1145464D01*
X-1722649Y1143904D01*
X-1721674Y1142344D01*
X-1720504Y1141304D01*
X-1719139Y1141044D01*
X-1717774Y1141564D01*
X-1716409Y1143124D01*
G01X-1698704Y1150144D02*
X-1700069Y1151184D01*
X-1701239Y1151444D01*
X-1702799Y1150924D01*
X-1703969Y1149884D01*
X-1704749Y1148064D01*
X-1704944Y1146244D01*
X-1704749Y1144424D01*
X-1703969Y1142864D01*
X-1702799Y1141564D01*
X-1701239Y1141044D01*
X-1699874Y1141564D01*
X-1698704Y1142604D01*
G01X-1683924Y1156644D02*
Y1141044D01*
G01X-1686654Y1151444D02*
X-1681194D01*
G01X-1668754Y1141044D02*
Y1151444D01*
G01Y1149364D02*
X-1667779Y1150404D01*
X-1666804Y1151184D01*
X-1665439Y1151444D01*
X-1664464Y1151184D01*
X-1663294Y1150404D01*
G01X-1648124Y1151444D02*
Y1141044D01*
G01Y1155604D02*
X-1648514Y1155864D01*
Y1156384D01*
X-1648124Y1156644D01*
X-1647734Y1156384D01*
Y1155864D01*
X-1648124Y1155604D01*
G01X-1627104Y1150144D02*
X-1628469Y1151184D01*
X-1629639Y1151444D01*
X-1631199Y1150924D01*
X-1632369Y1149884D01*
X-1633149Y1148064D01*
X-1633344Y1146244D01*
X-1633149Y1144424D01*
X-1632369Y1142864D01*
X-1631199Y1141564D01*
X-1629639Y1141044D01*
X-1628274Y1141564D01*
X-1627104Y1142604D01*
G01X-1608814Y1141044D02*
Y1151444D01*
G01Y1149624D02*
X-1609594Y1150664D01*
X-1610764Y1151184D01*
X-1612129Y1151444D01*
X-1613494Y1150924D01*
X-1614664Y1149884D01*
X-1615444Y1148324D01*
X-1615834Y1146244D01*
X-1615444Y1144164D01*
X-1614664Y1142604D01*
X-1613494Y1141564D01*
X-1612129Y1141044D01*
X-1610764Y1141304D01*
X-1609594Y1142084D01*
X-1608814Y1143124D01*
G01X-1594424Y1141044D02*
Y1156644D01*
G01X-1576524Y1141044D02*
Y1156644D01*
G01X-1562719Y1136364D02*
X-1561549Y1135844D01*
X-1559989Y1136364D01*
X-1559014Y1137404D01*
X-1558234Y1138704D01*
X-1557064Y1142864D01*
X-1554529Y1151444D01*
G01X-1560769D02*
X-1557064Y1142864D01*
G01X-1522824Y1156644D02*
Y1141044D01*
G01X-1525554Y1151444D02*
X-1520094D01*
G01X-1507849Y1148064D02*
X-1501609D01*
X-1502194Y1149884D01*
X-1503169Y1150924D01*
X-1504534Y1151444D01*
X-1505899Y1151184D01*
X-1507069Y1150404D01*
X-1507849Y1148584D01*
X-1508239Y1147024D01*
Y1145464D01*
X-1507849Y1143904D01*
X-1506874Y1142344D01*
X-1505704Y1141304D01*
X-1504339Y1141044D01*
X-1502974Y1141564D01*
X-1501609Y1143124D01*
G01X-1489949Y1142864D02*
X-1488974Y1141824D01*
X-1487609Y1141044D01*
X-1486439D01*
X-1485269Y1141564D01*
X-1484489Y1142344D01*
X-1484099Y1143384D01*
X-1484294Y1144944D01*
X-1485074Y1145724D01*
X-1488584Y1147284D01*
X-1489364Y1149104D01*
X-1488974Y1150404D01*
X-1488194Y1151184D01*
X-1487024Y1151444D01*
X-1485854Y1151184D01*
X-1484684Y1150404D01*
G01X-1469124Y1156644D02*
Y1141044D01*
G01X-1471854Y1151444D02*
X-1466394D01*
G01X-1454149Y1148064D02*
X-1447909D01*
X-1448494Y1149884D01*
X-1449469Y1150924D01*
X-1450834Y1151444D01*
X-1452199Y1151184D01*
X-1453369Y1150404D01*
X-1454149Y1148584D01*
X-1454539Y1147024D01*
Y1145464D01*
X-1454149Y1143904D01*
X-1453174Y1142344D01*
X-1452004Y1141304D01*
X-1450639Y1141044D01*
X-1449274Y1141564D01*
X-1447909Y1143124D01*
G01X-1429814Y1156644D02*
Y1141044D01*
G01Y1143384D02*
X-1430594Y1142084D01*
X-1431764Y1141304D01*
X-1433129Y1141044D01*
X-1434689Y1141564D01*
X-1435859Y1142864D01*
X-1436639Y1144424D01*
X-1436834Y1146244D01*
X-1436639Y1148064D01*
X-1435859Y1149624D01*
X-1434689Y1150924D01*
X-1433129Y1151444D01*
X-1431764Y1151184D01*
X-1430789Y1150664D01*
X-1429814Y1149624D01*
G01X-1401034Y1135844D02*
Y1151444D01*
G01Y1149104D02*
X-1400059Y1150404D01*
X-1399084Y1151184D01*
X-1397524Y1151444D01*
X-1396159Y1151184D01*
X-1394794Y1149884D01*
X-1394209Y1148064D01*
X-1394014Y1146244D01*
X-1394209Y1144424D01*
X-1394794Y1142604D01*
X-1395964Y1141564D01*
X-1397524Y1141044D01*
X-1398889Y1141304D01*
X-1400254Y1142084D01*
X-1401034Y1143124D01*
G01X-1382549Y1148064D02*
X-1376309D01*
X-1376894Y1149884D01*
X-1377869Y1150924D01*
X-1379234Y1151444D01*
X-1380599Y1151184D01*
X-1381769Y1150404D01*
X-1382549Y1148584D01*
X-1382939Y1147024D01*
Y1145464D01*
X-1382549Y1143904D01*
X-1381574Y1142344D01*
X-1380404Y1141304D01*
X-1379039Y1141044D01*
X-1377674Y1141564D01*
X-1376309Y1143124D01*
G01X-1364454Y1141044D02*
Y1151444D01*
G01Y1149364D02*
X-1363479Y1150404D01*
X-1362504Y1151184D01*
X-1361139Y1151444D01*
X-1360164Y1151184D01*
X-1358994Y1150404D01*
G01X-1322804Y1150144D02*
X-1324169Y1151184D01*
X-1325339Y1151444D01*
X-1326899Y1150924D01*
X-1328069Y1149884D01*
X-1328849Y1148064D01*
X-1329044Y1146244D01*
X-1328849Y1144424D01*
X-1328069Y1142864D01*
X-1326899Y1141564D01*
X-1325339Y1141044D01*
X-1323974Y1141564D01*
X-1322804Y1142604D01*
G01X-1311339Y1151444D02*
Y1144164D01*
X-1310559Y1142344D01*
X-1309389Y1141304D01*
X-1308024Y1141044D01*
X-1306659Y1141304D01*
X-1305489Y1142344D01*
X-1304709Y1144164D01*
G01Y1141044D02*
Y1151444D01*
G01X-1292854Y1141044D02*
Y1151444D01*
G01Y1149364D02*
X-1291879Y1150404D01*
X-1290904Y1151184D01*
X-1289539Y1151444D01*
X-1288564Y1151184D01*
X-1287394Y1150404D01*
G01X-1274954Y1141044D02*
Y1151444D01*
G01Y1149364D02*
X-1273979Y1150404D01*
X-1273004Y1151184D01*
X-1271639Y1151444D01*
X-1270664Y1151184D01*
X-1269494Y1150404D01*
G01X-1257249Y1148064D02*
X-1251009D01*
X-1251594Y1149884D01*
X-1252569Y1150924D01*
X-1253934Y1151444D01*
X-1255299Y1151184D01*
X-1256469Y1150404D01*
X-1257249Y1148584D01*
X-1257639Y1147024D01*
Y1145464D01*
X-1257249Y1143904D01*
X-1256274Y1142344D01*
X-1255104Y1141304D01*
X-1253739Y1141044D01*
X-1252374Y1141564D01*
X-1251009Y1143124D01*
G01X-1239739Y1141044D02*
Y1151444D01*
G01Y1148844D02*
X-1238959Y1150144D01*
X-1237789Y1151184D01*
X-1236229Y1151444D01*
X-1234864Y1151184D01*
X-1233694Y1150144D01*
X-1233109Y1148324D01*
Y1141044D01*
G01X-1218524Y1156644D02*
Y1141044D01*
G01X-1221254Y1151444D02*
X-1215794D01*
G01X-1185454Y1141044D02*
Y1151444D01*
G01Y1149364D02*
X-1184479Y1150404D01*
X-1183504Y1151184D01*
X-1182139Y1151444D01*
X-1181164Y1151184D01*
X-1179994Y1150404D01*
G01X-1167749Y1148064D02*
X-1161509D01*
X-1162094Y1149884D01*
X-1163069Y1150924D01*
X-1164434Y1151444D01*
X-1165799Y1151184D01*
X-1166969Y1150404D01*
X-1167749Y1148584D01*
X-1168139Y1147024D01*
Y1145464D01*
X-1167749Y1143904D01*
X-1166774Y1142344D01*
X-1165604Y1141304D01*
X-1164239Y1141044D01*
X-1162874Y1141564D01*
X-1161509Y1143124D01*
G01X-1150434Y1151444D02*
X-1146924Y1141044D01*
X-1143414Y1151444D01*
G01X-1129024D02*
Y1141044D01*
G01Y1155604D02*
X-1129414Y1155864D01*
Y1156384D01*
X-1129024Y1156644D01*
X-1128634Y1156384D01*
Y1155864D01*
X-1129024Y1155604D01*
G01X-1114049Y1142864D02*
X-1113074Y1141824D01*
X-1111709Y1141044D01*
X-1110539D01*
X-1109369Y1141564D01*
X-1108589Y1142344D01*
X-1108199Y1143384D01*
X-1108394Y1144944D01*
X-1109174Y1145724D01*
X-1112684Y1147284D01*
X-1113464Y1149104D01*
X-1113074Y1150404D01*
X-1112294Y1151184D01*
X-1111124Y1151444D01*
X-1109954Y1151184D01*
X-1108784Y1150404D01*
G01X-1093224Y1151444D02*
Y1141044D01*
G01Y1155604D02*
X-1093614Y1155864D01*
Y1156384D01*
X-1093224Y1156644D01*
X-1092834Y1156384D01*
Y1155864D01*
X-1093224Y1155604D01*
G01X-1075324Y1141044D02*
X-1076494Y1141304D01*
X-1077664Y1142344D01*
X-1078444Y1144164D01*
X-1078834Y1146244D01*
X-1078444Y1148324D01*
X-1077664Y1150144D01*
X-1076494Y1151184D01*
X-1075324Y1151444D01*
X-1074154Y1151184D01*
X-1072984Y1150144D01*
X-1072204Y1148324D01*
X-1072009Y1146244D01*
X-1072204Y1144164D01*
X-1072984Y1142344D01*
X-1074154Y1141304D01*
X-1075324Y1141044D01*
G01X-1060739D02*
Y1151444D01*
G01Y1148844D02*
X-1059959Y1150144D01*
X-1058789Y1151184D01*
X-1057229Y1151444D01*
X-1055864Y1151184D01*
X-1054694Y1150144D01*
X-1054109Y1148324D01*
Y1141044D01*
G01X-1021624D02*
X-1022794Y1141304D01*
X-1023964Y1142344D01*
X-1024744Y1144164D01*
X-1025134Y1146244D01*
X-1024744Y1148324D01*
X-1023964Y1150144D01*
X-1022794Y1151184D01*
X-1021624Y1151444D01*
X-1020454Y1151184D01*
X-1019284Y1150144D01*
X-1018504Y1148324D01*
X-1018309Y1146244D01*
X-1018504Y1144164D01*
X-1019284Y1142344D01*
X-1020454Y1141304D01*
X-1021624Y1141044D01*
G01X-1004894D02*
Y1154304D01*
X-1004504Y1155604D01*
X-1003724Y1156384D01*
X-1002554Y1156644D01*
X-1001384Y1156124D01*
X-1000799Y1154824D01*
G01X-1003139Y1150404D02*
X-1007039D01*
G01X-970264Y1156644D02*
X-965584D01*
G01X-967924D02*
Y1141044D01*
G01X-970264D02*
X-965584D01*
G01X-953924D02*
Y1156644D01*
X-949244D01*
X-947684Y1155864D01*
X-946514Y1154044D01*
X-946124Y1151964D01*
X-946514Y1149884D01*
X-947489Y1148324D01*
X-949244Y1147544D01*
X-953924D01*
G01X-927834Y1155344D02*
X-929004Y1156124D01*
X-930369Y1156644D01*
X-931929D01*
X-933684Y1155864D01*
X-935049Y1154564D01*
X-936024Y1153004D01*
X-936804Y1150404D01*
X-936999Y1148064D01*
X-936609Y1145724D01*
X-936024Y1144164D01*
X-934854Y1142604D01*
X-933489Y1141564D01*
X-932124Y1141044D01*
X-930759D01*
X-929394Y1141564D01*
X-928224Y1142344D01*
X-927249Y1143384D01*
G01X-900029Y1147544D02*
X-898664Y1149364D01*
X-897494Y1150404D01*
X-895934Y1150924D01*
X-894569Y1150404D01*
X-893594Y1149364D01*
X-892814Y1147804D01*
X-892619Y1145984D01*
X-892814Y1144424D01*
X-893594Y1142864D01*
X-894764Y1141564D01*
X-896129Y1141044D01*
X-897689Y1141564D01*
X-899054Y1143124D01*
X-899834Y1145464D01*
X-900029Y1148064D01*
X-899639Y1151444D01*
X-899054Y1153264D01*
X-898079Y1155084D01*
X-896714Y1156384D01*
X-895349Y1156644D01*
X-893984Y1156124D01*
X-893009Y1154824D01*
G01X-878424Y1156644D02*
X-879984Y1156124D01*
X-881154Y1154824D01*
X-881934Y1153264D01*
X-882519Y1151184D01*
X-882714Y1148844D01*
X-882519Y1146504D01*
X-881934Y1144424D01*
X-881154Y1142864D01*
X-879984Y1141564D01*
X-878424Y1141044D01*
X-876864Y1141564D01*
X-875694Y1142864D01*
X-874914Y1144424D01*
X-874329Y1146504D01*
X-874134Y1148844D01*
X-874329Y1151184D01*
X-874914Y1153264D01*
X-875694Y1154824D01*
X-876864Y1156124D01*
X-878424Y1156644D01*
G01X-860524Y1141044D02*
Y1156644D01*
X-862864Y1153524D01*
G01Y1141044D02*
X-858184D01*
G01X-846329Y1154044D02*
X-845159Y1155604D01*
X-843794Y1156384D01*
X-842234Y1156644D01*
X-840284Y1156124D01*
X-838919Y1154824D01*
X-838529Y1153264D01*
X-838724Y1151704D01*
X-839504Y1150404D01*
X-843404Y1147804D01*
X-845159Y1145984D01*
X-846329Y1143384D01*
X-846719Y1141044D01*
X-838529D01*
G01X-803314D02*
Y1151444D01*
G01Y1149624D02*
X-804094Y1150664D01*
X-805264Y1151184D01*
X-806629Y1151444D01*
X-807994Y1150924D01*
X-809164Y1149884D01*
X-809944Y1148324D01*
X-810334Y1146244D01*
X-809944Y1144164D01*
X-809164Y1142604D01*
X-807994Y1141564D01*
X-806629Y1141044D01*
X-805264Y1141304D01*
X-804094Y1142084D01*
X-803314Y1143124D01*
G01X-792239Y1141044D02*
Y1151444D01*
G01Y1148844D02*
X-791459Y1150144D01*
X-790289Y1151184D01*
X-788729Y1151444D01*
X-787364Y1151184D01*
X-786194Y1150144D01*
X-785609Y1148324D01*
Y1141044D01*
G01X-767514Y1156644D02*
Y1141044D01*
G01Y1143384D02*
X-768294Y1142084D01*
X-769464Y1141304D01*
X-770829Y1141044D01*
X-772389Y1141564D01*
X-773559Y1142864D01*
X-774339Y1144424D01*
X-774534Y1146244D01*
X-774339Y1148064D01*
X-773559Y1149624D01*
X-772389Y1150924D01*
X-770829Y1151444D01*
X-769464Y1151184D01*
X-768489Y1150664D01*
X-767514Y1149624D01*
G01X-737564Y1156644D02*
X-732884D01*
G01X-735224D02*
Y1141044D01*
G01X-737564D02*
X-732884D01*
G01X-721224D02*
Y1156644D01*
X-716544D01*
X-714984Y1155864D01*
X-713814Y1154044D01*
X-713424Y1151964D01*
X-713814Y1149884D01*
X-714789Y1148324D01*
X-716544Y1147544D01*
X-721224D01*
G01X-695134Y1155344D02*
X-696304Y1156124D01*
X-697669Y1156644D01*
X-699229D01*
X-700984Y1155864D01*
X-702349Y1154564D01*
X-703324Y1153004D01*
X-704104Y1150404D01*
X-704299Y1148064D01*
X-703909Y1145724D01*
X-703324Y1144164D01*
X-702154Y1142604D01*
X-700789Y1141564D01*
X-699424Y1141044D01*
X-698059D01*
X-696694Y1141564D01*
X-695524Y1142344D01*
X-694549Y1143384D01*
G01X-666939Y1142864D02*
X-665574Y1141564D01*
X-664014Y1141044D01*
X-662454Y1141564D01*
X-661089Y1143124D01*
X-660114Y1145464D01*
X-659724Y1147804D01*
Y1150664D01*
X-660114Y1153004D01*
X-661089Y1155084D01*
X-662259Y1156124D01*
X-663624Y1156644D01*
X-665184Y1156124D01*
X-666354Y1155084D01*
X-667134Y1153524D01*
X-667524Y1151444D01*
X-667134Y1149624D01*
X-666159Y1147804D01*
X-664989Y1146764D01*
X-663624Y1146504D01*
X-662064Y1147024D01*
X-660894Y1148324D01*
X-659724Y1150664D01*
G01X-649429Y1154044D02*
X-648259Y1155604D01*
X-646894Y1156384D01*
X-645334Y1156644D01*
X-643384Y1156124D01*
X-642019Y1154824D01*
X-641629Y1153264D01*
X-641824Y1151704D01*
X-642604Y1150404D01*
X-646504Y1147804D01*
X-648259Y1145984D01*
X-649429Y1143384D01*
X-649819Y1141044D01*
X-641629D01*
G01X-632114Y1143384D02*
X-630944Y1142084D01*
X-629579Y1141304D01*
X-627824Y1141044D01*
X-626069Y1141564D01*
X-624704Y1142604D01*
X-623729Y1144424D01*
X-623534Y1146504D01*
X-623924Y1148584D01*
X-624899Y1149884D01*
X-626264Y1150924D01*
X-627629Y1151184D01*
X-628994Y1150924D01*
X-630749Y1149884D01*
X-630164Y1156644D01*
X-624899D01*
G01X-613629Y1154044D02*
X-612459Y1155604D01*
X-611094Y1156384D01*
X-609534Y1156644D01*
X-607584Y1156124D01*
X-606219Y1154824D01*
X-605829Y1153264D01*
X-606024Y1151704D01*
X-606804Y1150404D01*
X-610704Y1147804D01*
X-612459Y1145984D01*
X-613629Y1143384D01*
X-614019Y1141044D01*
X-605829D01*
G01X-571004Y1150144D02*
X-572369Y1151184D01*
X-573539Y1151444D01*
X-575099Y1150924D01*
X-576269Y1149884D01*
X-577049Y1148064D01*
X-577244Y1146244D01*
X-577049Y1144424D01*
X-576269Y1142864D01*
X-575099Y1141564D01*
X-573539Y1141044D01*
X-572174Y1141564D01*
X-571004Y1142604D01*
G01X-556224Y1141044D02*
Y1156644D01*
G01X-534814Y1141044D02*
Y1151444D01*
G01Y1149624D02*
X-535594Y1150664D01*
X-536764Y1151184D01*
X-538129Y1151444D01*
X-539494Y1150924D01*
X-540664Y1149884D01*
X-541444Y1148324D01*
X-541834Y1146244D01*
X-541444Y1144164D01*
X-540664Y1142604D01*
X-539494Y1141564D01*
X-538129Y1141044D01*
X-536764Y1141304D01*
X-535594Y1142084D01*
X-534814Y1143124D01*
G01X-523349Y1142864D02*
X-522374Y1141824D01*
X-521009Y1141044D01*
X-519839D01*
X-518669Y1141564D01*
X-517889Y1142344D01*
X-517499Y1143384D01*
X-517694Y1144944D01*
X-518474Y1145724D01*
X-521984Y1147284D01*
X-522764Y1149104D01*
X-522374Y1150404D01*
X-521594Y1151184D01*
X-520424Y1151444D01*
X-519254Y1151184D01*
X-518084Y1150404D01*
G01X-505449Y1142864D02*
X-504474Y1141824D01*
X-503109Y1141044D01*
X-501939D01*
X-500769Y1141564D01*
X-499989Y1142344D01*
X-499599Y1143384D01*
X-499794Y1144944D01*
X-500574Y1145724D01*
X-504084Y1147284D01*
X-504864Y1149104D01*
X-504474Y1150404D01*
X-503694Y1151184D01*
X-502524Y1151444D01*
X-501354Y1151184D01*
X-500184Y1150404D01*
G01X-469064Y1156644D02*
X-464384D01*
G01X-466724D02*
Y1141044D01*
G01X-469064D02*
X-464384D01*
G01X-451164Y1156644D02*
X-446484D01*
G01X-448824D02*
Y1141044D01*
G01X-451164D02*
X-446484D01*
G01X-430924Y1140524D02*
X-431314Y1140784D01*
Y1141304D01*
X-430924Y1141564D01*
X-430534Y1141304D01*
Y1140784D01*
X-430924Y1140524D01*
G01X-2074214Y1209044D02*
Y1219444D01*
G01Y1217624D02*
X-2074994Y1218664D01*
X-2076164Y1219184D01*
X-2077529Y1219444D01*
X-2078894Y1218924D01*
X-2080064Y1217884D01*
X-2080844Y1216324D01*
X-2081234Y1214244D01*
X-2080844Y1212164D01*
X-2080064Y1210604D01*
X-2078894Y1209564D01*
X-2077529Y1209044D01*
X-2076164Y1209304D01*
X-2074994Y1210084D01*
X-2074214Y1211124D01*
G01X-2059824Y1208524D02*
X-2060214Y1208784D01*
Y1209304D01*
X-2059824Y1209564D01*
X-2059434Y1209304D01*
Y1208784D01*
X-2059824Y1208524D01*
G01X-2022464Y1217364D02*
X-2021684Y1218144D01*
X-2021099Y1219444D01*
X-2020709Y1221264D01*
X-2021099Y1222824D01*
X-2021879Y1223864D01*
X-2023244Y1224644D01*
X-2028509D01*
Y1209044D01*
X-2022074D01*
X-2020709Y1210084D01*
X-2019929Y1211644D01*
X-2019539Y1213464D01*
X-2019929Y1215284D01*
X-2021099Y1216844D01*
X-2022464Y1217364D01*
X-2028509D01*
G01X-2006124Y1209044D02*
X-2007294Y1209304D01*
X-2008464Y1210344D01*
X-2009244Y1212164D01*
X-2009634Y1214244D01*
X-2009244Y1216324D01*
X-2008464Y1218144D01*
X-2007294Y1219184D01*
X-2006124Y1219444D01*
X-2004954Y1219184D01*
X-2003784Y1218144D01*
X-2003004Y1216324D01*
X-2002809Y1214244D01*
X-2003004Y1212164D01*
X-2003784Y1210344D01*
X-2004954Y1209304D01*
X-2006124Y1209044D01*
G01X-1984714D02*
Y1219444D01*
G01Y1217624D02*
X-1985494Y1218664D01*
X-1986664Y1219184D01*
X-1988029Y1219444D01*
X-1989394Y1218924D01*
X-1990564Y1217884D01*
X-1991344Y1216324D01*
X-1991734Y1214244D01*
X-1991344Y1212164D01*
X-1990564Y1210604D01*
X-1989394Y1209564D01*
X-1988029Y1209044D01*
X-1986664Y1209304D01*
X-1985494Y1210084D01*
X-1984714Y1211124D01*
G01X-1973054Y1209044D02*
Y1219444D01*
G01Y1217364D02*
X-1972079Y1218404D01*
X-1971104Y1219184D01*
X-1969739Y1219444D01*
X-1968764Y1219184D01*
X-1967594Y1218404D01*
G01X-1948914Y1224644D02*
Y1209044D01*
G01Y1211384D02*
X-1949694Y1210084D01*
X-1950864Y1209304D01*
X-1952229Y1209044D01*
X-1953789Y1209564D01*
X-1954959Y1210864D01*
X-1955739Y1212424D01*
X-1955934Y1214244D01*
X-1955739Y1216064D01*
X-1954959Y1217624D01*
X-1953789Y1218924D01*
X-1952229Y1219444D01*
X-1950864Y1219184D01*
X-1949889Y1218664D01*
X-1948914Y1217624D01*
G01X-1919549Y1210864D02*
X-1918574Y1209824D01*
X-1917209Y1209044D01*
X-1916039D01*
X-1914869Y1209564D01*
X-1914089Y1210344D01*
X-1913699Y1211384D01*
X-1913894Y1212944D01*
X-1914674Y1213724D01*
X-1918184Y1215284D01*
X-1918964Y1217104D01*
X-1918574Y1218404D01*
X-1917794Y1219184D01*
X-1916624Y1219444D01*
X-1915454Y1219184D01*
X-1914284Y1218404D01*
G01X-1902039Y1209044D02*
Y1224644D01*
G01Y1217104D02*
X-1901064Y1218404D01*
X-1900089Y1219184D01*
X-1898529Y1219444D01*
X-1897359Y1219184D01*
X-1895994Y1218144D01*
X-1895409Y1216584D01*
Y1209044D01*
G01X-1877314D02*
Y1219444D01*
G01Y1217624D02*
X-1878094Y1218664D01*
X-1879264Y1219184D01*
X-1880629Y1219444D01*
X-1881994Y1218924D01*
X-1883164Y1217884D01*
X-1883944Y1216324D01*
X-1884334Y1214244D01*
X-1883944Y1212164D01*
X-1883164Y1210604D01*
X-1881994Y1209564D01*
X-1880629Y1209044D01*
X-1879264Y1209304D01*
X-1878094Y1210084D01*
X-1877314Y1211124D01*
G01X-1862924Y1209044D02*
Y1224644D01*
G01X-1845024Y1209044D02*
Y1224644D01*
G01X-1812734Y1209044D02*
Y1224644D01*
G01Y1216844D02*
X-1811759Y1218404D01*
X-1810589Y1219184D01*
X-1809419Y1219444D01*
X-1807664Y1218924D01*
X-1806494Y1217884D01*
X-1805714Y1216064D01*
Y1213984D01*
X-1806104Y1211904D01*
X-1806884Y1210344D01*
X-1808249Y1209304D01*
X-1809419Y1209044D01*
X-1810589Y1209304D01*
X-1811759Y1210084D01*
X-1812734Y1211384D01*
G01X-1794249Y1216064D02*
X-1788009D01*
X-1788594Y1217884D01*
X-1789569Y1218924D01*
X-1790934Y1219444D01*
X-1792299Y1219184D01*
X-1793469Y1218404D01*
X-1794249Y1216584D01*
X-1794639Y1215024D01*
Y1213464D01*
X-1794249Y1211904D01*
X-1793274Y1210344D01*
X-1792104Y1209304D01*
X-1790739Y1209044D01*
X-1789374Y1209564D01*
X-1788009Y1211124D01*
G01X-1759034Y1209044D02*
Y1224644D01*
G01Y1216844D02*
X-1758059Y1218404D01*
X-1756889Y1219184D01*
X-1755719Y1219444D01*
X-1753964Y1218924D01*
X-1752794Y1217884D01*
X-1752014Y1216064D01*
Y1213984D01*
X-1752404Y1211904D01*
X-1753184Y1210344D01*
X-1754549Y1209304D01*
X-1755719Y1209044D01*
X-1756889Y1209304D01*
X-1758059Y1210084D01*
X-1759034Y1211384D01*
G01X-1740939Y1219444D02*
Y1212164D01*
X-1740159Y1210344D01*
X-1738989Y1209304D01*
X-1737624Y1209044D01*
X-1736259Y1209304D01*
X-1735089Y1210344D01*
X-1734309Y1212164D01*
G01Y1209044D02*
Y1219444D01*
G01X-1719724D02*
Y1209044D01*
G01Y1223604D02*
X-1720114Y1223864D01*
Y1224384D01*
X-1719724Y1224644D01*
X-1719334Y1224384D01*
Y1223864D01*
X-1719724Y1223604D01*
G01X-1701824Y1209044D02*
Y1224644D01*
G01X-1683924D02*
Y1209044D01*
G01X-1686654Y1219444D02*
X-1681194D01*
G01X-1651634Y1203844D02*
Y1219444D01*
G01Y1217104D02*
X-1650659Y1218404D01*
X-1649684Y1219184D01*
X-1648124Y1219444D01*
X-1646759Y1219184D01*
X-1645394Y1217884D01*
X-1644809Y1216064D01*
X-1644614Y1214244D01*
X-1644809Y1212424D01*
X-1645394Y1210604D01*
X-1646564Y1209564D01*
X-1648124Y1209044D01*
X-1649489Y1209304D01*
X-1650854Y1210084D01*
X-1651634Y1211124D01*
G01X-1633149Y1216064D02*
X-1626909D01*
X-1627494Y1217884D01*
X-1628469Y1218924D01*
X-1629834Y1219444D01*
X-1631199Y1219184D01*
X-1632369Y1218404D01*
X-1633149Y1216584D01*
X-1633539Y1215024D01*
Y1213464D01*
X-1633149Y1211904D01*
X-1632174Y1210344D01*
X-1631004Y1209304D01*
X-1629639Y1209044D01*
X-1628274Y1209564D01*
X-1626909Y1211124D01*
G01X-1615054Y1209044D02*
Y1219444D01*
G01Y1217364D02*
X-1614079Y1218404D01*
X-1613104Y1219184D01*
X-1611739Y1219444D01*
X-1610764Y1219184D01*
X-1609594Y1218404D01*
G01X-1578864Y1224644D02*
X-1574184D01*
G01X-1576524D02*
Y1209044D01*
G01X-1578864D02*
X-1574184D01*
G01X-1562524D02*
Y1224644D01*
X-1557844D01*
X-1556284Y1223864D01*
X-1555114Y1222044D01*
X-1554724Y1219964D01*
X-1555114Y1217884D01*
X-1556089Y1216324D01*
X-1557844Y1215544D01*
X-1562524D01*
G01X-1536434Y1223344D02*
X-1537604Y1224124D01*
X-1538969Y1224644D01*
X-1540529D01*
X-1542284Y1223864D01*
X-1543649Y1222564D01*
X-1544624Y1221004D01*
X-1545404Y1218404D01*
X-1545599Y1216064D01*
X-1545209Y1213724D01*
X-1544624Y1212164D01*
X-1543454Y1210604D01*
X-1542089Y1209564D01*
X-1540724Y1209044D01*
X-1539359D01*
X-1537994Y1209564D01*
X-1536824Y1210344D01*
X-1535849Y1211384D01*
G01X-1525359Y1214244D02*
X-1520289D01*
G01X-1509799Y1209044D02*
X-1504924Y1224644D01*
X-1500049Y1209044D01*
G01X-1501804Y1214504D02*
X-1508044D01*
G01X-1489559Y1214244D02*
X-1484489D01*
G01X-1472829Y1215544D02*
X-1471464Y1217364D01*
X-1470294Y1218404D01*
X-1468734Y1218924D01*
X-1467369Y1218404D01*
X-1466394Y1217364D01*
X-1465614Y1215804D01*
X-1465419Y1213984D01*
X-1465614Y1212424D01*
X-1466394Y1210864D01*
X-1467564Y1209564D01*
X-1468929Y1209044D01*
X-1470489Y1209564D01*
X-1471854Y1211124D01*
X-1472634Y1213464D01*
X-1472829Y1216064D01*
X-1472439Y1219444D01*
X-1471854Y1221264D01*
X-1470879Y1223084D01*
X-1469514Y1224384D01*
X-1468149Y1224644D01*
X-1466784Y1224124D01*
X-1465809Y1222824D01*
G01X-1451224Y1224644D02*
X-1452784Y1224124D01*
X-1453954Y1222824D01*
X-1454734Y1221264D01*
X-1455319Y1219184D01*
X-1455514Y1216844D01*
X-1455319Y1214504D01*
X-1454734Y1212424D01*
X-1453954Y1210864D01*
X-1452784Y1209564D01*
X-1451224Y1209044D01*
X-1449664Y1209564D01*
X-1448494Y1210864D01*
X-1447714Y1212424D01*
X-1447129Y1214504D01*
X-1446934Y1216844D01*
X-1447129Y1219184D01*
X-1447714Y1221264D01*
X-1448494Y1222824D01*
X-1449664Y1224124D01*
X-1451224Y1224644D01*
G01X-1433324D02*
X-1434884Y1224124D01*
X-1436054Y1222824D01*
X-1436834Y1221264D01*
X-1437419Y1219184D01*
X-1437614Y1216844D01*
X-1437419Y1214504D01*
X-1436834Y1212424D01*
X-1436054Y1210864D01*
X-1434884Y1209564D01*
X-1433324Y1209044D01*
X-1431764Y1209564D01*
X-1430594Y1210864D01*
X-1429814Y1212424D01*
X-1429229Y1214504D01*
X-1429034Y1216844D01*
X-1429229Y1219184D01*
X-1429814Y1221264D01*
X-1430594Y1222824D01*
X-1431764Y1224124D01*
X-1433324Y1224644D01*
G01X-1394014Y1209044D02*
Y1219444D01*
G01Y1217624D02*
X-1394794Y1218664D01*
X-1395964Y1219184D01*
X-1397329Y1219444D01*
X-1398694Y1218924D01*
X-1399864Y1217884D01*
X-1400644Y1216324D01*
X-1401034Y1214244D01*
X-1400644Y1212164D01*
X-1399864Y1210604D01*
X-1398694Y1209564D01*
X-1397329Y1209044D01*
X-1395964Y1209304D01*
X-1394794Y1210084D01*
X-1394014Y1211124D01*
G01X-1382939Y1209044D02*
Y1219444D01*
G01Y1216844D02*
X-1382159Y1218144D01*
X-1380989Y1219184D01*
X-1379429Y1219444D01*
X-1378064Y1219184D01*
X-1376894Y1218144D01*
X-1376309Y1216324D01*
Y1209044D01*
G01X-1358214Y1224644D02*
Y1209044D01*
G01Y1211384D02*
X-1358994Y1210084D01*
X-1360164Y1209304D01*
X-1361529Y1209044D01*
X-1363089Y1209564D01*
X-1364259Y1210864D01*
X-1365039Y1212424D01*
X-1365234Y1214244D01*
X-1365039Y1216064D01*
X-1364259Y1217624D01*
X-1363089Y1218924D01*
X-1361529Y1219444D01*
X-1360164Y1219184D01*
X-1359189Y1218664D01*
X-1358214Y1217624D01*
G01X-1328264Y1224644D02*
X-1323584D01*
G01X-1325924D02*
Y1209044D01*
G01X-1328264D02*
X-1323584D01*
G01X-1311924D02*
Y1224644D01*
X-1307244D01*
X-1305684Y1223864D01*
X-1304514Y1222044D01*
X-1304124Y1219964D01*
X-1304514Y1217884D01*
X-1305489Y1216324D01*
X-1307244Y1215544D01*
X-1311924D01*
G01X-1285834Y1223344D02*
X-1287004Y1224124D01*
X-1288369Y1224644D01*
X-1289929D01*
X-1291684Y1223864D01*
X-1293049Y1222564D01*
X-1294024Y1221004D01*
X-1294804Y1218404D01*
X-1294999Y1216064D01*
X-1294609Y1213724D01*
X-1294024Y1212164D01*
X-1292854Y1210604D01*
X-1291489Y1209564D01*
X-1290124Y1209044D01*
X-1288759D01*
X-1287394Y1209564D01*
X-1286224Y1210344D01*
X-1285249Y1211384D01*
G01X-1275929Y1215544D02*
X-1274564Y1217364D01*
X-1273394Y1218404D01*
X-1271834Y1218924D01*
X-1270469Y1218404D01*
X-1269494Y1217364D01*
X-1268714Y1215804D01*
X-1268519Y1213984D01*
X-1268714Y1212424D01*
X-1269494Y1210864D01*
X-1270664Y1209564D01*
X-1272029Y1209044D01*
X-1273589Y1209564D01*
X-1274954Y1211124D01*
X-1275734Y1213464D01*
X-1275929Y1216064D01*
X-1275539Y1219444D01*
X-1274954Y1221264D01*
X-1273979Y1223084D01*
X-1272614Y1224384D01*
X-1271249Y1224644D01*
X-1269884Y1224124D01*
X-1268909Y1222824D01*
G01X-1254324Y1224644D02*
X-1255884Y1224124D01*
X-1257054Y1222824D01*
X-1257834Y1221264D01*
X-1258419Y1219184D01*
X-1258614Y1216844D01*
X-1258419Y1214504D01*
X-1257834Y1212424D01*
X-1257054Y1210864D01*
X-1255884Y1209564D01*
X-1254324Y1209044D01*
X-1252764Y1209564D01*
X-1251594Y1210864D01*
X-1250814Y1212424D01*
X-1250229Y1214504D01*
X-1250034Y1216844D01*
X-1250229Y1219184D01*
X-1250814Y1221264D01*
X-1251594Y1222824D01*
X-1252764Y1224124D01*
X-1254324Y1224644D01*
G01X-1236424Y1209044D02*
Y1224644D01*
X-1238764Y1221524D01*
G01Y1209044D02*
X-1234084D01*
G01X-1222229Y1222044D02*
X-1221059Y1223604D01*
X-1219694Y1224384D01*
X-1218134Y1224644D01*
X-1216184Y1224124D01*
X-1214819Y1222824D01*
X-1214429Y1221264D01*
X-1214624Y1219704D01*
X-1215404Y1218404D01*
X-1219304Y1215804D01*
X-1221059Y1213984D01*
X-1222229Y1211384D01*
X-1222619Y1209044D01*
X-1214429D01*
G01X-1201014Y1206184D02*
X-1200234Y1209564D01*
G01X-1161704Y1218144D02*
X-1163069Y1219184D01*
X-1164239Y1219444D01*
X-1165799Y1218924D01*
X-1166969Y1217884D01*
X-1167749Y1216064D01*
X-1167944Y1214244D01*
X-1167749Y1212424D01*
X-1166969Y1210864D01*
X-1165799Y1209564D01*
X-1164239Y1209044D01*
X-1162874Y1209564D01*
X-1161704Y1210604D01*
G01X-1146924Y1209044D02*
Y1224644D01*
G01X-1125514Y1209044D02*
Y1219444D01*
G01Y1217624D02*
X-1126294Y1218664D01*
X-1127464Y1219184D01*
X-1128829Y1219444D01*
X-1130194Y1218924D01*
X-1131364Y1217884D01*
X-1132144Y1216324D01*
X-1132534Y1214244D01*
X-1132144Y1212164D01*
X-1131364Y1210604D01*
X-1130194Y1209564D01*
X-1128829Y1209044D01*
X-1127464Y1209304D01*
X-1126294Y1210084D01*
X-1125514Y1211124D01*
G01X-1114049Y1210864D02*
X-1113074Y1209824D01*
X-1111709Y1209044D01*
X-1110539D01*
X-1109369Y1209564D01*
X-1108589Y1210344D01*
X-1108199Y1211384D01*
X-1108394Y1212944D01*
X-1109174Y1213724D01*
X-1112684Y1215284D01*
X-1113464Y1217104D01*
X-1113074Y1218404D01*
X-1112294Y1219184D01*
X-1111124Y1219444D01*
X-1109954Y1219184D01*
X-1108784Y1218404D01*
G01X-1096149Y1210864D02*
X-1095174Y1209824D01*
X-1093809Y1209044D01*
X-1092639D01*
X-1091469Y1209564D01*
X-1090689Y1210344D01*
X-1090299Y1211384D01*
X-1090494Y1212944D01*
X-1091274Y1213724D01*
X-1094784Y1215284D01*
X-1095564Y1217104D01*
X-1095174Y1218404D01*
X-1094394Y1219184D01*
X-1093224Y1219444D01*
X-1092054Y1219184D01*
X-1090884Y1218404D01*
G01X-1059764Y1224644D02*
X-1055084D01*
G01X-1057424D02*
Y1209044D01*
G01X-1059764D02*
X-1055084D01*
G01X-1041864Y1224644D02*
X-1037184D01*
G01X-1039524D02*
Y1209044D01*
G01X-1041864D02*
X-1037184D01*
G01X-1022014Y1206184D02*
X-1021234Y1209564D01*
G01X-985824Y1209044D02*
Y1224644D01*
G01X-964414Y1209044D02*
Y1219444D01*
G01Y1217624D02*
X-965194Y1218664D01*
X-966364Y1219184D01*
X-967729Y1219444D01*
X-969094Y1218924D01*
X-970264Y1217884D01*
X-971044Y1216324D01*
X-971434Y1214244D01*
X-971044Y1212164D01*
X-970264Y1210604D01*
X-969094Y1209564D01*
X-967729Y1209044D01*
X-966364Y1209304D01*
X-965194Y1210084D01*
X-964414Y1211124D01*
G01X-950024Y1224644D02*
Y1209044D01*
G01X-952754Y1219444D02*
X-947294D01*
G01X-935049Y1216064D02*
X-928809D01*
X-929394Y1217884D01*
X-930369Y1218924D01*
X-931734Y1219444D01*
X-933099Y1219184D01*
X-934269Y1218404D01*
X-935049Y1216584D01*
X-935439Y1215024D01*
Y1213464D01*
X-935049Y1211904D01*
X-934074Y1210344D01*
X-932904Y1209304D01*
X-931539Y1209044D01*
X-930174Y1209564D01*
X-928809Y1211124D01*
G01X-917149Y1210864D02*
X-916174Y1209824D01*
X-914809Y1209044D01*
X-913639D01*
X-912469Y1209564D01*
X-911689Y1210344D01*
X-911299Y1211384D01*
X-911494Y1212944D01*
X-912274Y1213724D01*
X-915784Y1215284D01*
X-916564Y1217104D01*
X-916174Y1218404D01*
X-915394Y1219184D01*
X-914224Y1219444D01*
X-913054Y1219184D01*
X-911884Y1218404D01*
G01X-896324Y1224644D02*
Y1209044D01*
G01X-899054Y1219444D02*
X-893594D01*
G01X-863254Y1209044D02*
Y1219444D01*
G01Y1217364D02*
X-862279Y1218404D01*
X-861304Y1219184D01*
X-859939Y1219444D01*
X-858964Y1219184D01*
X-857794Y1218404D01*
G01X-845549Y1216064D02*
X-839309D01*
X-839894Y1217884D01*
X-840869Y1218924D01*
X-842234Y1219444D01*
X-843599Y1219184D01*
X-844769Y1218404D01*
X-845549Y1216584D01*
X-845939Y1215024D01*
Y1213464D01*
X-845549Y1211904D01*
X-844574Y1210344D01*
X-843404Y1209304D01*
X-842039Y1209044D01*
X-840674Y1209564D01*
X-839309Y1211124D01*
G01X-828234Y1219444D02*
X-824724Y1209044D01*
X-821214Y1219444D01*
G01X-806824D02*
Y1209044D01*
G01Y1223604D02*
X-807214Y1223864D01*
Y1224384D01*
X-806824Y1224644D01*
X-806434Y1224384D01*
Y1223864D01*
X-806824Y1223604D01*
G01X-791849Y1210864D02*
X-790874Y1209824D01*
X-789509Y1209044D01*
X-788339D01*
X-787169Y1209564D01*
X-786389Y1210344D01*
X-785999Y1211384D01*
X-786194Y1212944D01*
X-786974Y1213724D01*
X-790484Y1215284D01*
X-791264Y1217104D01*
X-790874Y1218404D01*
X-790094Y1219184D01*
X-788924Y1219444D01*
X-787754Y1219184D01*
X-786584Y1218404D01*
G01X-771024Y1219444D02*
Y1209044D01*
G01Y1223604D02*
X-771414Y1223864D01*
Y1224384D01*
X-771024Y1224644D01*
X-770634Y1224384D01*
Y1223864D01*
X-771024Y1223604D01*
G01X-753124Y1209044D02*
X-754294Y1209304D01*
X-755464Y1210344D01*
X-756244Y1212164D01*
X-756634Y1214244D01*
X-756244Y1216324D01*
X-755464Y1218144D01*
X-754294Y1219184D01*
X-753124Y1219444D01*
X-751954Y1219184D01*
X-750784Y1218144D01*
X-750004Y1216324D01*
X-749809Y1214244D01*
X-750004Y1212164D01*
X-750784Y1210344D01*
X-751954Y1209304D01*
X-753124Y1209044D01*
G01X-738539D02*
Y1219444D01*
G01Y1216844D02*
X-737759Y1218144D01*
X-736589Y1219184D01*
X-735029Y1219444D01*
X-733664Y1219184D01*
X-732494Y1218144D01*
X-731909Y1216324D01*
Y1209044D01*
G01X-717324Y1208524D02*
X-717714Y1208784D01*
Y1209304D01*
X-717324Y1209564D01*
X-716934Y1209304D01*
Y1208784D01*
X-717324Y1208524D01*
G01X-2075650Y-254400D02*
Y-270000D01*
G01X-2080135Y-254400D02*
X-2071165D01*
G01X-2057750Y-270000D02*
X-2059310Y-269740D01*
X-2060675Y-268700D01*
X-2061845Y-267140D01*
X-2062625Y-265320D01*
X-2063015Y-263240D01*
Y-261160D01*
X-2062625Y-259080D01*
X-2061845Y-257260D01*
X-2060675Y-255700D01*
X-2059310Y-254660D01*
X-2057750Y-254400D01*
X-2056190Y-254660D01*
X-2054825Y-255700D01*
X-2053655Y-257260D01*
X-2052875Y-259080D01*
X-2052485Y-261160D01*
Y-263240D01*
X-2052875Y-265320D01*
X-2053655Y-267140D01*
X-2054825Y-268700D01*
X-2056190Y-269740D01*
X-2057750Y-270000D01*
G01X-2043750D02*
Y-254400D01*
X-2039070D01*
X-2037510Y-255180D01*
X-2036340Y-257000D01*
X-2035950Y-259080D01*
X-2036340Y-261160D01*
X-2037315Y-262720D01*
X-2039070Y-263500D01*
X-2043750D01*
G01X-2008145Y-267920D02*
X-2006585Y-269220D01*
X-2004830Y-270000D01*
X-2003270D01*
X-2001710Y-269220D01*
X-2000540Y-267920D01*
X-1999955Y-266100D01*
X-2000345Y-264280D01*
X-2001320Y-262720D01*
X-2003075Y-261680D01*
X-2005415Y-261160D01*
X-2006780Y-260120D01*
X-2007365Y-258300D01*
X-2006975Y-256480D01*
X-2006000Y-255180D01*
X-2004635Y-254400D01*
X-2003270D01*
X-2001905Y-254920D01*
X-2000735Y-256220D01*
G01X-1988490Y-254400D02*
X-1983810D01*
G01X-1986150D02*
Y-270000D01*
G01X-1988490D02*
X-1983810D01*
G01X-1972540D02*
Y-254400D01*
X-1968640D01*
X-1967080Y-255180D01*
X-1965910Y-256220D01*
X-1964935Y-257780D01*
X-1964155Y-259600D01*
X-1963960Y-262200D01*
X-1964155Y-264800D01*
X-1964935Y-266620D01*
X-1965910Y-268180D01*
X-1967080Y-269220D01*
X-1968640Y-270000D01*
X-1972540D01*
G01X-1946450D02*
X-1954250D01*
Y-254400D01*
X-1946450D01*
G01X-1949570Y-261940D02*
X-1954250D01*
G01X-1932450Y-270520D02*
X-1932840Y-270260D01*
Y-269740D01*
X-1932450Y-269480D01*
X-1932060Y-269740D01*
Y-270260D01*
X-1932450Y-270520D01*
G01Y-263500D02*
X-1932840Y-263240D01*
Y-262720D01*
X-1932450Y-262460D01*
X-1932060Y-262720D01*
Y-263240D01*
X-1932450Y-263500D01*
G01X-1900160Y-270000D02*
Y-254400D01*
G01Y-262200D02*
X-1899185Y-260640D01*
X-1898015Y-259860D01*
X-1896845Y-259600D01*
X-1895090Y-260120D01*
X-1893920Y-261160D01*
X-1893140Y-262980D01*
Y-265060D01*
X-1893530Y-267140D01*
X-1894310Y-268700D01*
X-1895675Y-269740D01*
X-1896845Y-270000D01*
X-1898015Y-269740D01*
X-1899185Y-268960D01*
X-1900160Y-267660D01*
G01X-1875240Y-254400D02*
Y-270000D01*
G01Y-267660D02*
X-1876020Y-268960D01*
X-1877190Y-269740D01*
X-1878555Y-270000D01*
X-1880115Y-269480D01*
X-1881285Y-268180D01*
X-1882065Y-266620D01*
X-1882260Y-264800D01*
X-1882065Y-262980D01*
X-1881285Y-261420D01*
X-1880115Y-260120D01*
X-1878555Y-259600D01*
X-1877190Y-259860D01*
X-1876215Y-260380D01*
X-1875240Y-261420D01*
G01X-1866700Y-275200D02*
X-1855000D01*
G01X-1842950Y-270000D02*
Y-254400D01*
X-1845290Y-257520D01*
G01Y-270000D02*
X-1840610D01*
G01X-1827585Y-264800D02*
X-1822515D01*
G01X-1807540Y-270000D02*
X-1807150Y-266620D01*
X-1806565Y-263760D01*
X-1805785Y-261160D01*
X-1804810Y-258300D01*
X-1803250Y-254400D01*
X-1811050D01*
G01X-1789640Y-272860D02*
X-1788860Y-269480D01*
G01X-1758520Y-270000D02*
Y-254400D01*
X-1753450Y-267400D01*
X-1748380Y-254400D01*
Y-270000D01*
G01X-1738865Y-259600D02*
Y-266880D01*
X-1738085Y-268700D01*
X-1736915Y-269740D01*
X-1735550Y-270000D01*
X-1734185Y-269740D01*
X-1733015Y-268700D01*
X-1732235Y-266880D01*
G01Y-270000D02*
Y-259600D01*
G01X-1720575Y-268180D02*
X-1719600Y-269220D01*
X-1718235Y-270000D01*
X-1717065D01*
X-1715895Y-269480D01*
X-1715115Y-268700D01*
X-1714725Y-267660D01*
X-1714920Y-266100D01*
X-1715700Y-265320D01*
X-1719210Y-263760D01*
X-1719990Y-261940D01*
X-1719600Y-260640D01*
X-1718820Y-259860D01*
X-1717650Y-259600D01*
X-1716480Y-259860D01*
X-1715310Y-260640D01*
G01X-1699750Y-254400D02*
Y-270000D01*
G01X-1702480Y-259600D02*
X-1697020D01*
G01X-1667265Y-270000D02*
Y-259600D01*
G01Y-262200D02*
X-1666485Y-260900D01*
X-1665315Y-259860D01*
X-1663755Y-259600D01*
X-1662390Y-259860D01*
X-1661220Y-260900D01*
X-1660635Y-262720D01*
Y-270000D01*
G01X-1646050D02*
X-1647220Y-269740D01*
X-1648390Y-268700D01*
X-1649170Y-266880D01*
X-1649560Y-264800D01*
X-1649170Y-262720D01*
X-1648390Y-260900D01*
X-1647220Y-259860D01*
X-1646050Y-259600D01*
X-1644880Y-259860D01*
X-1643710Y-260900D01*
X-1642930Y-262720D01*
X-1642735Y-264800D01*
X-1642930Y-266880D01*
X-1643710Y-268700D01*
X-1644880Y-269740D01*
X-1646050Y-270000D01*
G01X-1628150Y-254400D02*
Y-270000D01*
G01X-1630880Y-259600D02*
X-1625420D01*
G01X-1589230Y-260900D02*
X-1590595Y-259860D01*
X-1591765Y-259600D01*
X-1593325Y-260120D01*
X-1594495Y-261160D01*
X-1595275Y-262980D01*
X-1595470Y-264800D01*
X-1595275Y-266620D01*
X-1594495Y-268180D01*
X-1593325Y-269480D01*
X-1591765Y-270000D01*
X-1590400Y-269480D01*
X-1589230Y-268440D01*
G01X-1577765Y-259600D02*
Y-266880D01*
X-1576985Y-268700D01*
X-1575815Y-269740D01*
X-1574450Y-270000D01*
X-1573085Y-269740D01*
X-1571915Y-268700D01*
X-1571135Y-266880D01*
G01Y-270000D02*
Y-259600D01*
G01X-1556550Y-254400D02*
Y-270000D01*
G01X-1559280Y-259600D02*
X-1553820D01*
G01X-1520750Y-270000D02*
Y-254400D01*
G01X-1499340Y-270000D02*
Y-259600D01*
G01Y-261420D02*
X-1500120Y-260380D01*
X-1501290Y-259860D01*
X-1502655Y-259600D01*
X-1504020Y-260120D01*
X-1505190Y-261160D01*
X-1505970Y-262720D01*
X-1506360Y-264800D01*
X-1505970Y-266880D01*
X-1505190Y-268440D01*
X-1504020Y-269480D01*
X-1502655Y-270000D01*
X-1501290Y-269740D01*
X-1500120Y-268960D01*
X-1499340Y-267920D01*
G01X-1489045Y-274680D02*
X-1487875Y-275200D01*
X-1486315Y-274680D01*
X-1485340Y-273640D01*
X-1484560Y-272340D01*
X-1483390Y-268180D01*
X-1480855Y-259600D01*
G01X-1487095D02*
X-1483390Y-268180D01*
G01X-1469975Y-262980D02*
X-1463735D01*
X-1464320Y-261160D01*
X-1465295Y-260120D01*
X-1466660Y-259600D01*
X-1468025Y-259860D01*
X-1469195Y-260640D01*
X-1469975Y-262460D01*
X-1470365Y-264020D01*
Y-265580D01*
X-1469975Y-267140D01*
X-1469000Y-268700D01*
X-1467830Y-269740D01*
X-1466465Y-270000D01*
X-1465100Y-269480D01*
X-1463735Y-267920D01*
G01X-1451880Y-270000D02*
Y-259600D01*
G01Y-261680D02*
X-1450905Y-260640D01*
X-1449930Y-259860D01*
X-1448565Y-259600D01*
X-1447590Y-259860D01*
X-1446420Y-260640D01*
G01X-1417250Y-254400D02*
Y-270000D01*
X-1409450D01*
G01X-1395450Y-254400D02*
X-1397010Y-254920D01*
X-1398180Y-256220D01*
X-1398960Y-257780D01*
X-1399545Y-259860D01*
X-1399740Y-262200D01*
X-1399545Y-264540D01*
X-1398960Y-266620D01*
X-1398180Y-268180D01*
X-1397010Y-269480D01*
X-1395450Y-270000D01*
X-1393890Y-269480D01*
X-1392720Y-268180D01*
X-1391940Y-266620D01*
X-1391355Y-264540D01*
X-1391160Y-262200D01*
X-1391355Y-259860D01*
X-1391940Y-257780D01*
X-1392720Y-256220D01*
X-1393890Y-254920D01*
X-1395450Y-254400D01*
G01X-1377550Y-270000D02*
X-1376185Y-269740D01*
X-1374625Y-268960D01*
X-1373650Y-267660D01*
X-1373260Y-265840D01*
X-1373650Y-264020D01*
X-1374820Y-262460D01*
X-1376575Y-261680D01*
X-1378525D01*
X-1379695Y-261160D01*
X-1380670Y-259860D01*
X-1381060Y-258040D01*
X-1380475Y-256220D01*
X-1379110Y-254920D01*
X-1377550Y-254400D01*
X-1375990Y-254920D01*
X-1374625Y-256220D01*
X-1374040Y-258040D01*
X-1374430Y-259860D01*
X-1375405Y-261160D01*
X-1376575Y-261680D01*
X-1378525D01*
X-1380280Y-262460D01*
X-1381450Y-264020D01*
X-1381840Y-265840D01*
X-1381450Y-267660D01*
X-1380475Y-268960D01*
X-1378915Y-269740D01*
X-1377550Y-270000D01*
G01X-1342725Y-275200D02*
X-1344675Y-272600D01*
X-1345650Y-270000D01*
Y-259600D01*
X-1344675Y-257000D01*
X-1342725Y-254400D01*
G01X-1327945Y-267920D02*
X-1326385Y-269220D01*
X-1324630Y-270000D01*
X-1323070D01*
X-1321510Y-269220D01*
X-1320340Y-267920D01*
X-1319755Y-266100D01*
X-1320145Y-264280D01*
X-1321120Y-262720D01*
X-1322875Y-261680D01*
X-1325215Y-261160D01*
X-1326580Y-260120D01*
X-1327165Y-258300D01*
X-1326775Y-256480D01*
X-1325800Y-255180D01*
X-1324435Y-254400D01*
X-1323070D01*
X-1321705Y-254920D01*
X-1320535Y-256220D01*
G01X-1305950Y-254400D02*
Y-270000D01*
G01X-1308680Y-259600D02*
X-1303220D01*
G01X-1291365D02*
Y-266880D01*
X-1290585Y-268700D01*
X-1289415Y-269740D01*
X-1288050Y-270000D01*
X-1286685Y-269740D01*
X-1285515Y-268700D01*
X-1284735Y-266880D01*
G01Y-270000D02*
Y-259600D01*
G01X-1273660Y-270000D02*
Y-254400D01*
G01Y-262200D02*
X-1272685Y-260640D01*
X-1271515Y-259860D01*
X-1270345Y-259600D01*
X-1268590Y-260120D01*
X-1267420Y-261160D01*
X-1266640Y-262980D01*
Y-265060D01*
X-1267030Y-267140D01*
X-1267810Y-268700D01*
X-1269175Y-269740D01*
X-1270345Y-270000D01*
X-1271515Y-269740D01*
X-1272685Y-268960D01*
X-1273660Y-267660D01*
G01X-1234350Y-270000D02*
Y-254400D01*
G01X-1219375Y-262980D02*
X-1213135D01*
X-1213720Y-261160D01*
X-1214695Y-260120D01*
X-1216060Y-259600D01*
X-1217425Y-259860D01*
X-1218595Y-260640D01*
X-1219375Y-262460D01*
X-1219765Y-264020D01*
Y-265580D01*
X-1219375Y-267140D01*
X-1218400Y-268700D01*
X-1217230Y-269740D01*
X-1215865Y-270000D01*
X-1214500Y-269480D01*
X-1213135Y-267920D01*
G01X-1201865Y-270000D02*
Y-259600D01*
G01Y-262200D02*
X-1201085Y-260900D01*
X-1199915Y-259860D01*
X-1198355Y-259600D01*
X-1196990Y-259860D01*
X-1195820Y-260900D01*
X-1195235Y-262720D01*
Y-270000D01*
G01X-1183380Y-273900D02*
X-1182015Y-274940D01*
X-1180455Y-275200D01*
X-1179090Y-274940D01*
X-1177920Y-273640D01*
X-1177140Y-271820D01*
Y-259600D01*
G01Y-261680D02*
X-1177920Y-260640D01*
X-1179090Y-259860D01*
X-1180455Y-259600D01*
X-1182015Y-260120D01*
X-1182990Y-261160D01*
X-1183770Y-262980D01*
X-1184160Y-264800D01*
X-1183965Y-266360D01*
X-1183185Y-268180D01*
X-1182015Y-269480D01*
X-1180455Y-270000D01*
X-1179285Y-269740D01*
X-1177920Y-268700D01*
X-1177140Y-267660D01*
G01X-1162750Y-254400D02*
Y-270000D01*
G01X-1165480Y-259600D02*
X-1160020D01*
G01X-1148165Y-270000D02*
Y-254400D01*
G01Y-261940D02*
X-1147190Y-260640D01*
X-1146215Y-259860D01*
X-1144655Y-259600D01*
X-1143485Y-259860D01*
X-1142120Y-260900D01*
X-1141535Y-262460D01*
Y-270000D01*
G01X-1112755Y-263500D02*
X-1111390Y-261680D01*
X-1110220Y-260640D01*
X-1108660Y-260120D01*
X-1107295Y-260640D01*
X-1106320Y-261680D01*
X-1105540Y-263240D01*
X-1105345Y-265060D01*
X-1105540Y-266620D01*
X-1106320Y-268180D01*
X-1107490Y-269480D01*
X-1108855Y-270000D01*
X-1110415Y-269480D01*
X-1111780Y-267920D01*
X-1112560Y-265580D01*
X-1112755Y-262980D01*
X-1112365Y-259600D01*
X-1111780Y-257780D01*
X-1110805Y-255960D01*
X-1109440Y-254660D01*
X-1108075Y-254400D01*
X-1106710Y-254920D01*
X-1105735Y-256220D01*
G01X-1093295Y-264800D02*
X-1088615D01*
G01X-1091150Y-261420D02*
Y-268180D01*
G01X-1076760Y-270520D02*
X-1069740Y-254400D01*
G01X-1057885Y-264800D02*
X-1052815D01*
G01X-1035110Y-270000D02*
Y-254400D01*
X-1042325Y-265580D01*
X-1032575D01*
G01X-1007500Y-270000D02*
Y-259600D01*
G01Y-262460D02*
X-1006915Y-261160D01*
X-1005940Y-260120D01*
X-1004575Y-259600D01*
X-1003210Y-260120D01*
X-1002235Y-261160D01*
X-1001650Y-262460D01*
Y-270000D01*
G01Y-262460D02*
X-1001065Y-261160D01*
X-1000090Y-260120D01*
X-998725Y-259600D01*
X-997360Y-260120D01*
X-996385Y-261160D01*
X-995800Y-262720D01*
Y-270000D01*
G01X-983750Y-259600D02*
Y-270000D01*
G01Y-255440D02*
X-984140Y-255180D01*
Y-254660D01*
X-983750Y-254400D01*
X-983360Y-254660D01*
Y-255180D01*
X-983750Y-255440D01*
G01X-965850Y-270000D02*
Y-254400D01*
G01X-930050D02*
Y-270000D01*
G01X-932780Y-259600D02*
X-927320D01*
G01X-912150Y-270000D02*
X-913320Y-269740D01*
X-914490Y-268700D01*
X-915270Y-266880D01*
X-915660Y-264800D01*
X-915270Y-262720D01*
X-914490Y-260900D01*
X-913320Y-259860D01*
X-912150Y-259600D01*
X-910980Y-259860D01*
X-909810Y-260900D01*
X-909030Y-262720D01*
X-908835Y-264800D01*
X-909030Y-266880D01*
X-909810Y-268700D01*
X-910980Y-269740D01*
X-912150Y-270000D01*
G01X-894250D02*
Y-254400D01*
G01X-879275Y-262980D02*
X-873035D01*
X-873620Y-261160D01*
X-874595Y-260120D01*
X-875960Y-259600D01*
X-877325Y-259860D01*
X-878495Y-260640D01*
X-879275Y-262460D01*
X-879665Y-264020D01*
Y-265580D01*
X-879275Y-267140D01*
X-878300Y-268700D01*
X-877130Y-269740D01*
X-875765Y-270000D01*
X-874400Y-269480D01*
X-873035Y-267920D01*
G01X-861180Y-270000D02*
Y-259600D01*
G01Y-261680D02*
X-860205Y-260640D01*
X-859230Y-259860D01*
X-857865Y-259600D01*
X-856890Y-259860D01*
X-855720Y-260640D01*
G01X-837040Y-270000D02*
Y-259600D01*
G01Y-261420D02*
X-837820Y-260380D01*
X-838990Y-259860D01*
X-840355Y-259600D01*
X-841720Y-260120D01*
X-842890Y-261160D01*
X-843670Y-262720D01*
X-844060Y-264800D01*
X-843670Y-266880D01*
X-842890Y-268440D01*
X-841720Y-269480D01*
X-840355Y-270000D01*
X-838990Y-269740D01*
X-837820Y-268960D01*
X-837040Y-267920D01*
G01X-825965Y-270000D02*
Y-259600D01*
G01Y-262200D02*
X-825185Y-260900D01*
X-824015Y-259860D01*
X-822455Y-259600D01*
X-821090Y-259860D01*
X-819920Y-260900D01*
X-819335Y-262720D01*
Y-270000D01*
G01X-801630Y-260900D02*
X-802995Y-259860D01*
X-804165Y-259600D01*
X-805725Y-260120D01*
X-806895Y-261160D01*
X-807675Y-262980D01*
X-807870Y-264800D01*
X-807675Y-266620D01*
X-806895Y-268180D01*
X-805725Y-269480D01*
X-804165Y-270000D01*
X-802800Y-269480D01*
X-801630Y-268440D01*
G01X-789775Y-262980D02*
X-783535D01*
X-784120Y-261160D01*
X-785095Y-260120D01*
X-786460Y-259600D01*
X-787825Y-259860D01*
X-788995Y-260640D01*
X-789775Y-262460D01*
X-790165Y-264020D01*
Y-265580D01*
X-789775Y-267140D01*
X-788800Y-268700D01*
X-787630Y-269740D01*
X-786265Y-270000D01*
X-784900Y-269480D01*
X-783535Y-267920D01*
G01X-767975Y-275200D02*
X-766025Y-272600D01*
X-765050Y-270000D01*
Y-259600D01*
X-766025Y-257000D01*
X-767975Y-254400D01*
G01X-2019214Y-127356D02*
Y-142956D01*
G01Y-140616D02*
X-2019994Y-141916D01*
X-2021164Y-142696D01*
X-2022529Y-142956D01*
X-2024089Y-142436D01*
X-2025259Y-141136D01*
X-2026039Y-139576D01*
X-2026234Y-137756D01*
X-2026039Y-135936D01*
X-2025259Y-134376D01*
X-2024089Y-133076D01*
X-2022529Y-132556D01*
X-2021164Y-132816D01*
X-2020189Y-133336D01*
X-2019214Y-134376D01*
G01X-2001314Y-142956D02*
Y-132556D01*
G01Y-134376D02*
X-2002094Y-133336D01*
X-2003264Y-132816D01*
X-2004629Y-132556D01*
X-2005994Y-133076D01*
X-2007164Y-134116D01*
X-2007944Y-135676D01*
X-2008334Y-137756D01*
X-2007944Y-139836D01*
X-2007164Y-141396D01*
X-2005994Y-142436D01*
X-2004629Y-142956D01*
X-2003264Y-142696D01*
X-2002094Y-141916D01*
X-2001314Y-140876D01*
G01X-1986924Y-127356D02*
Y-142956D01*
G01X-1989654Y-132556D02*
X-1984194D01*
G01X-1971949Y-135936D02*
X-1965709D01*
X-1966294Y-134116D01*
X-1967269Y-133076D01*
X-1968634Y-132556D01*
X-1969999Y-132816D01*
X-1971169Y-133596D01*
X-1971949Y-135416D01*
X-1972339Y-136976D01*
Y-138536D01*
X-1971949Y-140096D01*
X-1970974Y-141656D01*
X-1969804Y-142696D01*
X-1968439Y-142956D01*
X-1967074Y-142436D01*
X-1965709Y-140876D01*
G01X-1930104Y-133856D02*
X-1931469Y-132816D01*
X-1932639Y-132556D01*
X-1934199Y-133076D01*
X-1935369Y-134116D01*
X-1936149Y-135936D01*
X-1936344Y-137756D01*
X-1936149Y-139576D01*
X-1935369Y-141136D01*
X-1934199Y-142436D01*
X-1932639Y-142956D01*
X-1931274Y-142436D01*
X-1930104Y-141396D01*
G01X-1915324Y-142956D02*
X-1916494Y-142696D01*
X-1917664Y-141656D01*
X-1918444Y-139836D01*
X-1918834Y-137756D01*
X-1918444Y-135676D01*
X-1917664Y-133856D01*
X-1916494Y-132816D01*
X-1915324Y-132556D01*
X-1914154Y-132816D01*
X-1912984Y-133856D01*
X-1912204Y-135676D01*
X-1912009Y-137756D01*
X-1912204Y-139836D01*
X-1912984Y-141656D01*
X-1914154Y-142696D01*
X-1915324Y-142956D01*
G01X-1893914Y-127356D02*
Y-142956D01*
G01Y-140616D02*
X-1894694Y-141916D01*
X-1895864Y-142696D01*
X-1897229Y-142956D01*
X-1898789Y-142436D01*
X-1899959Y-141136D01*
X-1900739Y-139576D01*
X-1900934Y-137756D01*
X-1900739Y-135936D01*
X-1899959Y-134376D01*
X-1898789Y-133076D01*
X-1897229Y-132556D01*
X-1895864Y-132816D01*
X-1894889Y-133336D01*
X-1893914Y-134376D01*
G01X-1882449Y-135936D02*
X-1876209D01*
X-1876794Y-134116D01*
X-1877769Y-133076D01*
X-1879134Y-132556D01*
X-1880499Y-132816D01*
X-1881669Y-133596D01*
X-1882449Y-135416D01*
X-1882839Y-136976D01*
Y-138536D01*
X-1882449Y-140096D01*
X-1881474Y-141656D01*
X-1880304Y-142696D01*
X-1878939Y-142956D01*
X-1877574Y-142436D01*
X-1876209Y-140876D01*
G01X-1843724Y-127356D02*
Y-142956D01*
G01X-1846454Y-132556D02*
X-1840994D01*
G01X-1825824Y-142956D02*
X-1826994Y-142696D01*
X-1828164Y-141656D01*
X-1828944Y-139836D01*
X-1829334Y-137756D01*
X-1828944Y-135676D01*
X-1828164Y-133856D01*
X-1826994Y-132816D01*
X-1825824Y-132556D01*
X-1824654Y-132816D01*
X-1823484Y-133856D01*
X-1822704Y-135676D01*
X-1822509Y-137756D01*
X-1822704Y-139836D01*
X-1823484Y-141656D01*
X-1824654Y-142696D01*
X-1825824Y-142956D01*
G01X-1793534D02*
Y-127356D01*
G01Y-135156D02*
X-1792559Y-133596D01*
X-1791389Y-132816D01*
X-1790219Y-132556D01*
X-1788464Y-133076D01*
X-1787294Y-134116D01*
X-1786514Y-135936D01*
Y-138016D01*
X-1786904Y-140096D01*
X-1787684Y-141656D01*
X-1789049Y-142696D01*
X-1790219Y-142956D01*
X-1791389Y-142696D01*
X-1792559Y-141916D01*
X-1793534Y-140616D01*
G01X-1775049Y-135936D02*
X-1768809D01*
X-1769394Y-134116D01*
X-1770369Y-133076D01*
X-1771734Y-132556D01*
X-1773099Y-132816D01*
X-1774269Y-133596D01*
X-1775049Y-135416D01*
X-1775439Y-136976D01*
Y-138536D01*
X-1775049Y-140096D01*
X-1774074Y-141656D01*
X-1772904Y-142696D01*
X-1771539Y-142956D01*
X-1770174Y-142436D01*
X-1768809Y-140876D01*
G01X-1739834Y-148156D02*
Y-132556D01*
G01Y-134896D02*
X-1738859Y-133596D01*
X-1737884Y-132816D01*
X-1736324Y-132556D01*
X-1734959Y-132816D01*
X-1733594Y-134116D01*
X-1733009Y-135936D01*
X-1732814Y-137756D01*
X-1733009Y-139576D01*
X-1733594Y-141396D01*
X-1734764Y-142436D01*
X-1736324Y-142956D01*
X-1737689Y-142696D01*
X-1739054Y-141916D01*
X-1739834Y-140876D01*
G01X-1718424Y-142956D02*
Y-127356D01*
G01X-1697014Y-142956D02*
Y-132556D01*
G01Y-134376D02*
X-1697794Y-133336D01*
X-1698964Y-132816D01*
X-1700329Y-132556D01*
X-1701694Y-133076D01*
X-1702864Y-134116D01*
X-1703644Y-135676D01*
X-1704034Y-137756D01*
X-1703644Y-139836D01*
X-1702864Y-141396D01*
X-1701694Y-142436D01*
X-1700329Y-142956D01*
X-1698964Y-142696D01*
X-1697794Y-141916D01*
X-1697014Y-140876D01*
G01X-1679504Y-133856D02*
X-1680869Y-132816D01*
X-1682039Y-132556D01*
X-1683599Y-133076D01*
X-1684769Y-134116D01*
X-1685549Y-135936D01*
X-1685744Y-137756D01*
X-1685549Y-139576D01*
X-1684769Y-141136D01*
X-1683599Y-142436D01*
X-1682039Y-142956D01*
X-1680674Y-142436D01*
X-1679504Y-141396D01*
G01X-1667649Y-135936D02*
X-1661409D01*
X-1661994Y-134116D01*
X-1662969Y-133076D01*
X-1664334Y-132556D01*
X-1665699Y-132816D01*
X-1666869Y-133596D01*
X-1667649Y-135416D01*
X-1668039Y-136976D01*
Y-138536D01*
X-1667649Y-140096D01*
X-1666674Y-141656D01*
X-1665504Y-142696D01*
X-1664139Y-142956D01*
X-1662774Y-142436D01*
X-1661409Y-140876D01*
G01X-1643314Y-127356D02*
Y-142956D01*
G01Y-140616D02*
X-1644094Y-141916D01*
X-1645264Y-142696D01*
X-1646629Y-142956D01*
X-1648189Y-142436D01*
X-1649359Y-141136D01*
X-1650139Y-139576D01*
X-1650334Y-137756D01*
X-1650139Y-135936D01*
X-1649359Y-134376D01*
X-1648189Y-133076D01*
X-1646629Y-132556D01*
X-1645264Y-132816D01*
X-1644289Y-133336D01*
X-1643314Y-134376D01*
G01X-1611024Y-142956D02*
X-1612194Y-142696D01*
X-1613364Y-141656D01*
X-1614144Y-139836D01*
X-1614534Y-137756D01*
X-1614144Y-135676D01*
X-1613364Y-133856D01*
X-1612194Y-132816D01*
X-1611024Y-132556D01*
X-1609854Y-132816D01*
X-1608684Y-133856D01*
X-1607904Y-135676D01*
X-1607709Y-137756D01*
X-1607904Y-139836D01*
X-1608684Y-141656D01*
X-1609854Y-142696D01*
X-1611024Y-142956D01*
G01X-1596439D02*
Y-132556D01*
G01Y-135156D02*
X-1595659Y-133856D01*
X-1594489Y-132816D01*
X-1592929Y-132556D01*
X-1591564Y-132816D01*
X-1590394Y-133856D01*
X-1589809Y-135676D01*
Y-142956D01*
G01X-1560249Y-141136D02*
X-1559274Y-142176D01*
X-1557909Y-142956D01*
X-1556739D01*
X-1555569Y-142436D01*
X-1554789Y-141656D01*
X-1554399Y-140616D01*
X-1554594Y-139056D01*
X-1555374Y-138276D01*
X-1558884Y-136716D01*
X-1559664Y-134896D01*
X-1559274Y-133596D01*
X-1558494Y-132816D01*
X-1557324Y-132556D01*
X-1556154Y-132816D01*
X-1554984Y-133596D01*
G01X-1539424Y-132556D02*
Y-142956D01*
G01Y-128396D02*
X-1539814Y-128136D01*
Y-127616D01*
X-1539424Y-127356D01*
X-1539034Y-127616D01*
Y-128136D01*
X-1539424Y-128396D01*
G01X-1521524Y-142956D02*
Y-127356D01*
G01X-1506939Y-142956D02*
Y-127356D01*
G01X-1500699Y-132556D02*
X-1506939Y-138536D01*
G01X-1504404Y-136196D02*
X-1500309Y-142956D01*
G01X-1488649Y-141136D02*
X-1487674Y-142176D01*
X-1486309Y-142956D01*
X-1485139D01*
X-1483969Y-142436D01*
X-1483189Y-141656D01*
X-1482799Y-140616D01*
X-1482994Y-139056D01*
X-1483774Y-138276D01*
X-1487284Y-136716D01*
X-1488064Y-134896D01*
X-1487674Y-133596D01*
X-1486894Y-132816D01*
X-1485724Y-132556D01*
X-1484554Y-132816D01*
X-1483384Y-133596D01*
G01X-1464704Y-133856D02*
X-1466069Y-132816D01*
X-1467239Y-132556D01*
X-1468799Y-133076D01*
X-1469969Y-134116D01*
X-1470749Y-135936D01*
X-1470944Y-137756D01*
X-1470749Y-139576D01*
X-1469969Y-141136D01*
X-1468799Y-142436D01*
X-1467239Y-142956D01*
X-1465874Y-142436D01*
X-1464704Y-141396D01*
G01X-1452654Y-142956D02*
Y-132556D01*
G01Y-134636D02*
X-1451679Y-133596D01*
X-1450704Y-132816D01*
X-1449339Y-132556D01*
X-1448364Y-132816D01*
X-1447194Y-133596D01*
G01X-1434949Y-135936D02*
X-1428709D01*
X-1429294Y-134116D01*
X-1430269Y-133076D01*
X-1431634Y-132556D01*
X-1432999Y-132816D01*
X-1434169Y-133596D01*
X-1434949Y-135416D01*
X-1435339Y-136976D01*
Y-138536D01*
X-1434949Y-140096D01*
X-1433974Y-141656D01*
X-1432804Y-142696D01*
X-1431439Y-142956D01*
X-1430074Y-142436D01*
X-1428709Y-140876D01*
G01X-1417049Y-135936D02*
X-1410809D01*
X-1411394Y-134116D01*
X-1412369Y-133076D01*
X-1413734Y-132556D01*
X-1415099Y-132816D01*
X-1416269Y-133596D01*
X-1417049Y-135416D01*
X-1417439Y-136976D01*
Y-138536D01*
X-1417049Y-140096D01*
X-1416074Y-141656D01*
X-1414904Y-142696D01*
X-1413539Y-142956D01*
X-1412174Y-142436D01*
X-1410809Y-140876D01*
G01X-1399539Y-142956D02*
Y-132556D01*
G01Y-135156D02*
X-1398759Y-133856D01*
X-1397589Y-132816D01*
X-1396029Y-132556D01*
X-1394664Y-132816D01*
X-1393494Y-133856D01*
X-1392909Y-135676D01*
Y-142956D01*
G01X-1363349Y-141136D02*
X-1362374Y-142176D01*
X-1361009Y-142956D01*
X-1359839D01*
X-1358669Y-142436D01*
X-1357889Y-141656D01*
X-1357499Y-140616D01*
X-1357694Y-139056D01*
X-1358474Y-138276D01*
X-1361984Y-136716D01*
X-1362764Y-134896D01*
X-1362374Y-133596D01*
X-1361594Y-132816D01*
X-1360424Y-132556D01*
X-1359254Y-132816D01*
X-1358084Y-133596D01*
G01X-1342524Y-142956D02*
X-1343694Y-142696D01*
X-1344864Y-141656D01*
X-1345644Y-139836D01*
X-1346034Y-137756D01*
X-1345644Y-135676D01*
X-1344864Y-133856D01*
X-1343694Y-132816D01*
X-1342524Y-132556D01*
X-1341354Y-132816D01*
X-1340184Y-133856D01*
X-1339404Y-135676D01*
X-1339209Y-137756D01*
X-1339404Y-139836D01*
X-1340184Y-141656D01*
X-1341354Y-142696D01*
X-1342524Y-142956D01*
G01X-1324624D02*
Y-127356D01*
G01X-1303214D02*
Y-142956D01*
G01Y-140616D02*
X-1303994Y-141916D01*
X-1305164Y-142696D01*
X-1306529Y-142956D01*
X-1308089Y-142436D01*
X-1309259Y-141136D01*
X-1310039Y-139576D01*
X-1310234Y-137756D01*
X-1310039Y-135936D01*
X-1309259Y-134376D01*
X-1308089Y-133076D01*
X-1306529Y-132556D01*
X-1305164Y-132816D01*
X-1304189Y-133336D01*
X-1303214Y-134376D01*
G01X-1291749Y-135936D02*
X-1285509D01*
X-1286094Y-134116D01*
X-1287069Y-133076D01*
X-1288434Y-132556D01*
X-1289799Y-132816D01*
X-1290969Y-133596D01*
X-1291749Y-135416D01*
X-1292139Y-136976D01*
Y-138536D01*
X-1291749Y-140096D01*
X-1290774Y-141656D01*
X-1289604Y-142696D01*
X-1288239Y-142956D01*
X-1286874Y-142436D01*
X-1285509Y-140876D01*
G01X-1273654Y-142956D02*
Y-132556D01*
G01Y-134636D02*
X-1272679Y-133596D01*
X-1271704Y-132816D01*
X-1270339Y-132556D01*
X-1269364Y-132816D01*
X-1268194Y-133596D01*
G01X-1238049Y-141136D02*
X-1237074Y-142176D01*
X-1235709Y-142956D01*
X-1234539D01*
X-1233369Y-142436D01*
X-1232589Y-141656D01*
X-1232199Y-140616D01*
X-1232394Y-139056D01*
X-1233174Y-138276D01*
X-1236684Y-136716D01*
X-1237464Y-134896D01*
X-1237074Y-133596D01*
X-1236294Y-132816D01*
X-1235124Y-132556D01*
X-1233954Y-132816D01*
X-1232784Y-133596D01*
G01X-1217224Y-132556D02*
Y-142956D01*
G01Y-128396D02*
X-1217614Y-128136D01*
Y-127616D01*
X-1217224Y-127356D01*
X-1216834Y-127616D01*
Y-128136D01*
X-1217224Y-128396D01*
G01X-1195814Y-127356D02*
Y-142956D01*
G01Y-140616D02*
X-1196594Y-141916D01*
X-1197764Y-142696D01*
X-1199129Y-142956D01*
X-1200689Y-142436D01*
X-1201859Y-141136D01*
X-1202639Y-139576D01*
X-1202834Y-137756D01*
X-1202639Y-135936D01*
X-1201859Y-134376D01*
X-1200689Y-133076D01*
X-1199129Y-132556D01*
X-1197764Y-132816D01*
X-1196789Y-133336D01*
X-1195814Y-134376D01*
G01X-1184349Y-135936D02*
X-1178109D01*
X-1178694Y-134116D01*
X-1179669Y-133076D01*
X-1181034Y-132556D01*
X-1182399Y-132816D01*
X-1183569Y-133596D01*
X-1184349Y-135416D01*
X-1184739Y-136976D01*
Y-138536D01*
X-1184349Y-140096D01*
X-1183374Y-141656D01*
X-1182204Y-142696D01*
X-1180839Y-142956D01*
X-1179474Y-142436D01*
X-1178109Y-140876D01*
G01X-1163524Y-143476D02*
X-1163914Y-143216D01*
Y-142696D01*
X-1163524Y-142436D01*
X-1163134Y-142696D01*
Y-143216D01*
X-1163524Y-143476D01*
G01X-2026429Y-108956D02*
Y-93356D01*
X-2019019D01*
G01X-2021749Y-100896D02*
X-2026429D01*
G01X-2001314Y-108956D02*
Y-98556D01*
G01Y-100376D02*
X-2002094Y-99336D01*
X-2003264Y-98816D01*
X-2004629Y-98556D01*
X-2005994Y-99076D01*
X-2007164Y-100116D01*
X-2007944Y-101676D01*
X-2008334Y-103756D01*
X-2007944Y-105836D01*
X-2007164Y-107396D01*
X-2005994Y-108436D01*
X-2004629Y-108956D01*
X-2003264Y-108696D01*
X-2002094Y-107916D01*
X-2001314Y-106876D01*
G01X-1990434Y-108956D02*
Y-93356D01*
G01Y-101156D02*
X-1989459Y-99596D01*
X-1988289Y-98816D01*
X-1987119Y-98556D01*
X-1985364Y-99076D01*
X-1984194Y-100116D01*
X-1983414Y-101936D01*
Y-104016D01*
X-1983804Y-106096D01*
X-1984584Y-107656D01*
X-1985949Y-108696D01*
X-1987119Y-108956D01*
X-1988289Y-108696D01*
X-1989459Y-107916D01*
X-1990434Y-106616D01*
G01X-1954634Y-98556D02*
X-1951124Y-108956D01*
X-1947614Y-98556D01*
G01X-1936149Y-101936D02*
X-1929909D01*
X-1930494Y-100116D01*
X-1931469Y-99076D01*
X-1932834Y-98556D01*
X-1934199Y-98816D01*
X-1935369Y-99596D01*
X-1936149Y-101416D01*
X-1936539Y-102976D01*
Y-104536D01*
X-1936149Y-106096D01*
X-1935174Y-107656D01*
X-1934004Y-108696D01*
X-1932639Y-108956D01*
X-1931274Y-108436D01*
X-1929909Y-106876D01*
G01X-1918639Y-108956D02*
Y-98556D01*
G01Y-101156D02*
X-1917859Y-99856D01*
X-1916689Y-98816D01*
X-1915129Y-98556D01*
X-1913764Y-98816D01*
X-1912594Y-99856D01*
X-1912009Y-101676D01*
Y-108956D01*
G01X-1893914Y-93356D02*
Y-108956D01*
G01Y-106616D02*
X-1894694Y-107916D01*
X-1895864Y-108696D01*
X-1897229Y-108956D01*
X-1898789Y-108436D01*
X-1899959Y-107136D01*
X-1900739Y-105576D01*
X-1900934Y-103756D01*
X-1900739Y-101936D01*
X-1899959Y-100376D01*
X-1898789Y-99076D01*
X-1897229Y-98556D01*
X-1895864Y-98816D01*
X-1894889Y-99336D01*
X-1893914Y-100376D01*
G01X-1879524Y-108956D02*
X-1880694Y-108696D01*
X-1881864Y-107656D01*
X-1882644Y-105836D01*
X-1883034Y-103756D01*
X-1882644Y-101676D01*
X-1881864Y-99856D01*
X-1880694Y-98816D01*
X-1879524Y-98556D01*
X-1878354Y-98816D01*
X-1877184Y-99856D01*
X-1876404Y-101676D01*
X-1876209Y-103756D01*
X-1876404Y-105836D01*
X-1877184Y-107656D01*
X-1878354Y-108696D01*
X-1879524Y-108956D01*
G01X-1864354D02*
Y-98556D01*
G01Y-100636D02*
X-1863379Y-99596D01*
X-1862404Y-98816D01*
X-1861039Y-98556D01*
X-1860064Y-98816D01*
X-1858894Y-99596D01*
G01X-1825824Y-108956D02*
Y-93356D01*
G01X-1807924Y-108956D02*
X-1809094Y-108696D01*
X-1810264Y-107656D01*
X-1811044Y-105836D01*
X-1811434Y-103756D01*
X-1811044Y-101676D01*
X-1810264Y-99856D01*
X-1809094Y-98816D01*
X-1807924Y-98556D01*
X-1806754Y-98816D01*
X-1805584Y-99856D01*
X-1804804Y-101676D01*
X-1804609Y-103756D01*
X-1804804Y-105836D01*
X-1805584Y-107656D01*
X-1806754Y-108696D01*
X-1807924Y-108956D01*
G01X-1792754Y-112856D02*
X-1791389Y-113896D01*
X-1789829Y-114156D01*
X-1788464Y-113896D01*
X-1787294Y-112596D01*
X-1786514Y-110776D01*
Y-98556D01*
G01Y-100636D02*
X-1787294Y-99596D01*
X-1788464Y-98816D01*
X-1789829Y-98556D01*
X-1791389Y-99076D01*
X-1792364Y-100116D01*
X-1793144Y-101936D01*
X-1793534Y-103756D01*
X-1793339Y-105316D01*
X-1792559Y-107136D01*
X-1791389Y-108436D01*
X-1789829Y-108956D01*
X-1788659Y-108696D01*
X-1787294Y-107656D01*
X-1786514Y-106616D01*
G01X-1772124Y-108956D02*
X-1773294Y-108696D01*
X-1774464Y-107656D01*
X-1775244Y-105836D01*
X-1775634Y-103756D01*
X-1775244Y-101676D01*
X-1774464Y-99856D01*
X-1773294Y-98816D01*
X-1772124Y-98556D01*
X-1770954Y-98816D01*
X-1769784Y-99856D01*
X-1769004Y-101676D01*
X-1768809Y-103756D01*
X-1769004Y-105836D01*
X-1769784Y-107656D01*
X-1770954Y-108696D01*
X-1772124Y-108956D01*
G01X-1754614Y-111816D02*
X-1753834Y-108436D01*
G01X-1740614Y-93356D02*
Y-104536D01*
X-1739834Y-106876D01*
X-1738274Y-108436D01*
X-1736324Y-108956D01*
X-1734374Y-108436D01*
X-1732814Y-106876D01*
X-1732034Y-104536D01*
Y-93356D01*
G01X-1722324D02*
Y-108956D01*
X-1714524D01*
G01X-1688474D02*
Y-98556D01*
G01Y-101416D02*
X-1687889Y-100116D01*
X-1686914Y-99076D01*
X-1685549Y-98556D01*
X-1684184Y-99076D01*
X-1683209Y-100116D01*
X-1682624Y-101416D01*
Y-108956D01*
G01Y-101416D02*
X-1682039Y-100116D01*
X-1681064Y-99076D01*
X-1679699Y-98556D01*
X-1678334Y-99076D01*
X-1677359Y-100116D01*
X-1676774Y-101676D01*
Y-108956D01*
G01X-1661214D02*
Y-98556D01*
G01Y-100376D02*
X-1661994Y-99336D01*
X-1663164Y-98816D01*
X-1664529Y-98556D01*
X-1665894Y-99076D01*
X-1667064Y-100116D01*
X-1667844Y-101676D01*
X-1668234Y-103756D01*
X-1667844Y-105836D01*
X-1667064Y-107396D01*
X-1665894Y-108436D01*
X-1664529Y-108956D01*
X-1663164Y-108696D01*
X-1661994Y-107916D01*
X-1661214Y-106876D01*
G01X-1649554Y-108956D02*
Y-98556D01*
G01Y-100636D02*
X-1648579Y-99596D01*
X-1647604Y-98816D01*
X-1646239Y-98556D01*
X-1645264Y-98816D01*
X-1644094Y-99596D01*
G01X-1632239Y-108956D02*
Y-93356D01*
G01X-1625999Y-98556D02*
X-1632239Y-104536D01*
G01X-1629704Y-102196D02*
X-1625609Y-108956D01*
G01X-1611024Y-98556D02*
Y-108956D01*
G01Y-94396D02*
X-1611414Y-94136D01*
Y-93616D01*
X-1611024Y-93356D01*
X-1610634Y-93616D01*
Y-94136D01*
X-1611024Y-94396D01*
G01X-1596439Y-108956D02*
Y-98556D01*
G01Y-101156D02*
X-1595659Y-99856D01*
X-1594489Y-98816D01*
X-1592929Y-98556D01*
X-1591564Y-98816D01*
X-1590394Y-99856D01*
X-1589809Y-101676D01*
Y-108956D01*
G01X-1577954Y-112856D02*
X-1576589Y-113896D01*
X-1575029Y-114156D01*
X-1573664Y-113896D01*
X-1572494Y-112596D01*
X-1571714Y-110776D01*
Y-98556D01*
G01Y-100636D02*
X-1572494Y-99596D01*
X-1573664Y-98816D01*
X-1575029Y-98556D01*
X-1576589Y-99076D01*
X-1577564Y-100116D01*
X-1578344Y-101936D01*
X-1578734Y-103756D01*
X-1578539Y-105316D01*
X-1577759Y-107136D01*
X-1576589Y-108436D01*
X-1575029Y-108956D01*
X-1573859Y-108696D01*
X-1572494Y-107656D01*
X-1571714Y-106616D01*
G01X-1558299Y-114156D02*
X-1560249Y-111556D01*
X-1561224Y-108956D01*
Y-98556D01*
X-1560249Y-95956D01*
X-1558299Y-93356D01*
G01X-1543714D02*
Y-104536D01*
X-1542934Y-106876D01*
X-1541374Y-108436D01*
X-1539424Y-108956D01*
X-1537474Y-108436D01*
X-1535914Y-106876D01*
X-1535134Y-104536D01*
Y-93356D01*
G01X-1525424D02*
Y-108956D01*
X-1517624D01*
G01X-1506939Y-107136D02*
X-1505574Y-108436D01*
X-1504014Y-108956D01*
X-1502454Y-108436D01*
X-1501089Y-106876D01*
X-1500114Y-104536D01*
X-1499724Y-102196D01*
Y-99336D01*
X-1500114Y-96996D01*
X-1501089Y-94916D01*
X-1502259Y-93876D01*
X-1503624Y-93356D01*
X-1505184Y-93876D01*
X-1506354Y-94916D01*
X-1507134Y-96476D01*
X-1507524Y-98556D01*
X-1507134Y-100376D01*
X-1506159Y-102196D01*
X-1504989Y-103236D01*
X-1503624Y-103496D01*
X-1502064Y-102976D01*
X-1500894Y-101676D01*
X-1499724Y-99336D01*
G01X-1483384Y-108956D02*
Y-93356D01*
X-1490599Y-104536D01*
X-1480849D01*
G01X-1472699Y-93356D02*
X-1467824Y-108956D01*
X-1462949Y-93356D01*
G01X-1452459Y-103756D02*
X-1447389D01*
G01X-1432024Y-93356D02*
X-1433584Y-93876D01*
X-1434754Y-95176D01*
X-1435534Y-96736D01*
X-1436119Y-98816D01*
X-1436314Y-101156D01*
X-1436119Y-103496D01*
X-1435534Y-105576D01*
X-1434754Y-107136D01*
X-1433584Y-108436D01*
X-1432024Y-108956D01*
X-1430464Y-108436D01*
X-1429294Y-107136D01*
X-1428514Y-105576D01*
X-1427929Y-103496D01*
X-1427734Y-101156D01*
X-1427929Y-98816D01*
X-1428514Y-96736D01*
X-1429294Y-95176D01*
X-1430464Y-93876D01*
X-1432024Y-93356D01*
G01X-1408274Y-114156D02*
X-1418024Y-98556D01*
Y-95956D01*
X-1416074Y-93356D01*
X-1414124D01*
X-1412174Y-95956D01*
Y-98556D01*
X-1414124Y-101156D01*
X-1418024Y-103756D01*
X-1419974Y-106356D01*
Y-111556D01*
X-1418024Y-114156D01*
X-1412174D01*
X-1408274Y-108956D01*
G01X-1400514Y-93356D02*
Y-104536D01*
X-1399734Y-106876D01*
X-1398174Y-108436D01*
X-1396224Y-108956D01*
X-1394274Y-108436D01*
X-1392714Y-106876D01*
X-1391934Y-104536D01*
Y-93356D01*
G01X-1382224D02*
Y-108956D01*
X-1374424D01*
G01X-1343694D02*
Y-95696D01*
X-1343304Y-94396D01*
X-1342524Y-93616D01*
X-1341354Y-93356D01*
X-1340184Y-93876D01*
X-1339599Y-95176D01*
G01X-1341939Y-99596D02*
X-1345839D01*
G01X-1324624Y-98556D02*
Y-108956D01*
G01Y-94396D02*
X-1325014Y-94136D01*
Y-93616D01*
X-1324624Y-93356D01*
X-1324234Y-93616D01*
Y-94136D01*
X-1324624Y-94396D01*
G01X-1306724Y-108956D02*
Y-93356D01*
G01X-1291749Y-101936D02*
X-1285509D01*
X-1286094Y-100116D01*
X-1287069Y-99076D01*
X-1288434Y-98556D01*
X-1289799Y-98816D01*
X-1290969Y-99596D01*
X-1291749Y-101416D01*
X-1292139Y-102976D01*
Y-104536D01*
X-1291749Y-106096D01*
X-1290774Y-107656D01*
X-1289604Y-108696D01*
X-1288239Y-108956D01*
X-1286874Y-108436D01*
X-1285509Y-106876D01*
G01X-1256339Y-108956D02*
Y-98556D01*
G01Y-101156D02*
X-1255559Y-99856D01*
X-1254389Y-98816D01*
X-1252829Y-98556D01*
X-1251464Y-98816D01*
X-1250294Y-99856D01*
X-1249709Y-101676D01*
Y-108956D01*
G01X-1238439Y-98556D02*
Y-105836D01*
X-1237659Y-107656D01*
X-1236489Y-108696D01*
X-1235124Y-108956D01*
X-1233759Y-108696D01*
X-1232589Y-107656D01*
X-1231809Y-105836D01*
G01Y-108956D02*
Y-98556D01*
G01X-1223074Y-108956D02*
Y-98556D01*
G01Y-101416D02*
X-1222489Y-100116D01*
X-1221514Y-99076D01*
X-1220149Y-98556D01*
X-1218784Y-99076D01*
X-1217809Y-100116D01*
X-1217224Y-101416D01*
Y-108956D01*
G01Y-101416D02*
X-1216639Y-100116D01*
X-1215664Y-99076D01*
X-1214299Y-98556D01*
X-1212934Y-99076D01*
X-1211959Y-100116D01*
X-1211374Y-101676D01*
Y-108956D01*
G01X-1202834D02*
Y-93356D01*
G01Y-101156D02*
X-1201859Y-99596D01*
X-1200689Y-98816D01*
X-1199519Y-98556D01*
X-1197764Y-99076D01*
X-1196594Y-100116D01*
X-1195814Y-101936D01*
Y-104016D01*
X-1196204Y-106096D01*
X-1196984Y-107656D01*
X-1198349Y-108696D01*
X-1199519Y-108956D01*
X-1200689Y-108696D01*
X-1201859Y-107916D01*
X-1202834Y-106616D01*
G01X-1184349Y-101936D02*
X-1178109D01*
X-1178694Y-100116D01*
X-1179669Y-99076D01*
X-1181034Y-98556D01*
X-1182399Y-98816D01*
X-1183569Y-99596D01*
X-1184349Y-101416D01*
X-1184739Y-102976D01*
Y-104536D01*
X-1184349Y-106096D01*
X-1183374Y-107656D01*
X-1182204Y-108696D01*
X-1180839Y-108956D01*
X-1179474Y-108436D01*
X-1178109Y-106876D01*
G01X-1166254Y-108956D02*
Y-98556D01*
G01Y-100636D02*
X-1165279Y-99596D01*
X-1164304Y-98816D01*
X-1162939Y-98556D01*
X-1161964Y-98816D01*
X-1160794Y-99596D01*
G01X-1144649Y-114156D02*
X-1142699Y-111556D01*
X-1141724Y-108956D01*
Y-98556D01*
X-1142699Y-95956D01*
X-1144649Y-93356D01*
G01X-1128114Y-111816D02*
X-1127334Y-108436D01*
G01X-1113724Y-108956D02*
Y-93356D01*
X-1109044D01*
X-1107484Y-94136D01*
X-1106314Y-95956D01*
X-1105924Y-98036D01*
X-1106314Y-100116D01*
X-1107289Y-101676D01*
X-1109044Y-102456D01*
X-1113724D01*
G01X-1097774Y-93356D02*
X-1095044Y-108956D01*
X-1091924Y-93356D01*
X-1088804Y-108956D01*
X-1086074Y-93356D01*
G01X-1072464Y-100636D02*
X-1071684Y-99856D01*
X-1071099Y-98556D01*
X-1070709Y-96736D01*
X-1071099Y-95176D01*
X-1071879Y-94136D01*
X-1073244Y-93356D01*
X-1078509D01*
Y-108956D01*
X-1072074D01*
X-1070709Y-107916D01*
X-1069929Y-106356D01*
X-1069539Y-104536D01*
X-1069929Y-102716D01*
X-1071099Y-101156D01*
X-1072464Y-100636D01*
X-1078509D01*
G01X-1042514Y-93356D02*
Y-104536D01*
X-1041734Y-106876D01*
X-1040174Y-108436D01*
X-1038224Y-108956D01*
X-1036274Y-108436D01*
X-1034714Y-106876D01*
X-1033934Y-104536D01*
Y-93356D01*
G01X-1024224D02*
Y-108956D01*
X-1016424D01*
G01X-984524Y-93356D02*
Y-108956D01*
G01X-987254Y-98556D02*
X-981794D01*
G01X-970719Y-113636D02*
X-969549Y-114156D01*
X-967989Y-113636D01*
X-967014Y-112596D01*
X-966234Y-111296D01*
X-965064Y-107136D01*
X-962529Y-98556D01*
G01X-968769D02*
X-965064Y-107136D01*
G01X-952234Y-114156D02*
Y-98556D01*
G01Y-100896D02*
X-951259Y-99596D01*
X-950284Y-98816D01*
X-948724Y-98556D01*
X-947359Y-98816D01*
X-945994Y-100116D01*
X-945409Y-101936D01*
X-945214Y-103756D01*
X-945409Y-105576D01*
X-945994Y-107396D01*
X-947164Y-108436D01*
X-948724Y-108956D01*
X-950089Y-108696D01*
X-951454Y-107916D01*
X-952234Y-106876D01*
G01X-933749Y-101936D02*
X-927509D01*
X-928094Y-100116D01*
X-929069Y-99076D01*
X-930434Y-98556D01*
X-931799Y-98816D01*
X-932969Y-99596D01*
X-933749Y-101416D01*
X-934139Y-102976D01*
Y-104536D01*
X-933749Y-106096D01*
X-932774Y-107656D01*
X-931604Y-108696D01*
X-930239Y-108956D01*
X-928874Y-108436D01*
X-927509Y-106876D01*
G01X-895024Y-108956D02*
X-896194Y-108696D01*
X-897364Y-107656D01*
X-898144Y-105836D01*
X-898534Y-103756D01*
X-898144Y-101676D01*
X-897364Y-99856D01*
X-896194Y-98816D01*
X-895024Y-98556D01*
X-893854Y-98816D01*
X-892684Y-99856D01*
X-891904Y-101676D01*
X-891709Y-103756D01*
X-891904Y-105836D01*
X-892684Y-107656D01*
X-893854Y-108696D01*
X-895024Y-108956D01*
G01X-879854D02*
Y-98556D01*
G01Y-100636D02*
X-878879Y-99596D01*
X-877904Y-98816D01*
X-876539Y-98556D01*
X-875564Y-98816D01*
X-874394Y-99596D01*
G01X-847174Y-108956D02*
Y-98556D01*
G01Y-101416D02*
X-846589Y-100116D01*
X-845614Y-99076D01*
X-844249Y-98556D01*
X-842884Y-99076D01*
X-841909Y-100116D01*
X-841324Y-101416D01*
Y-108956D01*
G01Y-101416D02*
X-840739Y-100116D01*
X-839764Y-99076D01*
X-838399Y-98556D01*
X-837034Y-99076D01*
X-836059Y-100116D01*
X-835474Y-101676D01*
Y-108956D01*
G01X-823424D02*
X-824594Y-108696D01*
X-825764Y-107656D01*
X-826544Y-105836D01*
X-826934Y-103756D01*
X-826544Y-101676D01*
X-825764Y-99856D01*
X-824594Y-98816D01*
X-823424Y-98556D01*
X-822254Y-98816D01*
X-821084Y-99856D01*
X-820304Y-101676D01*
X-820109Y-103756D01*
X-820304Y-105836D01*
X-821084Y-107656D01*
X-822254Y-108696D01*
X-823424Y-108956D01*
G01X-802014Y-93356D02*
Y-108956D01*
G01Y-106616D02*
X-802794Y-107916D01*
X-803964Y-108696D01*
X-805329Y-108956D01*
X-806889Y-108436D01*
X-808059Y-107136D01*
X-808839Y-105576D01*
X-809034Y-103756D01*
X-808839Y-101936D01*
X-808059Y-100376D01*
X-806889Y-99076D01*
X-805329Y-98556D01*
X-803964Y-98816D01*
X-802989Y-99336D01*
X-802014Y-100376D01*
G01X-790549Y-101936D02*
X-784309D01*
X-784894Y-100116D01*
X-785869Y-99076D01*
X-787234Y-98556D01*
X-788599Y-98816D01*
X-789769Y-99596D01*
X-790549Y-101416D01*
X-790939Y-102976D01*
Y-104536D01*
X-790549Y-106096D01*
X-789574Y-107656D01*
X-788404Y-108696D01*
X-787039Y-108956D01*
X-785674Y-108436D01*
X-784309Y-106876D01*
G01X-769724Y-108956D02*
Y-93356D01*
G01X-752214Y-111816D02*
X-751434Y-108436D01*
G01X-2026624Y-25356D02*
Y-40956D01*
X-2018824D01*
G01X-2001314D02*
Y-30556D01*
G01Y-32376D02*
X-2002094Y-31336D01*
X-2003264Y-30816D01*
X-2004629Y-30556D01*
X-2005994Y-31076D01*
X-2007164Y-32116D01*
X-2007944Y-33676D01*
X-2008334Y-35756D01*
X-2007944Y-37836D01*
X-2007164Y-39396D01*
X-2005994Y-40436D01*
X-2004629Y-40956D01*
X-2003264Y-40696D01*
X-2002094Y-39916D01*
X-2001314Y-38876D01*
G01X-1990239Y-40956D02*
Y-30556D01*
G01Y-33156D02*
X-1989459Y-31856D01*
X-1988289Y-30816D01*
X-1986729Y-30556D01*
X-1985364Y-30816D01*
X-1984194Y-31856D01*
X-1983609Y-33676D01*
Y-40956D01*
G01X-1965514Y-25356D02*
Y-40956D01*
G01Y-38616D02*
X-1966294Y-39916D01*
X-1967464Y-40696D01*
X-1968829Y-40956D01*
X-1970389Y-40436D01*
X-1971559Y-39136D01*
X-1972339Y-37576D01*
X-1972534Y-35756D01*
X-1972339Y-33936D01*
X-1971559Y-32376D01*
X-1970389Y-31076D01*
X-1968829Y-30556D01*
X-1967464Y-30816D01*
X-1966489Y-31336D01*
X-1965514Y-32376D01*
G01X-1954049Y-39136D02*
X-1953074Y-40176D01*
X-1951709Y-40956D01*
X-1950539D01*
X-1949369Y-40436D01*
X-1948589Y-39656D01*
X-1948199Y-38616D01*
X-1948394Y-37056D01*
X-1949174Y-36276D01*
X-1952684Y-34716D01*
X-1953464Y-32896D01*
X-1953074Y-31596D01*
X-1952294Y-30816D01*
X-1951124Y-30556D01*
X-1949954Y-30816D01*
X-1948784Y-31596D01*
G01X-1911814Y-40956D02*
Y-30556D01*
G01Y-32376D02*
X-1912594Y-31336D01*
X-1913764Y-30816D01*
X-1915129Y-30556D01*
X-1916494Y-31076D01*
X-1917664Y-32116D01*
X-1918444Y-33676D01*
X-1918834Y-35756D01*
X-1918444Y-37836D01*
X-1917664Y-39396D01*
X-1916494Y-40436D01*
X-1915129Y-40956D01*
X-1913764Y-40696D01*
X-1912594Y-39916D01*
X-1911814Y-38876D01*
G01X-1900739Y-40956D02*
Y-30556D01*
G01Y-33156D02*
X-1899959Y-31856D01*
X-1898789Y-30816D01*
X-1897229Y-30556D01*
X-1895864Y-30816D01*
X-1894694Y-31856D01*
X-1894109Y-33676D01*
Y-40956D01*
G01X-1876014Y-25356D02*
Y-40956D01*
G01Y-38616D02*
X-1876794Y-39916D01*
X-1877964Y-40696D01*
X-1879329Y-40956D01*
X-1880889Y-40436D01*
X-1882059Y-39136D01*
X-1882839Y-37576D01*
X-1883034Y-35756D01*
X-1882839Y-33936D01*
X-1882059Y-32376D01*
X-1880889Y-31076D01*
X-1879329Y-30556D01*
X-1877964Y-30816D01*
X-1876989Y-31336D01*
X-1876014Y-32376D01*
G01X-1846649Y-33936D02*
X-1840409D01*
X-1840994Y-32116D01*
X-1841969Y-31076D01*
X-1843334Y-30556D01*
X-1844699Y-30816D01*
X-1845869Y-31596D01*
X-1846649Y-33416D01*
X-1847039Y-34976D01*
Y-36536D01*
X-1846649Y-38096D01*
X-1845674Y-39656D01*
X-1844504Y-40696D01*
X-1843139Y-40956D01*
X-1841774Y-40436D01*
X-1840409Y-38876D01*
G01X-1828749Y-30556D02*
X-1822899Y-40956D01*
G01Y-30556D02*
X-1828749Y-40956D01*
G01X-1811434Y-46156D02*
Y-30556D01*
G01Y-32896D02*
X-1810459Y-31596D01*
X-1809484Y-30816D01*
X-1807924Y-30556D01*
X-1806559Y-30816D01*
X-1805194Y-32116D01*
X-1804609Y-33936D01*
X-1804414Y-35756D01*
X-1804609Y-37576D01*
X-1805194Y-39396D01*
X-1806364Y-40436D01*
X-1807924Y-40956D01*
X-1809289Y-40696D01*
X-1810654Y-39916D01*
X-1811434Y-38876D01*
G01X-1790024Y-40956D02*
X-1791194Y-40696D01*
X-1792364Y-39656D01*
X-1793144Y-37836D01*
X-1793534Y-35756D01*
X-1793144Y-33676D01*
X-1792364Y-31856D01*
X-1791194Y-30816D01*
X-1790024Y-30556D01*
X-1788854Y-30816D01*
X-1787684Y-31856D01*
X-1786904Y-33676D01*
X-1786709Y-35756D01*
X-1786904Y-37836D01*
X-1787684Y-39656D01*
X-1788854Y-40696D01*
X-1790024Y-40956D01*
G01X-1775049Y-39136D02*
X-1774074Y-40176D01*
X-1772709Y-40956D01*
X-1771539D01*
X-1770369Y-40436D01*
X-1769589Y-39656D01*
X-1769199Y-38616D01*
X-1769394Y-37056D01*
X-1770174Y-36276D01*
X-1773684Y-34716D01*
X-1774464Y-32896D01*
X-1774074Y-31596D01*
X-1773294Y-30816D01*
X-1772124Y-30556D01*
X-1770954Y-30816D01*
X-1769784Y-31596D01*
G01X-1757149Y-33936D02*
X-1750909D01*
X-1751494Y-32116D01*
X-1752469Y-31076D01*
X-1753834Y-30556D01*
X-1755199Y-30816D01*
X-1756369Y-31596D01*
X-1757149Y-33416D01*
X-1757539Y-34976D01*
Y-36536D01*
X-1757149Y-38096D01*
X-1756174Y-39656D01*
X-1755004Y-40696D01*
X-1753639Y-40956D01*
X-1752274Y-40436D01*
X-1750909Y-38876D01*
G01X-1732814Y-25356D02*
Y-40956D01*
G01Y-38616D02*
X-1733594Y-39916D01*
X-1734764Y-40696D01*
X-1736129Y-40956D01*
X-1737689Y-40436D01*
X-1738859Y-39136D01*
X-1739639Y-37576D01*
X-1739834Y-35756D01*
X-1739639Y-33936D01*
X-1738859Y-32376D01*
X-1737689Y-31076D01*
X-1736129Y-30556D01*
X-1734764Y-30816D01*
X-1733789Y-31336D01*
X-1732814Y-32376D01*
G01X-1704034Y-46156D02*
Y-30556D01*
G01Y-32896D02*
X-1703059Y-31596D01*
X-1702084Y-30816D01*
X-1700524Y-30556D01*
X-1699159Y-30816D01*
X-1697794Y-32116D01*
X-1697209Y-33936D01*
X-1697014Y-35756D01*
X-1697209Y-37576D01*
X-1697794Y-39396D01*
X-1698964Y-40436D01*
X-1700524Y-40956D01*
X-1701889Y-40696D01*
X-1703254Y-39916D01*
X-1704034Y-38876D01*
G01X-1682624Y-40956D02*
Y-25356D01*
G01X-1661214Y-40956D02*
Y-30556D01*
G01Y-32376D02*
X-1661994Y-31336D01*
X-1663164Y-30816D01*
X-1664529Y-30556D01*
X-1665894Y-31076D01*
X-1667064Y-32116D01*
X-1667844Y-33676D01*
X-1668234Y-35756D01*
X-1667844Y-37836D01*
X-1667064Y-39396D01*
X-1665894Y-40436D01*
X-1664529Y-40956D01*
X-1663164Y-40696D01*
X-1661994Y-39916D01*
X-1661214Y-38876D01*
G01X-1646824Y-25356D02*
Y-40956D01*
G01X-1649554Y-30556D02*
X-1644094D01*
G01X-1631849Y-33936D02*
X-1625609D01*
X-1626194Y-32116D01*
X-1627169Y-31076D01*
X-1628534Y-30556D01*
X-1629899Y-30816D01*
X-1631069Y-31596D01*
X-1631849Y-33416D01*
X-1632239Y-34976D01*
Y-36536D01*
X-1631849Y-38096D01*
X-1630874Y-39656D01*
X-1629704Y-40696D01*
X-1628339Y-40956D01*
X-1626974Y-40436D01*
X-1625609Y-38876D01*
G01X-1607514Y-25356D02*
Y-40956D01*
G01Y-38616D02*
X-1608294Y-39916D01*
X-1609464Y-40696D01*
X-1610829Y-40956D01*
X-1612389Y-40436D01*
X-1613559Y-39136D01*
X-1614339Y-37576D01*
X-1614534Y-35756D01*
X-1614339Y-33936D01*
X-1613559Y-32376D01*
X-1612389Y-31076D01*
X-1610829Y-30556D01*
X-1609464Y-30816D01*
X-1608489Y-31336D01*
X-1607514Y-32376D01*
G01X-1571714Y-40956D02*
Y-30556D01*
G01Y-32376D02*
X-1572494Y-31336D01*
X-1573664Y-30816D01*
X-1575029Y-30556D01*
X-1576394Y-31076D01*
X-1577564Y-32116D01*
X-1578344Y-33676D01*
X-1578734Y-35756D01*
X-1578344Y-37836D01*
X-1577564Y-39396D01*
X-1576394Y-40436D01*
X-1575029Y-40956D01*
X-1573664Y-40696D01*
X-1572494Y-39916D01*
X-1571714Y-38876D01*
G01X-1560054Y-40956D02*
Y-30556D01*
G01Y-32636D02*
X-1559079Y-31596D01*
X-1558104Y-30816D01*
X-1556739Y-30556D01*
X-1555764Y-30816D01*
X-1554594Y-31596D01*
G01X-1542349Y-33936D02*
X-1536109D01*
X-1536694Y-32116D01*
X-1537669Y-31076D01*
X-1539034Y-30556D01*
X-1540399Y-30816D01*
X-1541569Y-31596D01*
X-1542349Y-33416D01*
X-1542739Y-34976D01*
Y-36536D01*
X-1542349Y-38096D01*
X-1541374Y-39656D01*
X-1540204Y-40696D01*
X-1538839Y-40956D01*
X-1537474Y-40436D01*
X-1536109Y-38876D01*
G01X-1518014Y-40956D02*
Y-30556D01*
G01Y-32376D02*
X-1518794Y-31336D01*
X-1519964Y-30816D01*
X-1521329Y-30556D01*
X-1522694Y-31076D01*
X-1523864Y-32116D01*
X-1524644Y-33676D01*
X-1525034Y-35756D01*
X-1524644Y-37836D01*
X-1523864Y-39396D01*
X-1522694Y-40436D01*
X-1521329Y-40956D01*
X-1519964Y-40696D01*
X-1518794Y-39916D01*
X-1518014Y-38876D01*
G01X-1506549Y-39136D02*
X-1505574Y-40176D01*
X-1504209Y-40956D01*
X-1503039D01*
X-1501869Y-40436D01*
X-1501089Y-39656D01*
X-1500699Y-38616D01*
X-1500894Y-37056D01*
X-1501674Y-36276D01*
X-1505184Y-34716D01*
X-1505964Y-32896D01*
X-1505574Y-31596D01*
X-1504794Y-30816D01*
X-1503624Y-30556D01*
X-1502454Y-30816D01*
X-1501284Y-31596D01*
G01X-1467824Y-25356D02*
Y-40956D01*
G01X-1470554Y-30556D02*
X-1465094D01*
G01X-1449924Y-40956D02*
X-1451094Y-40696D01*
X-1452264Y-39656D01*
X-1453044Y-37836D01*
X-1453434Y-35756D01*
X-1453044Y-33676D01*
X-1452264Y-31856D01*
X-1451094Y-30816D01*
X-1449924Y-30556D01*
X-1448754Y-30816D01*
X-1447584Y-31856D01*
X-1446804Y-33676D01*
X-1446609Y-35756D01*
X-1446804Y-37836D01*
X-1447584Y-39656D01*
X-1448754Y-40696D01*
X-1449924Y-40956D01*
G01X-1417634D02*
Y-25356D01*
G01Y-33156D02*
X-1416659Y-31596D01*
X-1415489Y-30816D01*
X-1414319Y-30556D01*
X-1412564Y-31076D01*
X-1411394Y-32116D01*
X-1410614Y-33936D01*
Y-36016D01*
X-1411004Y-38096D01*
X-1411784Y-39656D01*
X-1413149Y-40696D01*
X-1414319Y-40956D01*
X-1415489Y-40696D01*
X-1416659Y-39916D01*
X-1417634Y-38616D01*
G01X-1399149Y-33936D02*
X-1392909D01*
X-1393494Y-32116D01*
X-1394469Y-31076D01*
X-1395834Y-30556D01*
X-1397199Y-30816D01*
X-1398369Y-31596D01*
X-1399149Y-33416D01*
X-1399539Y-34976D01*
Y-36536D01*
X-1399149Y-38096D01*
X-1398174Y-39656D01*
X-1397004Y-40696D01*
X-1395639Y-40956D01*
X-1394274Y-40436D01*
X-1392909Y-38876D01*
G01X-1361594Y-40956D02*
Y-27696D01*
X-1361204Y-26396D01*
X-1360424Y-25616D01*
X-1359254Y-25356D01*
X-1358084Y-25876D01*
X-1357499Y-27176D01*
G01X-1359839Y-31596D02*
X-1363739D01*
G01X-1345254Y-40956D02*
Y-30556D01*
G01Y-32636D02*
X-1344279Y-31596D01*
X-1343304Y-30816D01*
X-1341939Y-30556D01*
X-1340964Y-30816D01*
X-1339794Y-31596D01*
G01X-1327549Y-33936D02*
X-1321309D01*
X-1321894Y-32116D01*
X-1322869Y-31076D01*
X-1324234Y-30556D01*
X-1325599Y-30816D01*
X-1326769Y-31596D01*
X-1327549Y-33416D01*
X-1327939Y-34976D01*
Y-36536D01*
X-1327549Y-38096D01*
X-1326574Y-39656D01*
X-1325404Y-40696D01*
X-1324039Y-40956D01*
X-1322674Y-40436D01*
X-1321309Y-38876D01*
G01X-1309649Y-33936D02*
X-1303409D01*
X-1303994Y-32116D01*
X-1304969Y-31076D01*
X-1306334Y-30556D01*
X-1307699Y-30816D01*
X-1308869Y-31596D01*
X-1309649Y-33416D01*
X-1310039Y-34976D01*
Y-36536D01*
X-1309649Y-38096D01*
X-1308674Y-39656D01*
X-1307504Y-40696D01*
X-1306139Y-40956D01*
X-1304774Y-40436D01*
X-1303409Y-38876D01*
G01X-1270924Y-40956D02*
X-1272094Y-40696D01*
X-1273264Y-39656D01*
X-1274044Y-37836D01*
X-1274434Y-35756D01*
X-1274044Y-33676D01*
X-1273264Y-31856D01*
X-1272094Y-30816D01*
X-1270924Y-30556D01*
X-1269754Y-30816D01*
X-1268584Y-31856D01*
X-1267804Y-33676D01*
X-1267609Y-35756D01*
X-1267804Y-37836D01*
X-1268584Y-39656D01*
X-1269754Y-40696D01*
X-1270924Y-40956D01*
G01X-1254194D02*
Y-27696D01*
X-1253804Y-26396D01*
X-1253024Y-25616D01*
X-1251854Y-25356D01*
X-1250684Y-25876D01*
X-1250099Y-27176D01*
G01X-1252439Y-31596D02*
X-1256339D01*
G01X-1217224Y-30556D02*
Y-40956D01*
G01Y-26396D02*
X-1217614Y-26136D01*
Y-25616D01*
X-1217224Y-25356D01*
X-1216834Y-25616D01*
Y-26136D01*
X-1217224Y-26396D01*
G01X-1202639Y-40956D02*
Y-30556D01*
G01Y-33156D02*
X-1201859Y-31856D01*
X-1200689Y-30816D01*
X-1199129Y-30556D01*
X-1197764Y-30816D01*
X-1196594Y-31856D01*
X-1196009Y-33676D01*
Y-40956D01*
G01X-1184739D02*
Y-25356D01*
G01X-1178499Y-30556D02*
X-1184739Y-36536D01*
G01X-1182204Y-34196D02*
X-1178109Y-40956D01*
G01X-1163524Y-41476D02*
X-1163914Y-41216D01*
Y-40696D01*
X-1163524Y-40436D01*
X-1163134Y-40696D01*
Y-41216D01*
X-1163524Y-41476D01*
G01X-2028574Y27044D02*
Y37444D01*
G01Y34584D02*
X-2027989Y35884D01*
X-2027014Y36924D01*
X-2025649Y37444D01*
X-2024284Y36924D01*
X-2023309Y35884D01*
X-2022724Y34584D01*
Y27044D01*
G01Y34584D02*
X-2022139Y35884D01*
X-2021164Y36924D01*
X-2019799Y37444D01*
X-2018434Y36924D01*
X-2017459Y35884D01*
X-2016874Y34324D01*
Y27044D01*
G01X-2001314D02*
Y37444D01*
G01Y35624D02*
X-2002094Y36664D01*
X-2003264Y37184D01*
X-2004629Y37444D01*
X-2005994Y36924D01*
X-2007164Y35884D01*
X-2007944Y34324D01*
X-2008334Y32244D01*
X-2007944Y30164D01*
X-2007164Y28604D01*
X-2005994Y27564D01*
X-2004629Y27044D01*
X-2003264Y27304D01*
X-2002094Y28084D01*
X-2001314Y29124D01*
G01X-1986924Y42644D02*
Y27044D01*
G01X-1989654Y37444D02*
X-1984194D01*
G01X-1969024Y42644D02*
Y27044D01*
G01X-1971754Y37444D02*
X-1966294D01*
G01X-1954049Y34064D02*
X-1947809D01*
X-1948394Y35884D01*
X-1949369Y36924D01*
X-1950734Y37444D01*
X-1952099Y37184D01*
X-1953269Y36404D01*
X-1954049Y34584D01*
X-1954439Y33024D01*
Y31464D01*
X-1954049Y29904D01*
X-1953074Y28344D01*
X-1951904Y27304D01*
X-1950539Y27044D01*
X-1949174Y27564D01*
X-1947809Y29124D01*
G01X-1916494Y27044D02*
Y40304D01*
X-1916104Y41604D01*
X-1915324Y42384D01*
X-1914154Y42644D01*
X-1912984Y42124D01*
X-1912399Y40824D01*
G01X-1914739Y36404D02*
X-1918639D01*
G01X-1897424Y37444D02*
Y27044D01*
G01Y41604D02*
X-1897814Y41864D01*
Y42384D01*
X-1897424Y42644D01*
X-1897034Y42384D01*
Y41864D01*
X-1897424Y41604D01*
G01X-1882839Y27044D02*
Y37444D01*
G01Y34844D02*
X-1882059Y36144D01*
X-1880889Y37184D01*
X-1879329Y37444D01*
X-1877964Y37184D01*
X-1876794Y36144D01*
X-1876209Y34324D01*
Y27044D01*
G01X-1861624Y37444D02*
Y27044D01*
G01Y41604D02*
X-1862014Y41864D01*
Y42384D01*
X-1861624Y42644D01*
X-1861234Y42384D01*
Y41864D01*
X-1861624Y41604D01*
G01X-1846649Y28864D02*
X-1845674Y27824D01*
X-1844309Y27044D01*
X-1843139D01*
X-1841969Y27564D01*
X-1841189Y28344D01*
X-1840799Y29384D01*
X-1840994Y30944D01*
X-1841774Y31724D01*
X-1845284Y33284D01*
X-1846064Y35104D01*
X-1845674Y36404D01*
X-1844894Y37184D01*
X-1843724Y37444D01*
X-1842554Y37184D01*
X-1841384Y36404D01*
G01X-1829139Y27044D02*
Y42644D01*
G01Y35104D02*
X-1828164Y36404D01*
X-1827189Y37184D01*
X-1825629Y37444D01*
X-1824459Y37184D01*
X-1823094Y36144D01*
X-1822509Y34584D01*
Y27044D01*
G01X-1795874D02*
Y37444D01*
G01Y34584D02*
X-1795289Y35884D01*
X-1794314Y36924D01*
X-1792949Y37444D01*
X-1791584Y36924D01*
X-1790609Y35884D01*
X-1790024Y34584D01*
Y27044D01*
G01Y34584D02*
X-1789439Y35884D01*
X-1788464Y36924D01*
X-1787099Y37444D01*
X-1785734Y36924D01*
X-1784759Y35884D01*
X-1784174Y34324D01*
Y27044D01*
G01X-1768614D02*
Y37444D01*
G01Y35624D02*
X-1769394Y36664D01*
X-1770564Y37184D01*
X-1771929Y37444D01*
X-1773294Y36924D01*
X-1774464Y35884D01*
X-1775244Y34324D01*
X-1775634Y32244D01*
X-1775244Y30164D01*
X-1774464Y28604D01*
X-1773294Y27564D01*
X-1771929Y27044D01*
X-1770564Y27304D01*
X-1769394Y28084D01*
X-1768614Y29124D01*
G01X-1754224Y42644D02*
Y27044D01*
G01X-1756954Y37444D02*
X-1751494D01*
G01X-1739249Y34064D02*
X-1733009D01*
X-1733594Y35884D01*
X-1734569Y36924D01*
X-1735934Y37444D01*
X-1737299Y37184D01*
X-1738469Y36404D01*
X-1739249Y34584D01*
X-1739639Y33024D01*
Y31464D01*
X-1739249Y29904D01*
X-1738274Y28344D01*
X-1737104Y27304D01*
X-1735739Y27044D01*
X-1734374Y27564D01*
X-1733009Y29124D01*
G01X-1721154Y27044D02*
Y37444D01*
G01Y35364D02*
X-1720179Y36404D01*
X-1719204Y37184D01*
X-1717839Y37444D01*
X-1716864Y37184D01*
X-1715694Y36404D01*
G01X-1700524Y37444D02*
Y27044D01*
G01Y41604D02*
X-1700914Y41864D01*
Y42384D01*
X-1700524Y42644D01*
X-1700134Y42384D01*
Y41864D01*
X-1700524Y41604D01*
G01X-1679114Y27044D02*
Y37444D01*
G01Y35624D02*
X-1679894Y36664D01*
X-1681064Y37184D01*
X-1682429Y37444D01*
X-1683794Y36924D01*
X-1684964Y35884D01*
X-1685744Y34324D01*
X-1686134Y32244D01*
X-1685744Y30164D01*
X-1684964Y28604D01*
X-1683794Y27564D01*
X-1682429Y27044D01*
X-1681064Y27304D01*
X-1679894Y28084D01*
X-1679114Y29124D01*
G01X-1664724Y27044D02*
Y42644D01*
G01X-1649749Y28864D02*
X-1648774Y27824D01*
X-1647409Y27044D01*
X-1646239D01*
X-1645069Y27564D01*
X-1644289Y28344D01*
X-1643899Y29384D01*
X-1644094Y30944D01*
X-1644874Y31724D01*
X-1648384Y33284D01*
X-1649164Y35104D01*
X-1648774Y36404D01*
X-1647994Y37184D01*
X-1646824Y37444D01*
X-1645654Y37184D01*
X-1644484Y36404D01*
G01X-1614534Y21844D02*
Y37444D01*
G01Y35104D02*
X-1613559Y36404D01*
X-1612584Y37184D01*
X-1611024Y37444D01*
X-1609659Y37184D01*
X-1608294Y35884D01*
X-1607709Y34064D01*
X-1607514Y32244D01*
X-1607709Y30424D01*
X-1608294Y28604D01*
X-1609464Y27564D01*
X-1611024Y27044D01*
X-1612389Y27304D01*
X-1613754Y28084D01*
X-1614534Y29124D01*
G01X-1595854Y27044D02*
Y37444D01*
G01Y35364D02*
X-1594879Y36404D01*
X-1593904Y37184D01*
X-1592539Y37444D01*
X-1591564Y37184D01*
X-1590394Y36404D01*
G01X-1578149Y34064D02*
X-1571909D01*
X-1572494Y35884D01*
X-1573469Y36924D01*
X-1574834Y37444D01*
X-1576199Y37184D01*
X-1577369Y36404D01*
X-1578149Y34584D01*
X-1578539Y33024D01*
Y31464D01*
X-1578149Y29904D01*
X-1577174Y28344D01*
X-1576004Y27304D01*
X-1574639Y27044D01*
X-1573274Y27564D01*
X-1571909Y29124D01*
G01X-1558494Y27044D02*
Y40304D01*
X-1558104Y41604D01*
X-1557324Y42384D01*
X-1556154Y42644D01*
X-1554984Y42124D01*
X-1554399Y40824D01*
G01X-1556739Y36404D02*
X-1560639D01*
G01X-1542349Y34064D02*
X-1536109D01*
X-1536694Y35884D01*
X-1537669Y36924D01*
X-1539034Y37444D01*
X-1540399Y37184D01*
X-1541569Y36404D01*
X-1542349Y34584D01*
X-1542739Y33024D01*
Y31464D01*
X-1542349Y29904D01*
X-1541374Y28344D01*
X-1540204Y27304D01*
X-1538839Y27044D01*
X-1537474Y27564D01*
X-1536109Y29124D01*
G01X-1524254Y27044D02*
Y37444D01*
G01Y35364D02*
X-1523279Y36404D01*
X-1522304Y37184D01*
X-1520939Y37444D01*
X-1519964Y37184D01*
X-1518794Y36404D01*
G01X-1506354Y27044D02*
Y37444D01*
G01Y35364D02*
X-1505379Y36404D01*
X-1504404Y37184D01*
X-1503039Y37444D01*
X-1502064Y37184D01*
X-1500894Y36404D01*
G01X-1488649Y34064D02*
X-1482409D01*
X-1482994Y35884D01*
X-1483969Y36924D01*
X-1485334Y37444D01*
X-1486699Y37184D01*
X-1487869Y36404D01*
X-1488649Y34584D01*
X-1489039Y33024D01*
Y31464D01*
X-1488649Y29904D01*
X-1487674Y28344D01*
X-1486504Y27304D01*
X-1485139Y27044D01*
X-1483774Y27564D01*
X-1482409Y29124D01*
G01X-1464314Y42644D02*
Y27044D01*
G01Y29384D02*
X-1465094Y28084D01*
X-1466264Y27304D01*
X-1467629Y27044D01*
X-1469189Y27564D01*
X-1470359Y28864D01*
X-1471139Y30424D01*
X-1471334Y32244D01*
X-1471139Y34064D01*
X-1470359Y35624D01*
X-1469189Y36924D01*
X-1467629Y37444D01*
X-1466264Y37184D01*
X-1465289Y36664D01*
X-1464314Y35624D01*
G01X-1449924Y26524D02*
X-1450314Y26784D01*
Y27304D01*
X-1449924Y27564D01*
X-1449534Y27304D01*
Y26784D01*
X-1449924Y26524D01*
G01X-2027599Y71444D02*
X-2025259Y61044D01*
X-2022724Y71444D01*
X-2020189Y61044D01*
X-2017849Y71444D01*
G01X-2004824D02*
Y61044D01*
G01Y75604D02*
X-2005214Y75864D01*
Y76384D01*
X-2004824Y76644D01*
X-2004434Y76384D01*
Y75864D01*
X-2004824Y75604D01*
G01X-1986924Y76644D02*
Y61044D01*
G01X-1989654Y71444D02*
X-1984194D01*
G01X-1972339Y61044D02*
Y76644D01*
G01Y69104D02*
X-1971364Y70404D01*
X-1970389Y71184D01*
X-1968829Y71444D01*
X-1967659Y71184D01*
X-1966294Y70144D01*
X-1965709Y68584D01*
Y61044D01*
G01X-1935564Y76644D02*
X-1930884D01*
G01X-1933224D02*
Y61044D01*
G01X-1935564D02*
X-1930884D01*
G01X-1919224D02*
Y76644D01*
X-1914544D01*
X-1912984Y75864D01*
X-1911814Y74044D01*
X-1911424Y71964D01*
X-1911814Y69884D01*
X-1912789Y68324D01*
X-1914544Y67544D01*
X-1919224D01*
G01X-1893134Y75344D02*
X-1894304Y76124D01*
X-1895669Y76644D01*
X-1897229D01*
X-1898984Y75864D01*
X-1900349Y74564D01*
X-1901324Y73004D01*
X-1902104Y70404D01*
X-1902299Y68064D01*
X-1901909Y65724D01*
X-1901324Y64164D01*
X-1900154Y62604D01*
X-1898789Y61564D01*
X-1897424Y61044D01*
X-1896059D01*
X-1894694Y61564D01*
X-1893524Y62344D01*
X-1892549Y63384D01*
G01X-1882059Y66244D02*
X-1876989D01*
G01X-1865719Y63124D02*
X-1864159Y61824D01*
X-1862404Y61044D01*
X-1860844D01*
X-1859284Y61824D01*
X-1858114Y63124D01*
X-1857529Y64944D01*
X-1857919Y66764D01*
X-1858894Y68324D01*
X-1860649Y69364D01*
X-1862989Y69884D01*
X-1864354Y70924D01*
X-1864939Y72744D01*
X-1864549Y74564D01*
X-1863574Y75864D01*
X-1862209Y76644D01*
X-1860844D01*
X-1859479Y76124D01*
X-1858309Y74824D01*
G01X-1848794Y61044D02*
Y76644D01*
X-1843724Y63644D01*
X-1838654Y76644D01*
Y61044D01*
G01X-1828359Y66244D02*
X-1823289D01*
G01X-1807924Y61044D02*
X-1806559Y61304D01*
X-1804999Y62084D01*
X-1804024Y63384D01*
X-1803634Y65204D01*
X-1804024Y67024D01*
X-1805194Y68584D01*
X-1806949Y69364D01*
X-1808899D01*
X-1810069Y69884D01*
X-1811044Y71184D01*
X-1811434Y73004D01*
X-1810849Y74824D01*
X-1809484Y76124D01*
X-1807924Y76644D01*
X-1806364Y76124D01*
X-1804999Y74824D01*
X-1804414Y73004D01*
X-1804804Y71184D01*
X-1805779Y69884D01*
X-1806949Y69364D01*
X-1808899D01*
X-1810654Y68584D01*
X-1811824Y67024D01*
X-1812214Y65204D01*
X-1811824Y63384D01*
X-1810849Y62084D01*
X-1809289Y61304D01*
X-1807924Y61044D01*
G01X-1787684D02*
Y76644D01*
X-1794899Y65464D01*
X-1785149D01*
G01X-1772124Y76644D02*
X-1773684Y76124D01*
X-1774854Y74824D01*
X-1775634Y73264D01*
X-1776219Y71184D01*
X-1776414Y68844D01*
X-1776219Y66504D01*
X-1775634Y64424D01*
X-1774854Y62864D01*
X-1773684Y61564D01*
X-1772124Y61044D01*
X-1770564Y61564D01*
X-1769394Y62864D01*
X-1768614Y64424D01*
X-1768029Y66504D01*
X-1767834Y68844D01*
X-1768029Y71184D01*
X-1768614Y73264D01*
X-1769394Y74824D01*
X-1770564Y76124D01*
X-1772124Y76644D01*
G01X-1754614Y58184D02*
X-1753834Y61564D01*
G01X-1718424Y76644D02*
Y61044D01*
G01X-1722909Y76644D02*
X-1713939D01*
G01X-1704619Y56364D02*
X-1703449Y55844D01*
X-1701889Y56364D01*
X-1700914Y57404D01*
X-1700134Y58704D01*
X-1698964Y62864D01*
X-1696429Y71444D01*
G01X-1702669D02*
X-1698964Y62864D01*
G01X-1686134Y55844D02*
Y71444D01*
G01Y69104D02*
X-1685159Y70404D01*
X-1684184Y71184D01*
X-1682624Y71444D01*
X-1681259Y71184D01*
X-1679894Y69884D01*
X-1679309Y68064D01*
X-1679114Y66244D01*
X-1679309Y64424D01*
X-1679894Y62604D01*
X-1681064Y61564D01*
X-1682624Y61044D01*
X-1683989Y61304D01*
X-1685354Y62084D01*
X-1686134Y63124D01*
G01X-1667649Y68064D02*
X-1661409D01*
X-1661994Y69884D01*
X-1662969Y70924D01*
X-1664334Y71444D01*
X-1665699Y71184D01*
X-1666869Y70404D01*
X-1667649Y68584D01*
X-1668039Y67024D01*
Y65464D01*
X-1667649Y63904D01*
X-1666674Y62344D01*
X-1665504Y61304D01*
X-1664139Y61044D01*
X-1662774Y61564D01*
X-1661409Y63124D01*
G01X-1627364Y69364D02*
X-1626584Y70144D01*
X-1625999Y71444D01*
X-1625609Y73264D01*
X-1625999Y74824D01*
X-1626779Y75864D01*
X-1628144Y76644D01*
X-1633409D01*
Y61044D01*
X-1626974D01*
X-1625609Y62084D01*
X-1624829Y63644D01*
X-1624439Y65464D01*
X-1624829Y67284D01*
X-1625999Y68844D01*
X-1627364Y69364D01*
X-1633409D01*
G01X-1611414Y58184D02*
X-1610634Y61564D01*
G01X-1570934Y75344D02*
X-1572104Y76124D01*
X-1573469Y76644D01*
X-1575029D01*
X-1576784Y75864D01*
X-1578149Y74564D01*
X-1579124Y73004D01*
X-1579904Y70404D01*
X-1580099Y68064D01*
X-1579709Y65724D01*
X-1579124Y64164D01*
X-1577954Y62604D01*
X-1576589Y61564D01*
X-1575224Y61044D01*
X-1573859D01*
X-1572494Y61564D01*
X-1571324Y62344D01*
X-1570349Y63384D01*
G01X-1557324Y61044D02*
Y76644D01*
G01X-1535914Y61044D02*
Y71444D01*
G01Y69624D02*
X-1536694Y70664D01*
X-1537864Y71184D01*
X-1539229Y71444D01*
X-1540594Y70924D01*
X-1541764Y69884D01*
X-1542544Y68324D01*
X-1542934Y66244D01*
X-1542544Y64164D01*
X-1541764Y62604D01*
X-1540594Y61564D01*
X-1539229Y61044D01*
X-1537864Y61304D01*
X-1536694Y62084D01*
X-1535914Y63124D01*
G01X-1524449Y62864D02*
X-1523474Y61824D01*
X-1522109Y61044D01*
X-1520939D01*
X-1519769Y61564D01*
X-1518989Y62344D01*
X-1518599Y63384D01*
X-1518794Y64944D01*
X-1519574Y65724D01*
X-1523084Y67284D01*
X-1523864Y69104D01*
X-1523474Y70404D01*
X-1522694Y71184D01*
X-1521524Y71444D01*
X-1520354Y71184D01*
X-1519184Y70404D01*
G01X-1506549Y62864D02*
X-1505574Y61824D01*
X-1504209Y61044D01*
X-1503039D01*
X-1501869Y61564D01*
X-1501089Y62344D01*
X-1500699Y63384D01*
X-1500894Y64944D01*
X-1501674Y65724D01*
X-1505184Y67284D01*
X-1505964Y69104D01*
X-1505574Y70404D01*
X-1504794Y71184D01*
X-1503624Y71444D01*
X-1502454Y71184D01*
X-1501284Y70404D01*
G01X-1471529Y74044D02*
X-1470359Y75604D01*
X-1468994Y76384D01*
X-1467434Y76644D01*
X-1465484Y76124D01*
X-1464119Y74824D01*
X-1463729Y73264D01*
X-1463924Y71704D01*
X-1464704Y70404D01*
X-1468604Y67804D01*
X-1470359Y65984D01*
X-1471529Y63384D01*
X-1471919Y61044D01*
X-1463729D01*
G01X-1450314Y58184D02*
X-1449534Y61564D01*
G01X-1414124Y61044D02*
X-1415294Y61304D01*
X-1416464Y62344D01*
X-1417244Y64164D01*
X-1417634Y66244D01*
X-1417244Y68324D01*
X-1416464Y70144D01*
X-1415294Y71184D01*
X-1414124Y71444D01*
X-1412954Y71184D01*
X-1411784Y70144D01*
X-1411004Y68324D01*
X-1410809Y66244D01*
X-1411004Y64164D01*
X-1411784Y62344D01*
X-1412954Y61304D01*
X-1414124Y61044D01*
G01X-1399734Y71444D02*
X-1396224Y61044D01*
X-1392714Y71444D01*
G01X-1381249Y68064D02*
X-1375009D01*
X-1375594Y69884D01*
X-1376569Y70924D01*
X-1377934Y71444D01*
X-1379299Y71184D01*
X-1380469Y70404D01*
X-1381249Y68584D01*
X-1381639Y67024D01*
Y65464D01*
X-1381249Y63904D01*
X-1380274Y62344D01*
X-1379104Y61304D01*
X-1377739Y61044D01*
X-1376374Y61564D01*
X-1375009Y63124D01*
G01X-1363154Y61044D02*
Y71444D01*
G01Y69364D02*
X-1362179Y70404D01*
X-1361204Y71184D01*
X-1359839Y71444D01*
X-1358864Y71184D01*
X-1357694Y70404D01*
G01X-1328134Y61044D02*
Y76644D01*
G01Y68844D02*
X-1327159Y70404D01*
X-1325989Y71184D01*
X-1324819Y71444D01*
X-1323064Y70924D01*
X-1321894Y69884D01*
X-1321114Y68064D01*
Y65984D01*
X-1321504Y63904D01*
X-1322284Y62344D01*
X-1323649Y61304D01*
X-1324819Y61044D01*
X-1325989Y61304D01*
X-1327159Y62084D01*
X-1328134Y63384D01*
G01X-1303214Y61044D02*
Y71444D01*
G01Y69624D02*
X-1303994Y70664D01*
X-1305164Y71184D01*
X-1306529Y71444D01*
X-1307894Y70924D01*
X-1309064Y69884D01*
X-1309844Y68324D01*
X-1310234Y66244D01*
X-1309844Y64164D01*
X-1309064Y62604D01*
X-1307894Y61564D01*
X-1306529Y61044D01*
X-1305164Y61304D01*
X-1303994Y62084D01*
X-1303214Y63124D01*
G01X-1291554Y61044D02*
Y71444D01*
G01Y69364D02*
X-1290579Y70404D01*
X-1289604Y71184D01*
X-1288239Y71444D01*
X-1287264Y71184D01*
X-1286094Y70404D01*
G01X-1273849Y68064D02*
X-1267609D01*
X-1268194Y69884D01*
X-1269169Y70924D01*
X-1270534Y71444D01*
X-1271899Y71184D01*
X-1273069Y70404D01*
X-1273849Y68584D01*
X-1274239Y67024D01*
Y65464D01*
X-1273849Y63904D01*
X-1272874Y62344D01*
X-1271704Y61304D01*
X-1270339Y61044D01*
X-1268974Y61564D01*
X-1267609Y63124D01*
G01X-1232004Y70144D02*
X-1233369Y71184D01*
X-1234539Y71444D01*
X-1236099Y70924D01*
X-1237269Y69884D01*
X-1238049Y68064D01*
X-1238244Y66244D01*
X-1238049Y64424D01*
X-1237269Y62864D01*
X-1236099Y61564D01*
X-1234539Y61044D01*
X-1233174Y61564D01*
X-1232004Y62604D01*
G01X-1217224Y61044D02*
X-1218394Y61304D01*
X-1219564Y62344D01*
X-1220344Y64164D01*
X-1220734Y66244D01*
X-1220344Y68324D01*
X-1219564Y70144D01*
X-1218394Y71184D01*
X-1217224Y71444D01*
X-1216054Y71184D01*
X-1214884Y70144D01*
X-1214104Y68324D01*
X-1213909Y66244D01*
X-1214104Y64164D01*
X-1214884Y62344D01*
X-1216054Y61304D01*
X-1217224Y61044D01*
G01X-1202834Y55844D02*
Y71444D01*
G01Y69104D02*
X-1201859Y70404D01*
X-1200884Y71184D01*
X-1199324Y71444D01*
X-1197959Y71184D01*
X-1196594Y69884D01*
X-1196009Y68064D01*
X-1195814Y66244D01*
X-1196009Y64424D01*
X-1196594Y62604D01*
X-1197764Y61564D01*
X-1199324Y61044D01*
X-1200689Y61304D01*
X-1202054Y62084D01*
X-1202834Y63124D01*
G01X-1184934Y55844D02*
Y71444D01*
G01Y69104D02*
X-1183959Y70404D01*
X-1182984Y71184D01*
X-1181424Y71444D01*
X-1180059Y71184D01*
X-1178694Y69884D01*
X-1178109Y68064D01*
X-1177914Y66244D01*
X-1178109Y64424D01*
X-1178694Y62604D01*
X-1179864Y61564D01*
X-1181424Y61044D01*
X-1182789Y61304D01*
X-1184154Y62084D01*
X-1184934Y63124D01*
G01X-1166449Y68064D02*
X-1160209D01*
X-1160794Y69884D01*
X-1161769Y70924D01*
X-1163134Y71444D01*
X-1164499Y71184D01*
X-1165669Y70404D01*
X-1166449Y68584D01*
X-1166839Y67024D01*
Y65464D01*
X-1166449Y63904D01*
X-1165474Y62344D01*
X-1164304Y61304D01*
X-1162939Y61044D01*
X-1161574Y61564D01*
X-1160209Y63124D01*
G01X-1148354Y61044D02*
Y71444D01*
G01Y69364D02*
X-1147379Y70404D01*
X-1146404Y71184D01*
X-1145039Y71444D01*
X-1144064Y71184D01*
X-1142894Y70404D01*
G01X-1127724Y60524D02*
X-1128114Y60784D01*
Y61304D01*
X-1127724Y61564D01*
X-1127334Y61304D01*
Y60784D01*
X-1127724Y60524D01*
G01X-1096019Y63124D02*
X-1094459Y61824D01*
X-1092704Y61044D01*
X-1091144D01*
X-1089584Y61824D01*
X-1088414Y63124D01*
X-1087829Y64944D01*
X-1088219Y66764D01*
X-1089194Y68324D01*
X-1090949Y69364D01*
X-1093289Y69884D01*
X-1094654Y70924D01*
X-1095239Y72744D01*
X-1094849Y74564D01*
X-1093874Y75864D01*
X-1092509Y76644D01*
X-1091144D01*
X-1089779Y76124D01*
X-1088609Y74824D01*
G01X-1074024Y61044D02*
X-1075194Y61304D01*
X-1076364Y62344D01*
X-1077144Y64164D01*
X-1077534Y66244D01*
X-1077144Y68324D01*
X-1076364Y70144D01*
X-1075194Y71184D01*
X-1074024Y71444D01*
X-1072854Y71184D01*
X-1071684Y70144D01*
X-1070904Y68324D01*
X-1070709Y66244D01*
X-1070904Y64164D01*
X-1071684Y62344D01*
X-1072854Y61304D01*
X-1074024Y61044D01*
G01X-1056124D02*
Y76644D01*
G01X-1034714D02*
Y61044D01*
G01Y63384D02*
X-1035494Y62084D01*
X-1036664Y61304D01*
X-1038029Y61044D01*
X-1039589Y61564D01*
X-1040759Y62864D01*
X-1041539Y64424D01*
X-1041734Y66244D01*
X-1041539Y68064D01*
X-1040759Y69624D01*
X-1039589Y70924D01*
X-1038029Y71444D01*
X-1036664Y71184D01*
X-1035689Y70664D01*
X-1034714Y69624D01*
G01X-1023249Y68064D02*
X-1017009D01*
X-1017594Y69884D01*
X-1018569Y70924D01*
X-1019934Y71444D01*
X-1021299Y71184D01*
X-1022469Y70404D01*
X-1023249Y68584D01*
X-1023639Y67024D01*
Y65464D01*
X-1023249Y63904D01*
X-1022274Y62344D01*
X-1021104Y61304D01*
X-1019739Y61044D01*
X-1018374Y61564D01*
X-1017009Y63124D01*
G01X-1005154Y61044D02*
Y71444D01*
G01Y69364D02*
X-1004179Y70404D01*
X-1003204Y71184D01*
X-1001839Y71444D01*
X-1000864Y71184D01*
X-999694Y70404D01*
G01X-990374Y61044D02*
Y71444D01*
G01Y68584D02*
X-989789Y69884D01*
X-988814Y70924D01*
X-987449Y71444D01*
X-986084Y70924D01*
X-985109Y69884D01*
X-984524Y68584D01*
Y61044D01*
G01Y68584D02*
X-983939Y69884D01*
X-982964Y70924D01*
X-981599Y71444D01*
X-980234Y70924D01*
X-979259Y69884D01*
X-978674Y68324D01*
Y61044D01*
G01X-963114D02*
Y71444D01*
G01Y69624D02*
X-963894Y70664D01*
X-965064Y71184D01*
X-966429Y71444D01*
X-967794Y70924D01*
X-968964Y69884D01*
X-969744Y68324D01*
X-970134Y66244D01*
X-969744Y64164D01*
X-968964Y62604D01*
X-967794Y61564D01*
X-966429Y61044D01*
X-965064Y61304D01*
X-963894Y62084D01*
X-963114Y63124D01*
G01X-951649Y62864D02*
X-950674Y61824D01*
X-949309Y61044D01*
X-948139D01*
X-946969Y61564D01*
X-946189Y62344D01*
X-945799Y63384D01*
X-945994Y64944D01*
X-946774Y65724D01*
X-950284Y67284D01*
X-951064Y69104D01*
X-950674Y70404D01*
X-949894Y71184D01*
X-948724Y71444D01*
X-947554Y71184D01*
X-946384Y70404D01*
G01X-934139Y61044D02*
Y76644D01*
G01X-927899Y71444D02*
X-934139Y65464D01*
G01X-931604Y67804D02*
X-927509Y61044D01*
G01X-891904Y70144D02*
X-893269Y71184D01*
X-894439Y71444D01*
X-895999Y70924D01*
X-897169Y69884D01*
X-897949Y68064D01*
X-898144Y66244D01*
X-897949Y64424D01*
X-897169Y62864D01*
X-895999Y61564D01*
X-894439Y61044D01*
X-893074Y61564D01*
X-891904Y62604D01*
G01X-877124Y61044D02*
X-878294Y61304D01*
X-879464Y62344D01*
X-880244Y64164D01*
X-880634Y66244D01*
X-880244Y68324D01*
X-879464Y70144D01*
X-878294Y71184D01*
X-877124Y71444D01*
X-875954Y71184D01*
X-874784Y70144D01*
X-874004Y68324D01*
X-873809Y66244D01*
X-874004Y64164D01*
X-874784Y62344D01*
X-875954Y61304D01*
X-877124Y61044D01*
G01X-859224D02*
Y76644D01*
G01X-841324Y61044D02*
X-842494Y61304D01*
X-843664Y62344D01*
X-844444Y64164D01*
X-844834Y66244D01*
X-844444Y68324D01*
X-843664Y70144D01*
X-842494Y71184D01*
X-841324Y71444D01*
X-840154Y71184D01*
X-838984Y70144D01*
X-838204Y68324D01*
X-838009Y66244D01*
X-838204Y64164D01*
X-838984Y62344D01*
X-840154Y61304D01*
X-841324Y61044D01*
G01X-826154D02*
Y71444D01*
G01Y69364D02*
X-825179Y70404D01*
X-824204Y71184D01*
X-822839Y71444D01*
X-821864Y71184D01*
X-820694Y70404D01*
G01X-787624Y76644D02*
Y61044D01*
G01X-790354Y71444D02*
X-784894D01*
G01X-769724Y61044D02*
X-770894Y61304D01*
X-772064Y62344D01*
X-772844Y64164D01*
X-773234Y66244D01*
X-772844Y68324D01*
X-772064Y70144D01*
X-770894Y71184D01*
X-769724Y71444D01*
X-768554Y71184D01*
X-767384Y70144D01*
X-766604Y68324D01*
X-766409Y66244D01*
X-766604Y64164D01*
X-767384Y62344D01*
X-768554Y61304D01*
X-769724Y61044D01*
G01X-737434D02*
Y76644D01*
G01Y68844D02*
X-736459Y70404D01*
X-735289Y71184D01*
X-734119Y71444D01*
X-732364Y70924D01*
X-731194Y69884D01*
X-730414Y68064D01*
Y65984D01*
X-730804Y63904D01*
X-731584Y62344D01*
X-732949Y61304D01*
X-734119Y61044D01*
X-735289Y61304D01*
X-736459Y62084D01*
X-737434Y63384D01*
G01X-718949Y68064D02*
X-712709D01*
X-713294Y69884D01*
X-714269Y70924D01*
X-715634Y71444D01*
X-716999Y71184D01*
X-718169Y70404D01*
X-718949Y68584D01*
X-719339Y67024D01*
Y65464D01*
X-718949Y63904D01*
X-717974Y62344D01*
X-716804Y61304D01*
X-715439Y61044D01*
X-714074Y61564D01*
X-712709Y63124D01*
G01X-679054Y68844D02*
X-675154D01*
Y64164D01*
X-676324Y62604D01*
X-677689Y61564D01*
X-679639Y61044D01*
X-681589Y61564D01*
X-682954Y62604D01*
X-684124Y64164D01*
X-684904Y65984D01*
X-685294Y68064D01*
Y69884D01*
X-684904Y71444D01*
X-684124Y73264D01*
X-682954Y74824D01*
X-681784Y75864D01*
X-680224Y76644D01*
X-678859D01*
X-677299Y76124D01*
X-676129Y75084D01*
G01X-666224Y61044D02*
Y76644D01*
X-661349D01*
X-659789Y75864D01*
X-658814Y74824D01*
X-658424Y72744D01*
X-658814Y70664D01*
X-659984Y69364D01*
X-661349Y68584D01*
X-666224D01*
G01X-661349D02*
X-658424Y61044D01*
G01X-640524D02*
X-648324D01*
Y76644D01*
X-640524D01*
G01X-643644Y69104D02*
X-648324D01*
G01X-622624Y61044D02*
X-630424D01*
Y76644D01*
X-622624D01*
G01X-625744Y69104D02*
X-630424D01*
G01X-613109Y61044D02*
Y76644D01*
X-604139Y61044D01*
Y76644D01*
G01X-590724Y60524D02*
X-591114Y60784D01*
Y61304D01*
X-590724Y61564D01*
X-590334Y61304D01*
Y60784D01*
X-590724Y60524D01*
G01X-2022724Y217044D02*
X-2023894Y217304D01*
X-2025064Y218344D01*
X-2025844Y220164D01*
X-2026234Y222244D01*
X-2025844Y224324D01*
X-2025064Y226144D01*
X-2023894Y227184D01*
X-2022724Y227444D01*
X-2021554Y227184D01*
X-2020384Y226144D01*
X-2019604Y224324D01*
X-2019409Y222244D01*
X-2019604Y220164D01*
X-2020384Y218344D01*
X-2021554Y217304D01*
X-2022724Y217044D01*
G01X-2004824Y232644D02*
Y217044D01*
G01X-2007554Y227444D02*
X-2002094D01*
G01X-1990239Y217044D02*
Y232644D01*
G01Y225104D02*
X-1989264Y226404D01*
X-1988289Y227184D01*
X-1986729Y227444D01*
X-1985559Y227184D01*
X-1984194Y226144D01*
X-1983609Y224584D01*
Y217044D01*
G01X-1971949Y224064D02*
X-1965709D01*
X-1966294Y225884D01*
X-1967269Y226924D01*
X-1968634Y227444D01*
X-1969999Y227184D01*
X-1971169Y226404D01*
X-1971949Y224584D01*
X-1972339Y223024D01*
Y221464D01*
X-1971949Y219904D01*
X-1970974Y218344D01*
X-1969804Y217304D01*
X-1968439Y217044D01*
X-1967074Y217564D01*
X-1965709Y219124D01*
G01X-1953854Y217044D02*
Y227444D01*
G01Y225364D02*
X-1952879Y226404D01*
X-1951904Y227184D01*
X-1950539Y227444D01*
X-1949564Y227184D01*
X-1948394Y226404D01*
G01X-1938099Y227444D02*
X-1935759Y217044D01*
X-1933224Y227444D01*
X-1930689Y217044D01*
X-1928349Y227444D01*
G01X-1915324D02*
Y217044D01*
G01Y231604D02*
X-1915714Y231864D01*
Y232384D01*
X-1915324Y232644D01*
X-1914934Y232384D01*
Y231864D01*
X-1915324Y231604D01*
G01X-1900349Y218864D02*
X-1899374Y217824D01*
X-1898009Y217044D01*
X-1896839D01*
X-1895669Y217564D01*
X-1894889Y218344D01*
X-1894499Y219384D01*
X-1894694Y220944D01*
X-1895474Y221724D01*
X-1898984Y223284D01*
X-1899764Y225104D01*
X-1899374Y226404D01*
X-1898594Y227184D01*
X-1897424Y227444D01*
X-1896254Y227184D01*
X-1895084Y226404D01*
G01X-1882449Y224064D02*
X-1876209D01*
X-1876794Y225884D01*
X-1877769Y226924D01*
X-1879134Y227444D01*
X-1880499Y227184D01*
X-1881669Y226404D01*
X-1882449Y224584D01*
X-1882839Y223024D01*
Y221464D01*
X-1882449Y219904D01*
X-1881474Y218344D01*
X-1880304Y217304D01*
X-1878939Y217044D01*
X-1877574Y217564D01*
X-1876209Y219124D01*
G01X-1846649Y218864D02*
X-1845674Y217824D01*
X-1844309Y217044D01*
X-1843139D01*
X-1841969Y217564D01*
X-1841189Y218344D01*
X-1840799Y219384D01*
X-1840994Y220944D01*
X-1841774Y221724D01*
X-1845284Y223284D01*
X-1846064Y225104D01*
X-1845674Y226404D01*
X-1844894Y227184D01*
X-1843724Y227444D01*
X-1842554Y227184D01*
X-1841384Y226404D01*
G01X-1829334Y211844D02*
Y227444D01*
G01Y225104D02*
X-1828359Y226404D01*
X-1827384Y227184D01*
X-1825824Y227444D01*
X-1824459Y227184D01*
X-1823094Y225884D01*
X-1822509Y224064D01*
X-1822314Y222244D01*
X-1822509Y220424D01*
X-1823094Y218604D01*
X-1824264Y217564D01*
X-1825824Y217044D01*
X-1827189Y217304D01*
X-1828554Y218084D01*
X-1829334Y219124D01*
G01X-1810849Y224064D02*
X-1804609D01*
X-1805194Y225884D01*
X-1806169Y226924D01*
X-1807534Y227444D01*
X-1808899Y227184D01*
X-1810069Y226404D01*
X-1810849Y224584D01*
X-1811239Y223024D01*
Y221464D01*
X-1810849Y219904D01*
X-1809874Y218344D01*
X-1808704Y217304D01*
X-1807339Y217044D01*
X-1805974Y217564D01*
X-1804609Y219124D01*
G01X-1786904Y226144D02*
X-1788269Y227184D01*
X-1789439Y227444D01*
X-1790999Y226924D01*
X-1792169Y225884D01*
X-1792949Y224064D01*
X-1793144Y222244D01*
X-1792949Y220424D01*
X-1792169Y218864D01*
X-1790999Y217564D01*
X-1789439Y217044D01*
X-1788074Y217564D01*
X-1786904Y218604D01*
G01X-1772124Y227444D02*
Y217044D01*
G01Y231604D02*
X-1772514Y231864D01*
Y232384D01*
X-1772124Y232644D01*
X-1771734Y232384D01*
Y231864D01*
X-1772124Y231604D01*
G01X-1755394Y217044D02*
Y230304D01*
X-1755004Y231604D01*
X-1754224Y232384D01*
X-1753054Y232644D01*
X-1751884Y232124D01*
X-1751299Y230824D01*
G01X-1753639Y226404D02*
X-1757539D01*
G01X-1736324Y227444D02*
Y217044D01*
G01Y231604D02*
X-1736714Y231864D01*
Y232384D01*
X-1736324Y232644D01*
X-1735934Y232384D01*
Y231864D01*
X-1736324Y231604D01*
G01X-1721349Y224064D02*
X-1715109D01*
X-1715694Y225884D01*
X-1716669Y226924D01*
X-1718034Y227444D01*
X-1719399Y227184D01*
X-1720569Y226404D01*
X-1721349Y224584D01*
X-1721739Y223024D01*
Y221464D01*
X-1721349Y219904D01*
X-1720374Y218344D01*
X-1719204Y217304D01*
X-1717839Y217044D01*
X-1716474Y217564D01*
X-1715109Y219124D01*
G01X-1697014Y232644D02*
Y217044D01*
G01Y219384D02*
X-1697794Y218084D01*
X-1698964Y217304D01*
X-1700329Y217044D01*
X-1701889Y217564D01*
X-1703059Y218864D01*
X-1703839Y220424D01*
X-1704034Y222244D01*
X-1703839Y224064D01*
X-1703059Y225624D01*
X-1701889Y226924D01*
X-1700329Y227444D01*
X-1698964Y227184D01*
X-1697989Y226664D01*
X-1697014Y225624D01*
G01X-1664724Y227444D02*
Y217044D01*
G01Y231604D02*
X-1665114Y231864D01*
Y232384D01*
X-1664724Y232644D01*
X-1664334Y232384D01*
Y231864D01*
X-1664724Y231604D01*
G01X-1650139Y217044D02*
Y227444D01*
G01Y224844D02*
X-1649359Y226144D01*
X-1648189Y227184D01*
X-1646629Y227444D01*
X-1645264Y227184D01*
X-1644094Y226144D01*
X-1643509Y224324D01*
Y217044D01*
G01X-1611024Y232644D02*
Y217044D01*
G01X-1613754Y227444D02*
X-1608294D01*
G01X-1596439Y217044D02*
Y232644D01*
G01Y225104D02*
X-1595464Y226404D01*
X-1594489Y227184D01*
X-1592929Y227444D01*
X-1591759Y227184D01*
X-1590394Y226144D01*
X-1589809Y224584D01*
Y217044D01*
G01X-1578149Y224064D02*
X-1571909D01*
X-1572494Y225884D01*
X-1573469Y226924D01*
X-1574834Y227444D01*
X-1576199Y227184D01*
X-1577369Y226404D01*
X-1578149Y224584D01*
X-1578539Y223024D01*
Y221464D01*
X-1578149Y219904D01*
X-1577174Y218344D01*
X-1576004Y217304D01*
X-1574639Y217044D01*
X-1573274Y217564D01*
X-1571909Y219124D01*
G01X-1535914Y232644D02*
Y217044D01*
G01Y219384D02*
X-1536694Y218084D01*
X-1537864Y217304D01*
X-1539229Y217044D01*
X-1540789Y217564D01*
X-1541959Y218864D01*
X-1542739Y220424D01*
X-1542934Y222244D01*
X-1542739Y224064D01*
X-1541959Y225624D01*
X-1540789Y226924D01*
X-1539229Y227444D01*
X-1537864Y227184D01*
X-1536889Y226664D01*
X-1535914Y225624D01*
G01X-1524254Y217044D02*
Y227444D01*
G01Y225364D02*
X-1523279Y226404D01*
X-1522304Y227184D01*
X-1520939Y227444D01*
X-1519964Y227184D01*
X-1518794Y226404D01*
G01X-1503624Y227444D02*
Y217044D01*
G01Y231604D02*
X-1504014Y231864D01*
Y232384D01*
X-1503624Y232644D01*
X-1503234Y232384D01*
Y231864D01*
X-1503624Y231604D01*
G01X-1485724Y217044D02*
Y232644D01*
G01X-1467824Y217044D02*
Y232644D01*
G01X-1432024D02*
Y217044D01*
G01X-1434754Y227444D02*
X-1429294D01*
G01X-1410614Y217044D02*
Y227444D01*
G01Y225624D02*
X-1411394Y226664D01*
X-1412564Y227184D01*
X-1413929Y227444D01*
X-1415294Y226924D01*
X-1416464Y225884D01*
X-1417244Y224324D01*
X-1417634Y222244D01*
X-1417244Y220164D01*
X-1416464Y218604D01*
X-1415294Y217564D01*
X-1413929Y217044D01*
X-1412564Y217304D01*
X-1411394Y218084D01*
X-1410614Y219124D01*
G01X-1399734Y217044D02*
Y232644D01*
G01Y224844D02*
X-1398759Y226404D01*
X-1397589Y227184D01*
X-1396419Y227444D01*
X-1394664Y226924D01*
X-1393494Y225884D01*
X-1392714Y224064D01*
Y221984D01*
X-1393104Y219904D01*
X-1393884Y218344D01*
X-1395249Y217304D01*
X-1396419Y217044D01*
X-1397589Y217304D01*
X-1398759Y218084D01*
X-1399734Y219384D01*
G01X-1378324Y217044D02*
Y232644D01*
G01X-1363349Y224064D02*
X-1357109D01*
X-1357694Y225884D01*
X-1358669Y226924D01*
X-1360034Y227444D01*
X-1361399Y227184D01*
X-1362569Y226404D01*
X-1363349Y224584D01*
X-1363739Y223024D01*
Y221464D01*
X-1363349Y219904D01*
X-1362374Y218344D01*
X-1361204Y217304D01*
X-1359839Y217044D01*
X-1358474Y217564D01*
X-1357109Y219124D01*
G01X-1342524Y216524D02*
X-1342914Y216784D01*
Y217304D01*
X-1342524Y217564D01*
X-1342134Y217304D01*
Y216784D01*
X-1342524Y216524D01*
G01X-2022724Y388644D02*
Y373044D01*
G01X-2027209Y388644D02*
X-2018239D01*
G01X-2007749Y380064D02*
X-2001509D01*
X-2002094Y381884D01*
X-2003069Y382924D01*
X-2004434Y383444D01*
X-2005799Y383184D01*
X-2006969Y382404D01*
X-2007749Y380584D01*
X-2008139Y379024D01*
Y377464D01*
X-2007749Y375904D01*
X-2006774Y374344D01*
X-2005604Y373304D01*
X-2004239Y373044D01*
X-2002874Y373564D01*
X-2001509Y375124D01*
G01X-1983414Y373044D02*
Y383444D01*
G01Y381624D02*
X-1984194Y382664D01*
X-1985364Y383184D01*
X-1986729Y383444D01*
X-1988094Y382924D01*
X-1989264Y381884D01*
X-1990044Y380324D01*
X-1990434Y378244D01*
X-1990044Y376164D01*
X-1989264Y374604D01*
X-1988094Y373564D01*
X-1986729Y373044D01*
X-1985364Y373304D01*
X-1984194Y374084D01*
X-1983414Y375124D01*
G01X-1971754Y373044D02*
Y383444D01*
G01Y381364D02*
X-1970779Y382404D01*
X-1969804Y383184D01*
X-1968439Y383444D01*
X-1967464Y383184D01*
X-1966294Y382404D01*
G01X-1929714Y388644D02*
Y373044D01*
G01Y375384D02*
X-1930494Y374084D01*
X-1931664Y373304D01*
X-1933029Y373044D01*
X-1934589Y373564D01*
X-1935759Y374864D01*
X-1936539Y376424D01*
X-1936734Y378244D01*
X-1936539Y380064D01*
X-1935759Y381624D01*
X-1934589Y382924D01*
X-1933029Y383444D01*
X-1931664Y383184D01*
X-1930689Y382664D01*
X-1929714Y381624D01*
G01X-1918054Y373044D02*
Y383444D01*
G01Y381364D02*
X-1917079Y382404D01*
X-1916104Y383184D01*
X-1914739Y383444D01*
X-1913764Y383184D01*
X-1912594Y382404D01*
G01X-1897424Y373044D02*
X-1898594Y373304D01*
X-1899764Y374344D01*
X-1900544Y376164D01*
X-1900934Y378244D01*
X-1900544Y380324D01*
X-1899764Y382144D01*
X-1898594Y383184D01*
X-1897424Y383444D01*
X-1896254Y383184D01*
X-1895084Y382144D01*
X-1894304Y380324D01*
X-1894109Y378244D01*
X-1894304Y376164D01*
X-1895084Y374344D01*
X-1896254Y373304D01*
X-1897424Y373044D01*
G01X-1883034Y367844D02*
Y383444D01*
G01Y381104D02*
X-1882059Y382404D01*
X-1881084Y383184D01*
X-1879524Y383444D01*
X-1878159Y383184D01*
X-1876794Y381884D01*
X-1876209Y380064D01*
X-1876014Y378244D01*
X-1876209Y376424D01*
X-1876794Y374604D01*
X-1877964Y373564D01*
X-1879524Y373044D01*
X-1880889Y373304D01*
X-1882254Y374084D01*
X-1883034Y375124D01*
G01X-1865134Y367844D02*
Y383444D01*
G01Y381104D02*
X-1864159Y382404D01*
X-1863184Y383184D01*
X-1861624Y383444D01*
X-1860259Y383184D01*
X-1858894Y381884D01*
X-1858309Y380064D01*
X-1858114Y378244D01*
X-1858309Y376424D01*
X-1858894Y374604D01*
X-1860064Y373564D01*
X-1861624Y373044D01*
X-1862989Y373304D01*
X-1864354Y374084D01*
X-1865134Y375124D01*
G01X-1843724Y383444D02*
Y373044D01*
G01Y387604D02*
X-1844114Y387864D01*
Y388384D01*
X-1843724Y388644D01*
X-1843334Y388384D01*
Y387864D01*
X-1843724Y387604D01*
G01X-1829139Y373044D02*
Y383444D01*
G01Y380844D02*
X-1828359Y382144D01*
X-1827189Y383184D01*
X-1825629Y383444D01*
X-1824264Y383184D01*
X-1823094Y382144D01*
X-1822509Y380324D01*
Y373044D01*
G01X-1810654Y369144D02*
X-1809289Y368104D01*
X-1807729Y367844D01*
X-1806364Y368104D01*
X-1805194Y369404D01*
X-1804414Y371224D01*
Y383444D01*
G01Y381364D02*
X-1805194Y382404D01*
X-1806364Y383184D01*
X-1807729Y383444D01*
X-1809289Y382924D01*
X-1810264Y381884D01*
X-1811044Y380064D01*
X-1811434Y378244D01*
X-1811239Y376684D01*
X-1810459Y374864D01*
X-1809289Y373564D01*
X-1807729Y373044D01*
X-1806559Y373304D01*
X-1805194Y374344D01*
X-1804414Y375384D01*
G01X-1772124Y383444D02*
Y373044D01*
G01Y387604D02*
X-1772514Y387864D01*
Y388384D01*
X-1772124Y388644D01*
X-1771734Y388384D01*
Y387864D01*
X-1772124Y387604D01*
G01X-1757149Y374864D02*
X-1756174Y373824D01*
X-1754809Y373044D01*
X-1753639D01*
X-1752469Y373564D01*
X-1751689Y374344D01*
X-1751299Y375384D01*
X-1751494Y376944D01*
X-1752274Y377724D01*
X-1755784Y379284D01*
X-1756564Y381104D01*
X-1756174Y382404D01*
X-1755394Y383184D01*
X-1754224Y383444D01*
X-1753054Y383184D01*
X-1751884Y382404D01*
G01X-1714914Y373044D02*
Y383444D01*
G01Y381624D02*
X-1715694Y382664D01*
X-1716864Y383184D01*
X-1718229Y383444D01*
X-1719594Y382924D01*
X-1720764Y381884D01*
X-1721544Y380324D01*
X-1721934Y378244D01*
X-1721544Y376164D01*
X-1720764Y374604D01*
X-1719594Y373564D01*
X-1718229Y373044D01*
X-1716864Y373304D01*
X-1715694Y374084D01*
X-1714914Y375124D01*
G01X-1704034Y367844D02*
Y383444D01*
G01Y381104D02*
X-1703059Y382404D01*
X-1702084Y383184D01*
X-1700524Y383444D01*
X-1699159Y383184D01*
X-1697794Y381884D01*
X-1697209Y380064D01*
X-1697014Y378244D01*
X-1697209Y376424D01*
X-1697794Y374604D01*
X-1698964Y373564D01*
X-1700524Y373044D01*
X-1701889Y373304D01*
X-1703254Y374084D01*
X-1704034Y375124D01*
G01X-1686134Y367844D02*
Y383444D01*
G01Y381104D02*
X-1685159Y382404D01*
X-1684184Y383184D01*
X-1682624Y383444D01*
X-1681259Y383184D01*
X-1679894Y381884D01*
X-1679309Y380064D01*
X-1679114Y378244D01*
X-1679309Y376424D01*
X-1679894Y374604D01*
X-1681064Y373564D01*
X-1682624Y373044D01*
X-1683989Y373304D01*
X-1685354Y374084D01*
X-1686134Y375124D01*
G01X-1664724Y373044D02*
Y388644D01*
G01X-1646824Y383444D02*
Y373044D01*
G01Y387604D02*
X-1647214Y387864D01*
Y388384D01*
X-1646824Y388644D01*
X-1646434Y388384D01*
Y387864D01*
X-1646824Y387604D01*
G01X-1631849Y380064D02*
X-1625609D01*
X-1626194Y381884D01*
X-1627169Y382924D01*
X-1628534Y383444D01*
X-1629899Y383184D01*
X-1631069Y382404D01*
X-1631849Y380584D01*
X-1632239Y379024D01*
Y377464D01*
X-1631849Y375904D01*
X-1630874Y374344D01*
X-1629704Y373304D01*
X-1628339Y373044D01*
X-1626974Y373564D01*
X-1625609Y375124D01*
G01X-1607514Y388644D02*
Y373044D01*
G01Y375384D02*
X-1608294Y374084D01*
X-1609464Y373304D01*
X-1610829Y373044D01*
X-1612389Y373564D01*
X-1613559Y374864D01*
X-1614339Y376424D01*
X-1614534Y378244D01*
X-1614339Y380064D01*
X-1613559Y381624D01*
X-1612389Y382924D01*
X-1610829Y383444D01*
X-1609464Y383184D01*
X-1608489Y382664D01*
X-1607514Y381624D01*
G01X-1575224Y388644D02*
Y373044D01*
G01X-1577954Y383444D02*
X-1572494D01*
G01X-1557324Y373044D02*
X-1558494Y373304D01*
X-1559664Y374344D01*
X-1560444Y376164D01*
X-1560834Y378244D01*
X-1560444Y380324D01*
X-1559664Y382144D01*
X-1558494Y383184D01*
X-1557324Y383444D01*
X-1556154Y383184D01*
X-1554984Y382144D01*
X-1554204Y380324D01*
X-1554009Y378244D01*
X-1554204Y376164D01*
X-1554984Y374344D01*
X-1556154Y373304D01*
X-1557324Y373044D01*
G01X-1521524Y388644D02*
Y373044D01*
G01X-1524254Y383444D02*
X-1518794D01*
G01X-1506939Y373044D02*
Y388644D01*
G01Y381104D02*
X-1505964Y382404D01*
X-1504989Y383184D01*
X-1503429Y383444D01*
X-1502259Y383184D01*
X-1500894Y382144D01*
X-1500309Y380584D01*
Y373044D01*
G01X-1488649Y380064D02*
X-1482409D01*
X-1482994Y381884D01*
X-1483969Y382924D01*
X-1485334Y383444D01*
X-1486699Y383184D01*
X-1487869Y382404D01*
X-1488649Y380584D01*
X-1489039Y379024D01*
Y377464D01*
X-1488649Y375904D01*
X-1487674Y374344D01*
X-1486504Y373304D01*
X-1485139Y373044D01*
X-1483774Y373564D01*
X-1482409Y375124D01*
G01X-1452849Y380064D02*
X-1446609D01*
X-1447194Y381884D01*
X-1448169Y382924D01*
X-1449534Y383444D01*
X-1450899Y383184D01*
X-1452069Y382404D01*
X-1452849Y380584D01*
X-1453239Y379024D01*
Y377464D01*
X-1452849Y375904D01*
X-1451874Y374344D01*
X-1450704Y373304D01*
X-1449339Y373044D01*
X-1447974Y373564D01*
X-1446609Y375124D01*
G01X-1435339Y373044D02*
Y383444D01*
G01Y380844D02*
X-1434559Y382144D01*
X-1433389Y383184D01*
X-1431829Y383444D01*
X-1430464Y383184D01*
X-1429294Y382144D01*
X-1428709Y380324D01*
Y373044D01*
G01X-1414124Y388644D02*
Y373044D01*
G01X-1416854Y383444D02*
X-1411394D01*
G01X-1398954Y373044D02*
Y383444D01*
G01Y381364D02*
X-1397979Y382404D01*
X-1397004Y383184D01*
X-1395639Y383444D01*
X-1394664Y383184D01*
X-1393494Y382404D01*
G01X-1382419Y368364D02*
X-1381249Y367844D01*
X-1379689Y368364D01*
X-1378714Y369404D01*
X-1377934Y370704D01*
X-1376764Y374864D01*
X-1374229Y383444D01*
G01X-1380469D02*
X-1376764Y374864D01*
G01X-1342524Y373044D02*
X-1343694Y373304D01*
X-1344864Y374344D01*
X-1345644Y376164D01*
X-1346034Y378244D01*
X-1345644Y380324D01*
X-1344864Y382144D01*
X-1343694Y383184D01*
X-1342524Y383444D01*
X-1341354Y383184D01*
X-1340184Y382144D01*
X-1339404Y380324D01*
X-1339209Y378244D01*
X-1339404Y376164D01*
X-1340184Y374344D01*
X-1341354Y373304D01*
X-1342524Y373044D01*
G01X-1325794D02*
Y386304D01*
X-1325404Y387604D01*
X-1324624Y388384D01*
X-1323454Y388644D01*
X-1322284Y388124D01*
X-1321699Y386824D01*
G01X-1324039Y382404D02*
X-1327939D01*
G01X-1288824Y388644D02*
Y373044D01*
G01X-1291554Y383444D02*
X-1286094D01*
G01X-1274239Y373044D02*
Y388644D01*
G01Y381104D02*
X-1273264Y382404D01*
X-1272289Y383184D01*
X-1270729Y383444D01*
X-1269559Y383184D01*
X-1268194Y382144D01*
X-1267609Y380584D01*
Y373044D01*
G01X-1255949Y380064D02*
X-1249709D01*
X-1250294Y381884D01*
X-1251269Y382924D01*
X-1252634Y383444D01*
X-1253999Y383184D01*
X-1255169Y382404D01*
X-1255949Y380584D01*
X-1256339Y379024D01*
Y377464D01*
X-1255949Y375904D01*
X-1254974Y374344D01*
X-1253804Y373304D01*
X-1252439Y373044D01*
X-1251074Y373564D01*
X-1249709Y375124D01*
G01X-1217224Y388644D02*
Y373044D01*
G01X-1219954Y383444D02*
X-1214494D01*
G01X-1202054Y373044D02*
Y383444D01*
G01Y381364D02*
X-1201079Y382404D01*
X-1200104Y383184D01*
X-1198739Y383444D01*
X-1197764Y383184D01*
X-1196594Y382404D01*
G01X-1177914Y373044D02*
Y383444D01*
G01Y381624D02*
X-1178694Y382664D01*
X-1179864Y383184D01*
X-1181229Y383444D01*
X-1182594Y382924D01*
X-1183764Y381884D01*
X-1184544Y380324D01*
X-1184934Y378244D01*
X-1184544Y376164D01*
X-1183764Y374604D01*
X-1182594Y373564D01*
X-1181229Y373044D01*
X-1179864Y373304D01*
X-1178694Y374084D01*
X-1177914Y375124D01*
G01X-1160404Y382144D02*
X-1161769Y383184D01*
X-1162939Y383444D01*
X-1164499Y382924D01*
X-1165669Y381884D01*
X-1166449Y380064D01*
X-1166644Y378244D01*
X-1166449Y376424D01*
X-1165669Y374864D01*
X-1164499Y373564D01*
X-1162939Y373044D01*
X-1161574Y373564D01*
X-1160404Y374604D01*
G01X-1148549Y380064D02*
X-1142309D01*
X-1142894Y381884D01*
X-1143869Y382924D01*
X-1145234Y383444D01*
X-1146599Y383184D01*
X-1147769Y382404D01*
X-1148549Y380584D01*
X-1148939Y379024D01*
Y377464D01*
X-1148549Y375904D01*
X-1147574Y374344D01*
X-1146404Y373304D01*
X-1145039Y373044D01*
X-1143674Y373564D01*
X-1142309Y375124D01*
G01X-1109824Y388644D02*
Y373044D01*
G01X-1112554Y383444D02*
X-1107094D01*
G01X-1091924Y373044D02*
X-1093094Y373304D01*
X-1094264Y374344D01*
X-1095044Y376164D01*
X-1095434Y378244D01*
X-1095044Y380324D01*
X-1094264Y382144D01*
X-1093094Y383184D01*
X-1091924Y383444D01*
X-1090754Y383184D01*
X-1089584Y382144D01*
X-1088804Y380324D01*
X-1088609Y378244D01*
X-1088804Y376164D01*
X-1089584Y374344D01*
X-1090754Y373304D01*
X-1091924Y373044D01*
G01X-1056124Y388644D02*
Y373044D01*
G01X-1058854Y383444D02*
X-1053394D01*
G01X-1041539Y373044D02*
Y388644D01*
G01Y381104D02*
X-1040564Y382404D01*
X-1039589Y383184D01*
X-1038029Y383444D01*
X-1036859Y383184D01*
X-1035494Y382144D01*
X-1034909Y380584D01*
Y373044D01*
G01X-1023249Y380064D02*
X-1017009D01*
X-1017594Y381884D01*
X-1018569Y382924D01*
X-1019934Y383444D01*
X-1021299Y383184D01*
X-1022469Y382404D01*
X-1023249Y380584D01*
X-1023639Y379024D01*
Y377464D01*
X-1023249Y375904D01*
X-1022274Y374344D01*
X-1021104Y373304D01*
X-1019739Y373044D01*
X-1018374Y373564D01*
X-1017009Y375124D01*
G01X-988034Y367844D02*
Y383444D01*
G01Y381104D02*
X-987059Y382404D01*
X-986084Y383184D01*
X-984524Y383444D01*
X-983159Y383184D01*
X-981794Y381884D01*
X-981209Y380064D01*
X-981014Y378244D01*
X-981209Y376424D01*
X-981794Y374604D01*
X-982964Y373564D01*
X-984524Y373044D01*
X-985889Y373304D01*
X-987254Y374084D01*
X-988034Y375124D01*
G01X-963114Y373044D02*
Y383444D01*
G01Y381624D02*
X-963894Y382664D01*
X-965064Y383184D01*
X-966429Y383444D01*
X-967794Y382924D01*
X-968964Y381884D01*
X-969744Y380324D01*
X-970134Y378244D01*
X-969744Y376164D01*
X-968964Y374604D01*
X-967794Y373564D01*
X-966429Y373044D01*
X-965064Y373304D01*
X-963894Y374084D01*
X-963114Y375124D01*
G01X-945214Y388644D02*
Y373044D01*
G01Y375384D02*
X-945994Y374084D01*
X-947164Y373304D01*
X-948529Y373044D01*
X-950089Y373564D01*
X-951259Y374864D01*
X-952039Y376424D01*
X-952234Y378244D01*
X-952039Y380064D01*
X-951259Y381624D01*
X-950089Y382924D01*
X-948529Y383444D01*
X-947164Y383184D01*
X-946189Y382664D01*
X-945214Y381624D01*
G01X-930824Y372524D02*
X-931214Y372784D01*
Y373304D01*
X-930824Y373564D01*
X-930434Y373304D01*
Y372784D01*
X-930824Y372524D01*
G01X-2028574Y563044D02*
Y573444D01*
G01Y570584D02*
X-2027989Y571884D01*
X-2027014Y572924D01*
X-2025649Y573444D01*
X-2024284Y572924D01*
X-2023309Y571884D01*
X-2022724Y570584D01*
Y563044D01*
G01Y570584D02*
X-2022139Y571884D01*
X-2021164Y572924D01*
X-2019799Y573444D01*
X-2018434Y572924D01*
X-2017459Y571884D01*
X-2016874Y570324D01*
Y563044D01*
G01X-2007749Y570064D02*
X-2001509D01*
X-2002094Y571884D01*
X-2003069Y572924D01*
X-2004434Y573444D01*
X-2005799Y573184D01*
X-2006969Y572404D01*
X-2007749Y570584D01*
X-2008139Y569024D01*
Y567464D01*
X-2007749Y565904D01*
X-2006774Y564344D01*
X-2005604Y563304D01*
X-2004239Y563044D01*
X-2002874Y563564D01*
X-2001509Y565124D01*
G01X-1983414Y563044D02*
Y573444D01*
G01Y571624D02*
X-1984194Y572664D01*
X-1985364Y573184D01*
X-1986729Y573444D01*
X-1988094Y572924D01*
X-1989264Y571884D01*
X-1990044Y570324D01*
X-1990434Y568244D01*
X-1990044Y566164D01*
X-1989264Y564604D01*
X-1988094Y563564D01*
X-1986729Y563044D01*
X-1985364Y563304D01*
X-1984194Y564084D01*
X-1983414Y565124D01*
G01X-1971949Y564864D02*
X-1970974Y563824D01*
X-1969609Y563044D01*
X-1968439D01*
X-1967269Y563564D01*
X-1966489Y564344D01*
X-1966099Y565384D01*
X-1966294Y566944D01*
X-1967074Y567724D01*
X-1970584Y569284D01*
X-1971364Y571104D01*
X-1970974Y572404D01*
X-1970194Y573184D01*
X-1969024Y573444D01*
X-1967854Y573184D01*
X-1966684Y572404D01*
G01X-1954439Y573444D02*
Y566164D01*
X-1953659Y564344D01*
X-1952489Y563304D01*
X-1951124Y563044D01*
X-1949759Y563304D01*
X-1948589Y564344D01*
X-1947809Y566164D01*
G01Y563044D02*
Y573444D01*
G01X-1935954Y563044D02*
Y573444D01*
G01Y571364D02*
X-1934979Y572404D01*
X-1934004Y573184D01*
X-1932639Y573444D01*
X-1931664Y573184D01*
X-1930494Y572404D01*
G01X-1918249Y570064D02*
X-1912009D01*
X-1912594Y571884D01*
X-1913569Y572924D01*
X-1914934Y573444D01*
X-1916299Y573184D01*
X-1917469Y572404D01*
X-1918249Y570584D01*
X-1918639Y569024D01*
Y567464D01*
X-1918249Y565904D01*
X-1917274Y564344D01*
X-1916104Y563304D01*
X-1914739Y563044D01*
X-1913374Y563564D01*
X-1912009Y565124D01*
G01X-1903274Y563044D02*
Y573444D01*
G01Y570584D02*
X-1902689Y571884D01*
X-1901714Y572924D01*
X-1900349Y573444D01*
X-1898984Y572924D01*
X-1898009Y571884D01*
X-1897424Y570584D01*
Y563044D01*
G01Y570584D02*
X-1896839Y571884D01*
X-1895864Y572924D01*
X-1894499Y573444D01*
X-1893134Y572924D01*
X-1892159Y571884D01*
X-1891574Y570324D01*
Y563044D01*
G01X-1882449Y570064D02*
X-1876209D01*
X-1876794Y571884D01*
X-1877769Y572924D01*
X-1879134Y573444D01*
X-1880499Y573184D01*
X-1881669Y572404D01*
X-1882449Y570584D01*
X-1882839Y569024D01*
Y567464D01*
X-1882449Y565904D01*
X-1881474Y564344D01*
X-1880304Y563304D01*
X-1878939Y563044D01*
X-1877574Y563564D01*
X-1876209Y565124D01*
G01X-1864939Y563044D02*
Y573444D01*
G01Y570844D02*
X-1864159Y572144D01*
X-1862989Y573184D01*
X-1861429Y573444D01*
X-1860064Y573184D01*
X-1858894Y572144D01*
X-1858309Y570324D01*
Y563044D01*
G01X-1843724Y578644D02*
Y563044D01*
G01X-1846454Y573444D02*
X-1840994D01*
G01X-1810849Y564864D02*
X-1809874Y563824D01*
X-1808509Y563044D01*
X-1807339D01*
X-1806169Y563564D01*
X-1805389Y564344D01*
X-1804999Y565384D01*
X-1805194Y566944D01*
X-1805974Y567724D01*
X-1809484Y569284D01*
X-1810264Y571104D01*
X-1809874Y572404D01*
X-1809094Y573184D01*
X-1807924Y573444D01*
X-1806754Y573184D01*
X-1805584Y572404D01*
G01X-1793339Y563044D02*
Y578644D01*
G01Y571104D02*
X-1792364Y572404D01*
X-1791389Y573184D01*
X-1789829Y573444D01*
X-1788659Y573184D01*
X-1787294Y572144D01*
X-1786709Y570584D01*
Y563044D01*
G01X-1768614D02*
Y573444D01*
G01Y571624D02*
X-1769394Y572664D01*
X-1770564Y573184D01*
X-1771929Y573444D01*
X-1773294Y572924D01*
X-1774464Y571884D01*
X-1775244Y570324D01*
X-1775634Y568244D01*
X-1775244Y566164D01*
X-1774464Y564604D01*
X-1773294Y563564D01*
X-1771929Y563044D01*
X-1770564Y563304D01*
X-1769394Y564084D01*
X-1768614Y565124D01*
G01X-1754224Y563044D02*
Y578644D01*
G01X-1736324Y563044D02*
Y578644D01*
G01X-1704034Y563044D02*
Y578644D01*
G01Y570844D02*
X-1703059Y572404D01*
X-1701889Y573184D01*
X-1700719Y573444D01*
X-1698964Y572924D01*
X-1697794Y571884D01*
X-1697014Y570064D01*
Y567984D01*
X-1697404Y565904D01*
X-1698184Y564344D01*
X-1699549Y563304D01*
X-1700719Y563044D01*
X-1701889Y563304D01*
X-1703059Y564084D01*
X-1704034Y565384D01*
G01X-1685549Y570064D02*
X-1679309D01*
X-1679894Y571884D01*
X-1680869Y572924D01*
X-1682234Y573444D01*
X-1683599Y573184D01*
X-1684769Y572404D01*
X-1685549Y570584D01*
X-1685939Y569024D01*
Y567464D01*
X-1685549Y565904D01*
X-1684574Y564344D01*
X-1683404Y563304D01*
X-1682039Y563044D01*
X-1680674Y563564D01*
X-1679309Y565124D01*
G01X-1646824Y578644D02*
Y563044D01*
G01X-1649554Y573444D02*
X-1644094D01*
G01X-1625414Y563044D02*
Y573444D01*
G01Y571624D02*
X-1626194Y572664D01*
X-1627364Y573184D01*
X-1628729Y573444D01*
X-1630094Y572924D01*
X-1631264Y571884D01*
X-1632044Y570324D01*
X-1632434Y568244D01*
X-1632044Y566164D01*
X-1631264Y564604D01*
X-1630094Y563564D01*
X-1628729Y563044D01*
X-1627364Y563304D01*
X-1626194Y564084D01*
X-1625414Y565124D01*
G01X-1614339Y563044D02*
Y578644D01*
G01X-1608099Y573444D02*
X-1614339Y567464D01*
G01X-1611804Y569804D02*
X-1607709Y563044D01*
G01X-1596049Y570064D02*
X-1589809D01*
X-1590394Y571884D01*
X-1591369Y572924D01*
X-1592734Y573444D01*
X-1594099Y573184D01*
X-1595269Y572404D01*
X-1596049Y570584D01*
X-1596439Y569024D01*
Y567464D01*
X-1596049Y565904D01*
X-1595074Y564344D01*
X-1593904Y563304D01*
X-1592539Y563044D01*
X-1591174Y563564D01*
X-1589809Y565124D01*
G01X-1578539Y563044D02*
Y573444D01*
G01Y570844D02*
X-1577759Y572144D01*
X-1576589Y573184D01*
X-1575029Y573444D01*
X-1573664Y573184D01*
X-1572494Y572144D01*
X-1571909Y570324D01*
Y563044D01*
G01X-1542934Y557844D02*
Y573444D01*
G01Y571104D02*
X-1541959Y572404D01*
X-1540984Y573184D01*
X-1539424Y573444D01*
X-1538059Y573184D01*
X-1536694Y571884D01*
X-1536109Y570064D01*
X-1535914Y568244D01*
X-1536109Y566424D01*
X-1536694Y564604D01*
X-1537864Y563564D01*
X-1539424Y563044D01*
X-1540789Y563304D01*
X-1542154Y564084D01*
X-1542934Y565124D01*
G01X-1524449Y570064D02*
X-1518209D01*
X-1518794Y571884D01*
X-1519769Y572924D01*
X-1521134Y573444D01*
X-1522499Y573184D01*
X-1523669Y572404D01*
X-1524449Y570584D01*
X-1524839Y569024D01*
Y567464D01*
X-1524449Y565904D01*
X-1523474Y564344D01*
X-1522304Y563304D01*
X-1520939Y563044D01*
X-1519574Y563564D01*
X-1518209Y565124D01*
G01X-1506354Y563044D02*
Y573444D01*
G01Y571364D02*
X-1505379Y572404D01*
X-1504404Y573184D01*
X-1503039Y573444D01*
X-1502064Y573184D01*
X-1500894Y572404D01*
G01X-1467824Y578644D02*
Y563044D01*
G01X-1470554Y573444D02*
X-1465094D01*
G01X-1453239Y563044D02*
Y578644D01*
G01Y571104D02*
X-1452264Y572404D01*
X-1451289Y573184D01*
X-1449729Y573444D01*
X-1448559Y573184D01*
X-1447194Y572144D01*
X-1446609Y570584D01*
Y563044D01*
G01X-1434949Y570064D02*
X-1428709D01*
X-1429294Y571884D01*
X-1430269Y572924D01*
X-1431634Y573444D01*
X-1432999Y573184D01*
X-1434169Y572404D01*
X-1434949Y570584D01*
X-1435339Y569024D01*
Y567464D01*
X-1434949Y565904D01*
X-1433974Y564344D01*
X-1432804Y563304D01*
X-1431439Y563044D01*
X-1430074Y563564D01*
X-1428709Y565124D01*
G01X-1398564Y578644D02*
X-1393884D01*
G01X-1396224D02*
Y563044D01*
G01X-1398564D02*
X-1393884D01*
G01X-1382224D02*
Y578644D01*
X-1377544D01*
X-1375984Y577864D01*
X-1374814Y576044D01*
X-1374424Y573964D01*
X-1374814Y571884D01*
X-1375789Y570324D01*
X-1377544Y569544D01*
X-1382224D01*
G01X-1356134Y577344D02*
X-1357304Y578124D01*
X-1358669Y578644D01*
X-1360229D01*
X-1361984Y577864D01*
X-1363349Y576564D01*
X-1364324Y575004D01*
X-1365104Y572404D01*
X-1365299Y570064D01*
X-1364909Y567724D01*
X-1364324Y566164D01*
X-1363154Y564604D01*
X-1361789Y563564D01*
X-1360424Y563044D01*
X-1359059D01*
X-1357694Y563564D01*
X-1356524Y564344D01*
X-1355549Y565384D01*
G01X-1328329Y569544D02*
X-1326964Y571364D01*
X-1325794Y572404D01*
X-1324234Y572924D01*
X-1322869Y572404D01*
X-1321894Y571364D01*
X-1321114Y569804D01*
X-1320919Y567984D01*
X-1321114Y566424D01*
X-1321894Y564864D01*
X-1323064Y563564D01*
X-1324429Y563044D01*
X-1325989Y563564D01*
X-1327354Y565124D01*
X-1328134Y567464D01*
X-1328329Y570064D01*
X-1327939Y573444D01*
X-1327354Y575264D01*
X-1326379Y577084D01*
X-1325014Y578384D01*
X-1323649Y578644D01*
X-1322284Y578124D01*
X-1321309Y576824D01*
G01X-1306724Y578644D02*
X-1308284Y578124D01*
X-1309454Y576824D01*
X-1310234Y575264D01*
X-1310819Y573184D01*
X-1311014Y570844D01*
X-1310819Y568504D01*
X-1310234Y566424D01*
X-1309454Y564864D01*
X-1308284Y563564D01*
X-1306724Y563044D01*
X-1305164Y563564D01*
X-1303994Y564864D01*
X-1303214Y566424D01*
X-1302629Y568504D01*
X-1302434Y570844D01*
X-1302629Y573184D01*
X-1303214Y575264D01*
X-1303994Y576824D01*
X-1305164Y578124D01*
X-1306724Y578644D01*
G01X-1288824Y563044D02*
Y578644D01*
X-1291164Y575524D01*
G01Y563044D02*
X-1286484D01*
G01X-1274629Y576044D02*
X-1273459Y577604D01*
X-1272094Y578384D01*
X-1270534Y578644D01*
X-1268584Y578124D01*
X-1267219Y576824D01*
X-1266829Y575264D01*
X-1267024Y573704D01*
X-1267804Y572404D01*
X-1271704Y569804D01*
X-1273459Y567984D01*
X-1274629Y565384D01*
X-1275019Y563044D01*
X-1266829D01*
G01X-1235124D02*
Y578644D01*
G01X-1213714Y563044D02*
Y573444D01*
G01Y571624D02*
X-1214494Y572664D01*
X-1215664Y573184D01*
X-1217029Y573444D01*
X-1218394Y572924D01*
X-1219564Y571884D01*
X-1220344Y570324D01*
X-1220734Y568244D01*
X-1220344Y566164D01*
X-1219564Y564604D01*
X-1218394Y563564D01*
X-1217029Y563044D01*
X-1215664Y563304D01*
X-1214494Y564084D01*
X-1213714Y565124D01*
G01X-1199324Y578644D02*
Y563044D01*
G01X-1202054Y573444D02*
X-1196594D01*
G01X-1184349Y570064D02*
X-1178109D01*
X-1178694Y571884D01*
X-1179669Y572924D01*
X-1181034Y573444D01*
X-1182399Y573184D01*
X-1183569Y572404D01*
X-1184349Y570584D01*
X-1184739Y569024D01*
Y567464D01*
X-1184349Y565904D01*
X-1183374Y564344D01*
X-1182204Y563304D01*
X-1180839Y563044D01*
X-1179474Y563564D01*
X-1178109Y565124D01*
G01X-1166449Y564864D02*
X-1165474Y563824D01*
X-1164109Y563044D01*
X-1162939D01*
X-1161769Y563564D01*
X-1160989Y564344D01*
X-1160599Y565384D01*
X-1160794Y566944D01*
X-1161574Y567724D01*
X-1165084Y569284D01*
X-1165864Y571104D01*
X-1165474Y572404D01*
X-1164694Y573184D01*
X-1163524Y573444D01*
X-1162354Y573184D01*
X-1161184Y572404D01*
G01X-1145624Y578644D02*
Y563044D01*
G01X-1148354Y573444D02*
X-1142894D01*
G01X-1112554Y563044D02*
Y573444D01*
G01Y571364D02*
X-1111579Y572404D01*
X-1110604Y573184D01*
X-1109239Y573444D01*
X-1108264Y573184D01*
X-1107094Y572404D01*
G01X-1094849Y570064D02*
X-1088609D01*
X-1089194Y571884D01*
X-1090169Y572924D01*
X-1091534Y573444D01*
X-1092899Y573184D01*
X-1094069Y572404D01*
X-1094849Y570584D01*
X-1095239Y569024D01*
Y567464D01*
X-1094849Y565904D01*
X-1093874Y564344D01*
X-1092704Y563304D01*
X-1091339Y563044D01*
X-1089974Y563564D01*
X-1088609Y565124D01*
G01X-1077534Y573444D02*
X-1074024Y563044D01*
X-1070514Y573444D01*
G01X-1056124D02*
Y563044D01*
G01Y577604D02*
X-1056514Y577864D01*
Y578384D01*
X-1056124Y578644D01*
X-1055734Y578384D01*
Y577864D01*
X-1056124Y577604D01*
G01X-1041149Y564864D02*
X-1040174Y563824D01*
X-1038809Y563044D01*
X-1037639D01*
X-1036469Y563564D01*
X-1035689Y564344D01*
X-1035299Y565384D01*
X-1035494Y566944D01*
X-1036274Y567724D01*
X-1039784Y569284D01*
X-1040564Y571104D01*
X-1040174Y572404D01*
X-1039394Y573184D01*
X-1038224Y573444D01*
X-1037054Y573184D01*
X-1035884Y572404D01*
G01X-1020324Y573444D02*
Y563044D01*
G01Y577604D02*
X-1020714Y577864D01*
Y578384D01*
X-1020324Y578644D01*
X-1019934Y578384D01*
Y577864D01*
X-1020324Y577604D01*
G01X-1002424Y563044D02*
X-1003594Y563304D01*
X-1004764Y564344D01*
X-1005544Y566164D01*
X-1005934Y568244D01*
X-1005544Y570324D01*
X-1004764Y572144D01*
X-1003594Y573184D01*
X-1002424Y573444D01*
X-1001254Y573184D01*
X-1000084Y572144D01*
X-999304Y570324D01*
X-999109Y568244D01*
X-999304Y566164D01*
X-1000084Y564344D01*
X-1001254Y563304D01*
X-1002424Y563044D01*
G01X-987839D02*
Y573444D01*
G01Y570844D02*
X-987059Y572144D01*
X-985889Y573184D01*
X-984329Y573444D01*
X-982964Y573184D01*
X-981794Y572144D01*
X-981209Y570324D01*
Y563044D01*
G01X-2026039Y597044D02*
Y607444D01*
G01Y604844D02*
X-2025259Y606144D01*
X-2024089Y607184D01*
X-2022529Y607444D01*
X-2021164Y607184D01*
X-2019994Y606144D01*
X-2019409Y604324D01*
Y597044D01*
G01X-2004824D02*
X-2005994Y597304D01*
X-2007164Y598344D01*
X-2007944Y600164D01*
X-2008334Y602244D01*
X-2007944Y604324D01*
X-2007164Y606144D01*
X-2005994Y607184D01*
X-2004824Y607444D01*
X-2003654Y607184D01*
X-2002484Y606144D01*
X-2001704Y604324D01*
X-2001509Y602244D01*
X-2001704Y600164D01*
X-2002484Y598344D01*
X-2003654Y597304D01*
X-2004824Y597044D01*
G01X-1986924Y612644D02*
Y597044D01*
G01X-1989654Y607444D02*
X-1984194D01*
G01X-1954634Y597044D02*
Y612644D01*
G01Y604844D02*
X-1953659Y606404D01*
X-1952489Y607184D01*
X-1951319Y607444D01*
X-1949564Y606924D01*
X-1948394Y605884D01*
X-1947614Y604064D01*
Y601984D01*
X-1948004Y599904D01*
X-1948784Y598344D01*
X-1950149Y597304D01*
X-1951319Y597044D01*
X-1952489Y597304D01*
X-1953659Y598084D01*
X-1954634Y599384D01*
G01X-1936149Y604064D02*
X-1929909D01*
X-1930494Y605884D01*
X-1931469Y606924D01*
X-1932834Y607444D01*
X-1934199Y607184D01*
X-1935369Y606404D01*
X-1936149Y604584D01*
X-1936539Y603024D01*
Y601464D01*
X-1936149Y599904D01*
X-1935174Y598344D01*
X-1934004Y597304D01*
X-1932639Y597044D01*
X-1931274Y597564D01*
X-1929909Y599124D01*
G01X-1897424Y597044D02*
Y612644D01*
G01X-1882449Y604064D02*
X-1876209D01*
X-1876794Y605884D01*
X-1877769Y606924D01*
X-1879134Y607444D01*
X-1880499Y607184D01*
X-1881669Y606404D01*
X-1882449Y604584D01*
X-1882839Y603024D01*
Y601464D01*
X-1882449Y599904D01*
X-1881474Y598344D01*
X-1880304Y597304D01*
X-1878939Y597044D01*
X-1877574Y597564D01*
X-1876209Y599124D01*
G01X-1864549Y598864D02*
X-1863574Y597824D01*
X-1862209Y597044D01*
X-1861039D01*
X-1859869Y597564D01*
X-1859089Y598344D01*
X-1858699Y599384D01*
X-1858894Y600944D01*
X-1859674Y601724D01*
X-1863184Y603284D01*
X-1863964Y605104D01*
X-1863574Y606404D01*
X-1862794Y607184D01*
X-1861624Y607444D01*
X-1860454Y607184D01*
X-1859284Y606404D01*
G01X-1846649Y598864D02*
X-1845674Y597824D01*
X-1844309Y597044D01*
X-1843139D01*
X-1841969Y597564D01*
X-1841189Y598344D01*
X-1840799Y599384D01*
X-1840994Y600944D01*
X-1841774Y601724D01*
X-1845284Y603284D01*
X-1846064Y605104D01*
X-1845674Y606404D01*
X-1844894Y607184D01*
X-1843724Y607444D01*
X-1842554Y607184D01*
X-1841384Y606404D01*
G01X-1807924Y612644D02*
Y597044D01*
G01X-1810654Y607444D02*
X-1805194D01*
G01X-1793339Y597044D02*
Y612644D01*
G01Y605104D02*
X-1792364Y606404D01*
X-1791389Y607184D01*
X-1789829Y607444D01*
X-1788659Y607184D01*
X-1787294Y606144D01*
X-1786709Y604584D01*
Y597044D01*
G01X-1768614D02*
Y607444D01*
G01Y605624D02*
X-1769394Y606664D01*
X-1770564Y607184D01*
X-1771929Y607444D01*
X-1773294Y606924D01*
X-1774464Y605884D01*
X-1775244Y604324D01*
X-1775634Y602244D01*
X-1775244Y600164D01*
X-1774464Y598604D01*
X-1773294Y597564D01*
X-1771929Y597044D01*
X-1770564Y597304D01*
X-1769394Y598084D01*
X-1768614Y599124D01*
G01X-1757539Y597044D02*
Y607444D01*
G01Y604844D02*
X-1756759Y606144D01*
X-1755589Y607184D01*
X-1754029Y607444D01*
X-1752664Y607184D01*
X-1751494Y606144D01*
X-1750909Y604324D01*
Y597044D01*
G01X-1718424Y612644D02*
X-1719984Y612124D01*
X-1721154Y610824D01*
X-1721934Y609264D01*
X-1722519Y607184D01*
X-1722714Y604844D01*
X-1722519Y602504D01*
X-1721934Y600424D01*
X-1721154Y598864D01*
X-1719984Y597564D01*
X-1718424Y597044D01*
X-1716864Y597564D01*
X-1715694Y598864D01*
X-1714914Y600424D01*
X-1714329Y602504D01*
X-1714134Y604844D01*
X-1714329Y607184D01*
X-1714914Y609264D01*
X-1715694Y610824D01*
X-1716864Y612124D01*
X-1718424Y612644D01*
G01X-1700524Y596524D02*
X-1700914Y596784D01*
Y597304D01*
X-1700524Y597564D01*
X-1700134Y597304D01*
Y596784D01*
X-1700524Y596524D01*
G01X-1682624Y612644D02*
X-1684184Y612124D01*
X-1685354Y610824D01*
X-1686134Y609264D01*
X-1686719Y607184D01*
X-1686914Y604844D01*
X-1686719Y602504D01*
X-1686134Y600424D01*
X-1685354Y598864D01*
X-1684184Y597564D01*
X-1682624Y597044D01*
X-1681064Y597564D01*
X-1679894Y598864D01*
X-1679114Y600424D01*
X-1678529Y602504D01*
X-1678334Y604844D01*
X-1678529Y607184D01*
X-1679114Y609264D01*
X-1679894Y610824D01*
X-1681064Y612124D01*
X-1682624Y612644D01*
G01X-1664724D02*
X-1666284Y612124D01*
X-1667454Y610824D01*
X-1668234Y609264D01*
X-1668819Y607184D01*
X-1669014Y604844D01*
X-1668819Y602504D01*
X-1668234Y600424D01*
X-1667454Y598864D01*
X-1666284Y597564D01*
X-1664724Y597044D01*
X-1663164Y597564D01*
X-1661994Y598864D01*
X-1661214Y600424D01*
X-1660629Y602504D01*
X-1660434Y604844D01*
X-1660629Y607184D01*
X-1661214Y609264D01*
X-1661994Y610824D01*
X-1663164Y612124D01*
X-1664724Y612644D01*
G01X-1646824Y597044D02*
Y612644D01*
X-1649164Y609524D01*
G01Y597044D02*
X-1644484D01*
G01X-1630679Y609264D02*
X-1629704Y612644D01*
G01X-1627169D02*
X-1628144Y609264D01*
G01X-1611414Y594184D02*
X-1610634Y597564D01*
G01X-1580099Y607444D02*
X-1577759Y597044D01*
X-1575224Y607444D01*
X-1572689Y597044D01*
X-1570349Y607444D01*
G01X-1557324D02*
Y597044D01*
G01Y611604D02*
X-1557714Y611864D01*
Y612384D01*
X-1557324Y612644D01*
X-1556934Y612384D01*
Y611864D01*
X-1557324Y611604D01*
G01X-1539424Y612644D02*
Y597044D01*
G01X-1542154Y607444D02*
X-1536694D01*
G01X-1524839Y597044D02*
Y612644D01*
G01Y605104D02*
X-1523864Y606404D01*
X-1522889Y607184D01*
X-1521329Y607444D01*
X-1520159Y607184D01*
X-1518794Y606144D01*
X-1518209Y604584D01*
Y597044D01*
G01X-1489039D02*
Y607444D01*
G01Y604844D02*
X-1488259Y606144D01*
X-1487089Y607184D01*
X-1485529Y607444D01*
X-1484164Y607184D01*
X-1482994Y606144D01*
X-1482409Y604324D01*
Y597044D01*
G01X-1467824D02*
X-1468994Y597304D01*
X-1470164Y598344D01*
X-1470944Y600164D01*
X-1471334Y602244D01*
X-1470944Y604324D01*
X-1470164Y606144D01*
X-1468994Y607184D01*
X-1467824Y607444D01*
X-1466654Y607184D01*
X-1465484Y606144D01*
X-1464704Y604324D01*
X-1464509Y602244D01*
X-1464704Y600164D01*
X-1465484Y598344D01*
X-1466654Y597304D01*
X-1467824Y597044D01*
G01X-1434949Y598864D02*
X-1433974Y597824D01*
X-1432609Y597044D01*
X-1431439D01*
X-1430269Y597564D01*
X-1429489Y598344D01*
X-1429099Y599384D01*
X-1429294Y600944D01*
X-1430074Y601724D01*
X-1433584Y603284D01*
X-1434364Y605104D01*
X-1433974Y606404D01*
X-1433194Y607184D01*
X-1432024Y607444D01*
X-1430854Y607184D01*
X-1429684Y606404D01*
G01X-1414124Y607444D02*
Y597044D01*
G01Y611604D02*
X-1414514Y611864D01*
Y612384D01*
X-1414124Y612644D01*
X-1413734Y612384D01*
Y611864D01*
X-1414124Y611604D01*
G01X-1399539Y597044D02*
Y607444D01*
G01Y604844D02*
X-1398759Y606144D01*
X-1397589Y607184D01*
X-1396029Y607444D01*
X-1394664Y607184D01*
X-1393494Y606144D01*
X-1392909Y604324D01*
Y597044D01*
G01X-1381054Y593144D02*
X-1379689Y592104D01*
X-1378129Y591844D01*
X-1376764Y592104D01*
X-1375594Y593404D01*
X-1374814Y595224D01*
Y607444D01*
G01Y605364D02*
X-1375594Y606404D01*
X-1376764Y607184D01*
X-1378129Y607444D01*
X-1379689Y606924D01*
X-1380664Y605884D01*
X-1381444Y604064D01*
X-1381834Y602244D01*
X-1381639Y600684D01*
X-1380859Y598864D01*
X-1379689Y597564D01*
X-1378129Y597044D01*
X-1376959Y597304D01*
X-1375594Y598344D01*
X-1374814Y599384D01*
G01X-1360424Y597044D02*
Y612644D01*
G01X-1345449Y604064D02*
X-1339209D01*
X-1339794Y605884D01*
X-1340769Y606924D01*
X-1342134Y607444D01*
X-1343499Y607184D01*
X-1344669Y606404D01*
X-1345449Y604584D01*
X-1345839Y603024D01*
Y601464D01*
X-1345449Y599904D01*
X-1344474Y598344D01*
X-1343304Y597304D01*
X-1341939Y597044D01*
X-1340574Y597564D01*
X-1339209Y599124D01*
G01X-1312574Y597044D02*
Y607444D01*
G01Y604584D02*
X-1311989Y605884D01*
X-1311014Y606924D01*
X-1309649Y607444D01*
X-1308284Y606924D01*
X-1307309Y605884D01*
X-1306724Y604584D01*
Y597044D01*
G01Y604584D02*
X-1306139Y605884D01*
X-1305164Y606924D01*
X-1303799Y607444D01*
X-1302434Y606924D01*
X-1301459Y605884D01*
X-1300874Y604324D01*
Y597044D01*
G01X-1291749Y604064D02*
X-1285509D01*
X-1286094Y605884D01*
X-1287069Y606924D01*
X-1288434Y607444D01*
X-1289799Y607184D01*
X-1290969Y606404D01*
X-1291749Y604584D01*
X-1292139Y603024D01*
Y601464D01*
X-1291749Y599904D01*
X-1290774Y598344D01*
X-1289604Y597304D01*
X-1288239Y597044D01*
X-1286874Y597564D01*
X-1285509Y599124D01*
G01X-1267414Y597044D02*
Y607444D01*
G01Y605624D02*
X-1268194Y606664D01*
X-1269364Y607184D01*
X-1270729Y607444D01*
X-1272094Y606924D01*
X-1273264Y605884D01*
X-1274044Y604324D01*
X-1274434Y602244D01*
X-1274044Y600164D01*
X-1273264Y598604D01*
X-1272094Y597564D01*
X-1270729Y597044D01*
X-1269364Y597304D01*
X-1268194Y598084D01*
X-1267414Y599124D01*
G01X-1255949Y598864D02*
X-1254974Y597824D01*
X-1253609Y597044D01*
X-1252439D01*
X-1251269Y597564D01*
X-1250489Y598344D01*
X-1250099Y599384D01*
X-1250294Y600944D01*
X-1251074Y601724D01*
X-1254584Y603284D01*
X-1255364Y605104D01*
X-1254974Y606404D01*
X-1254194Y607184D01*
X-1253024Y607444D01*
X-1251854Y607184D01*
X-1250684Y606404D01*
G01X-1238439Y607444D02*
Y600164D01*
X-1237659Y598344D01*
X-1236489Y597304D01*
X-1235124Y597044D01*
X-1233759Y597304D01*
X-1232589Y598344D01*
X-1231809Y600164D01*
G01Y597044D02*
Y607444D01*
G01X-1219954Y597044D02*
Y607444D01*
G01Y605364D02*
X-1218979Y606404D01*
X-1218004Y607184D01*
X-1216639Y607444D01*
X-1215664Y607184D01*
X-1214494Y606404D01*
G01X-1202249Y604064D02*
X-1196009D01*
X-1196594Y605884D01*
X-1197569Y606924D01*
X-1198934Y607444D01*
X-1200299Y607184D01*
X-1201469Y606404D01*
X-1202249Y604584D01*
X-1202639Y603024D01*
Y601464D01*
X-1202249Y599904D01*
X-1201274Y598344D01*
X-1200104Y597304D01*
X-1198739Y597044D01*
X-1197374Y597564D01*
X-1196009Y599124D01*
G01X-1187274Y597044D02*
Y607444D01*
G01Y604584D02*
X-1186689Y605884D01*
X-1185714Y606924D01*
X-1184349Y607444D01*
X-1182984Y606924D01*
X-1182009Y605884D01*
X-1181424Y604584D01*
Y597044D01*
G01Y604584D02*
X-1180839Y605884D01*
X-1179864Y606924D01*
X-1178499Y607444D01*
X-1177134Y606924D01*
X-1176159Y605884D01*
X-1175574Y604324D01*
Y597044D01*
G01X-1166449Y604064D02*
X-1160209D01*
X-1160794Y605884D01*
X-1161769Y606924D01*
X-1163134Y607444D01*
X-1164499Y607184D01*
X-1165669Y606404D01*
X-1166449Y604584D01*
X-1166839Y603024D01*
Y601464D01*
X-1166449Y599904D01*
X-1165474Y598344D01*
X-1164304Y597304D01*
X-1162939Y597044D01*
X-1161574Y597564D01*
X-1160209Y599124D01*
G01X-1148939Y597044D02*
Y607444D01*
G01Y604844D02*
X-1148159Y606144D01*
X-1146989Y607184D01*
X-1145429Y607444D01*
X-1144064Y607184D01*
X-1142894Y606144D01*
X-1142309Y604324D01*
Y597044D01*
G01X-1127724Y612644D02*
Y597044D01*
G01X-1130454Y607444D02*
X-1124994D01*
G01X-1091924Y597044D02*
Y612644D01*
G01X-1076949Y604064D02*
X-1070709D01*
X-1071294Y605884D01*
X-1072269Y606924D01*
X-1073634Y607444D01*
X-1074999Y607184D01*
X-1076169Y606404D01*
X-1076949Y604584D01*
X-1077339Y603024D01*
Y601464D01*
X-1076949Y599904D01*
X-1075974Y598344D01*
X-1074804Y597304D01*
X-1073439Y597044D01*
X-1072074Y597564D01*
X-1070709Y599124D01*
G01X-1059049Y598864D02*
X-1058074Y597824D01*
X-1056709Y597044D01*
X-1055539D01*
X-1054369Y597564D01*
X-1053589Y598344D01*
X-1053199Y599384D01*
X-1053394Y600944D01*
X-1054174Y601724D01*
X-1057684Y603284D01*
X-1058464Y605104D01*
X-1058074Y606404D01*
X-1057294Y607184D01*
X-1056124Y607444D01*
X-1054954Y607184D01*
X-1053784Y606404D01*
G01X-1041149Y598864D02*
X-1040174Y597824D01*
X-1038809Y597044D01*
X-1037639D01*
X-1036469Y597564D01*
X-1035689Y598344D01*
X-1035299Y599384D01*
X-1035494Y600944D01*
X-1036274Y601724D01*
X-1039784Y603284D01*
X-1040564Y605104D01*
X-1040174Y606404D01*
X-1039394Y607184D01*
X-1038224Y607444D01*
X-1037054Y607184D01*
X-1035884Y606404D01*
G01X-1002424Y612644D02*
Y597044D01*
G01X-1005154Y607444D02*
X-999694D01*
G01X-987839Y597044D02*
Y612644D01*
G01Y605104D02*
X-986864Y606404D01*
X-985889Y607184D01*
X-984329Y607444D01*
X-983159Y607184D01*
X-981794Y606144D01*
X-981209Y604584D01*
Y597044D01*
G01X-963114D02*
Y607444D01*
G01Y605624D02*
X-963894Y606664D01*
X-965064Y607184D01*
X-966429Y607444D01*
X-967794Y606924D01*
X-968964Y605884D01*
X-969744Y604324D01*
X-970134Y602244D01*
X-969744Y600164D01*
X-968964Y598604D01*
X-967794Y597564D01*
X-966429Y597044D01*
X-965064Y597304D01*
X-963894Y598084D01*
X-963114Y599124D01*
G01X-952039Y597044D02*
Y607444D01*
G01Y604844D02*
X-951259Y606144D01*
X-950089Y607184D01*
X-948529Y607444D01*
X-947164Y607184D01*
X-945994Y606144D01*
X-945409Y604324D01*
Y597044D01*
G01X-912924Y612644D02*
X-914484Y612124D01*
X-915654Y610824D01*
X-916434Y609264D01*
X-917019Y607184D01*
X-917214Y604844D01*
X-917019Y602504D01*
X-916434Y600424D01*
X-915654Y598864D01*
X-914484Y597564D01*
X-912924Y597044D01*
X-911364Y597564D01*
X-910194Y598864D01*
X-909414Y600424D01*
X-908829Y602504D01*
X-908634Y604844D01*
X-908829Y607184D01*
X-909414Y609264D01*
X-910194Y610824D01*
X-911364Y612124D01*
X-912924Y612644D01*
G01X-895024Y596524D02*
X-895414Y596784D01*
Y597304D01*
X-895024Y597564D01*
X-894634Y597304D01*
Y596784D01*
X-895024Y596524D01*
G01X-877124Y612644D02*
X-878684Y612124D01*
X-879854Y610824D01*
X-880634Y609264D01*
X-881219Y607184D01*
X-881414Y604844D01*
X-881219Y602504D01*
X-880634Y600424D01*
X-879854Y598864D01*
X-878684Y597564D01*
X-877124Y597044D01*
X-875564Y597564D01*
X-874394Y598864D01*
X-873614Y600424D01*
X-873029Y602504D01*
X-872834Y604844D01*
X-873029Y607184D01*
X-873614Y609264D01*
X-874394Y610824D01*
X-875564Y612124D01*
X-877124Y612644D01*
G01X-859224D02*
X-860784Y612124D01*
X-861954Y610824D01*
X-862734Y609264D01*
X-863319Y607184D01*
X-863514Y604844D01*
X-863319Y602504D01*
X-862734Y600424D01*
X-861954Y598864D01*
X-860784Y597564D01*
X-859224Y597044D01*
X-857664Y597564D01*
X-856494Y598864D01*
X-855714Y600424D01*
X-855129Y602504D01*
X-854934Y604844D01*
X-855129Y607184D01*
X-855714Y609264D01*
X-856494Y610824D01*
X-857664Y612124D01*
X-859224Y612644D01*
G01X-841324D02*
X-842884Y612124D01*
X-844054Y610824D01*
X-844834Y609264D01*
X-845419Y607184D01*
X-845614Y604844D01*
X-845419Y602504D01*
X-844834Y600424D01*
X-844054Y598864D01*
X-842884Y597564D01*
X-841324Y597044D01*
X-839764Y597564D01*
X-838594Y598864D01*
X-837814Y600424D01*
X-837229Y602504D01*
X-837034Y604844D01*
X-837229Y607184D01*
X-837814Y609264D01*
X-838594Y610824D01*
X-839764Y612124D01*
X-841324Y612644D01*
G01X-823424Y597044D02*
X-822059Y597304D01*
X-820499Y598084D01*
X-819524Y599384D01*
X-819134Y601204D01*
X-819524Y603024D01*
X-820694Y604584D01*
X-822449Y605364D01*
X-824399D01*
X-825569Y605884D01*
X-826544Y607184D01*
X-826934Y609004D01*
X-826349Y610824D01*
X-824984Y612124D01*
X-823424Y612644D01*
X-821864Y612124D01*
X-820499Y610824D01*
X-819914Y609004D01*
X-820304Y607184D01*
X-821279Y605884D01*
X-822449Y605364D01*
X-824399D01*
X-826154Y604584D01*
X-827324Y603024D01*
X-827714Y601204D01*
X-827324Y599384D01*
X-826349Y598084D01*
X-824789Y597304D01*
X-823424Y597044D01*
G01X-807279Y609264D02*
X-806304Y612644D01*
G01X-803769D02*
X-804744Y609264D01*
G01X-787624Y596524D02*
X-788014Y596784D01*
Y597304D01*
X-787624Y597564D01*
X-787234Y597304D01*
Y596784D01*
X-787624Y596524D01*
G01X-2019214Y665044D02*
Y675444D01*
G01Y673624D02*
X-2019994Y674664D01*
X-2021164Y675184D01*
X-2022529Y675444D01*
X-2023894Y674924D01*
X-2025064Y673884D01*
X-2025844Y672324D01*
X-2026234Y670244D01*
X-2025844Y668164D01*
X-2025064Y666604D01*
X-2023894Y665564D01*
X-2022529Y665044D01*
X-2021164Y665304D01*
X-2019994Y666084D01*
X-2019214Y667124D01*
G01X-2009699Y675444D02*
X-2007359Y665044D01*
X-2004824Y675444D01*
X-2002289Y665044D01*
X-1999949Y675444D01*
G01X-1983414Y665044D02*
Y675444D01*
G01Y673624D02*
X-1984194Y674664D01*
X-1985364Y675184D01*
X-1986729Y675444D01*
X-1988094Y674924D01*
X-1989264Y673884D01*
X-1990044Y672324D01*
X-1990434Y670244D01*
X-1990044Y668164D01*
X-1989264Y666604D01*
X-1988094Y665564D01*
X-1986729Y665044D01*
X-1985364Y665304D01*
X-1984194Y666084D01*
X-1983414Y667124D01*
G01X-1973119Y660364D02*
X-1971949Y659844D01*
X-1970389Y660364D01*
X-1969414Y661404D01*
X-1968634Y662704D01*
X-1967464Y666864D01*
X-1964929Y675444D01*
G01X-1971169D02*
X-1967464Y666864D01*
G01X-1934394Y665044D02*
Y678304D01*
X-1934004Y679604D01*
X-1933224Y680384D01*
X-1932054Y680644D01*
X-1930884Y680124D01*
X-1930299Y678824D01*
G01X-1932639Y674404D02*
X-1936539D01*
G01X-1918054Y665044D02*
Y675444D01*
G01Y673364D02*
X-1917079Y674404D01*
X-1916104Y675184D01*
X-1914739Y675444D01*
X-1913764Y675184D01*
X-1912594Y674404D01*
G01X-1897424Y665044D02*
X-1898594Y665304D01*
X-1899764Y666344D01*
X-1900544Y668164D01*
X-1900934Y670244D01*
X-1900544Y672324D01*
X-1899764Y674144D01*
X-1898594Y675184D01*
X-1897424Y675444D01*
X-1896254Y675184D01*
X-1895084Y674144D01*
X-1894304Y672324D01*
X-1894109Y670244D01*
X-1894304Y668164D01*
X-1895084Y666344D01*
X-1896254Y665304D01*
X-1897424Y665044D01*
G01X-1885374D02*
Y675444D01*
G01Y672584D02*
X-1884789Y673884D01*
X-1883814Y674924D01*
X-1882449Y675444D01*
X-1881084Y674924D01*
X-1880109Y673884D01*
X-1879524Y672584D01*
Y665044D01*
G01Y672584D02*
X-1878939Y673884D01*
X-1877964Y674924D01*
X-1876599Y675444D01*
X-1875234Y674924D01*
X-1874259Y673884D01*
X-1873674Y672324D01*
Y665044D01*
G01X-1840214D02*
Y675444D01*
G01Y673624D02*
X-1840994Y674664D01*
X-1842164Y675184D01*
X-1843529Y675444D01*
X-1844894Y674924D01*
X-1846064Y673884D01*
X-1846844Y672324D01*
X-1847234Y670244D01*
X-1846844Y668164D01*
X-1846064Y666604D01*
X-1844894Y665564D01*
X-1843529Y665044D01*
X-1842164Y665304D01*
X-1840994Y666084D01*
X-1840214Y667124D01*
G01X-1829139Y665044D02*
Y675444D01*
G01Y672844D02*
X-1828359Y674144D01*
X-1827189Y675184D01*
X-1825629Y675444D01*
X-1824264Y675184D01*
X-1823094Y674144D01*
X-1822509Y672324D01*
Y665044D01*
G01X-1812019Y660364D02*
X-1810849Y659844D01*
X-1809289Y660364D01*
X-1808314Y661404D01*
X-1807534Y662704D01*
X-1806364Y666864D01*
X-1803829Y675444D01*
G01X-1810069D02*
X-1806364Y666864D01*
G01X-1768614Y680644D02*
Y665044D01*
G01Y667384D02*
X-1769394Y666084D01*
X-1770564Y665304D01*
X-1771929Y665044D01*
X-1773489Y665564D01*
X-1774659Y666864D01*
X-1775439Y668424D01*
X-1775634Y670244D01*
X-1775439Y672064D01*
X-1774659Y673624D01*
X-1773489Y674924D01*
X-1771929Y675444D01*
X-1770564Y675184D01*
X-1769589Y674664D01*
X-1768614Y673624D01*
G01X-1757149Y672064D02*
X-1750909D01*
X-1751494Y673884D01*
X-1752469Y674924D01*
X-1753834Y675444D01*
X-1755199Y675184D01*
X-1756369Y674404D01*
X-1757149Y672584D01*
X-1757539Y671024D01*
Y669464D01*
X-1757149Y667904D01*
X-1756174Y666344D01*
X-1755004Y665304D01*
X-1753639Y665044D01*
X-1752274Y665564D01*
X-1750909Y667124D01*
G01X-1739249Y666864D02*
X-1738274Y665824D01*
X-1736909Y665044D01*
X-1735739D01*
X-1734569Y665564D01*
X-1733789Y666344D01*
X-1733399Y667384D01*
X-1733594Y668944D01*
X-1734374Y669724D01*
X-1737884Y671284D01*
X-1738664Y673104D01*
X-1738274Y674404D01*
X-1737494Y675184D01*
X-1736324Y675444D01*
X-1735154Y675184D01*
X-1733984Y674404D01*
G01X-1718424Y675444D02*
Y665044D01*
G01Y679604D02*
X-1718814Y679864D01*
Y680384D01*
X-1718424Y680644D01*
X-1718034Y680384D01*
Y679864D01*
X-1718424Y679604D01*
G01X-1703254Y661144D02*
X-1701889Y660104D01*
X-1700329Y659844D01*
X-1698964Y660104D01*
X-1697794Y661404D01*
X-1697014Y663224D01*
Y675444D01*
G01Y673364D02*
X-1697794Y674404D01*
X-1698964Y675184D01*
X-1700329Y675444D01*
X-1701889Y674924D01*
X-1702864Y673884D01*
X-1703644Y672064D01*
X-1704034Y670244D01*
X-1703839Y668684D01*
X-1703059Y666864D01*
X-1701889Y665564D01*
X-1700329Y665044D01*
X-1699159Y665304D01*
X-1697794Y666344D01*
X-1697014Y667384D01*
G01X-1685939Y665044D02*
Y675444D01*
G01Y672844D02*
X-1685159Y674144D01*
X-1683989Y675184D01*
X-1682429Y675444D01*
X-1681064Y675184D01*
X-1679894Y674144D01*
X-1679309Y672324D01*
Y665044D01*
G01X-1667649Y672064D02*
X-1661409D01*
X-1661994Y673884D01*
X-1662969Y674924D01*
X-1664334Y675444D01*
X-1665699Y675184D01*
X-1666869Y674404D01*
X-1667649Y672584D01*
X-1668039Y671024D01*
Y669464D01*
X-1667649Y667904D01*
X-1666674Y666344D01*
X-1665504Y665304D01*
X-1664139Y665044D01*
X-1662774Y665564D01*
X-1661409Y667124D01*
G01X-1643314Y680644D02*
Y665044D01*
G01Y667384D02*
X-1644094Y666084D01*
X-1645264Y665304D01*
X-1646629Y665044D01*
X-1648189Y665564D01*
X-1649359Y666864D01*
X-1650139Y668424D01*
X-1650334Y670244D01*
X-1650139Y672064D01*
X-1649359Y673624D01*
X-1648189Y674924D01*
X-1646629Y675444D01*
X-1645264Y675184D01*
X-1644289Y674664D01*
X-1643314Y673624D01*
G01X-1612194Y665044D02*
Y678304D01*
X-1611804Y679604D01*
X-1611024Y680384D01*
X-1609854Y680644D01*
X-1608684Y680124D01*
X-1608099Y678824D01*
G01X-1610439Y674404D02*
X-1614339D01*
G01X-1596049Y672064D02*
X-1589809D01*
X-1590394Y673884D01*
X-1591369Y674924D01*
X-1592734Y675444D01*
X-1594099Y675184D01*
X-1595269Y674404D01*
X-1596049Y672584D01*
X-1596439Y671024D01*
Y669464D01*
X-1596049Y667904D01*
X-1595074Y666344D01*
X-1593904Y665304D01*
X-1592539Y665044D01*
X-1591174Y665564D01*
X-1589809Y667124D01*
G01X-1571714Y665044D02*
Y675444D01*
G01Y673624D02*
X-1572494Y674664D01*
X-1573664Y675184D01*
X-1575029Y675444D01*
X-1576394Y674924D01*
X-1577564Y673884D01*
X-1578344Y672324D01*
X-1578734Y670244D01*
X-1578344Y668164D01*
X-1577564Y666604D01*
X-1576394Y665564D01*
X-1575029Y665044D01*
X-1573664Y665304D01*
X-1572494Y666084D01*
X-1571714Y667124D01*
G01X-1557324Y680644D02*
Y665044D01*
G01X-1560054Y675444D02*
X-1554594D01*
G01X-1542739D02*
Y668164D01*
X-1541959Y666344D01*
X-1540789Y665304D01*
X-1539424Y665044D01*
X-1538059Y665304D01*
X-1536889Y666344D01*
X-1536109Y668164D01*
G01Y665044D02*
Y675444D01*
G01X-1524254Y665044D02*
Y675444D01*
G01Y673364D02*
X-1523279Y674404D01*
X-1522304Y675184D01*
X-1520939Y675444D01*
X-1519964Y675184D01*
X-1518794Y674404D01*
G01X-1506549Y672064D02*
X-1500309D01*
X-1500894Y673884D01*
X-1501869Y674924D01*
X-1503234Y675444D01*
X-1504599Y675184D01*
X-1505769Y674404D01*
X-1506549Y672584D01*
X-1506939Y671024D01*
Y669464D01*
X-1506549Y667904D01*
X-1505574Y666344D01*
X-1504404Y665304D01*
X-1503039Y665044D01*
X-1501674Y665564D01*
X-1500309Y667124D01*
G01X-1488649Y666864D02*
X-1487674Y665824D01*
X-1486309Y665044D01*
X-1485139D01*
X-1483969Y665564D01*
X-1483189Y666344D01*
X-1482799Y667384D01*
X-1482994Y668944D01*
X-1483774Y669724D01*
X-1487284Y671284D01*
X-1488064Y673104D01*
X-1487674Y674404D01*
X-1486894Y675184D01*
X-1485724Y675444D01*
X-1484554Y675184D01*
X-1483384Y674404D01*
G01X-1450899Y659844D02*
X-1452849Y662444D01*
X-1453824Y665044D01*
Y675444D01*
X-1452849Y678044D01*
X-1450899Y680644D01*
G01X-1432024Y675444D02*
Y665044D01*
G01Y679604D02*
X-1432414Y679864D01*
Y680384D01*
X-1432024Y680644D01*
X-1431634Y680384D01*
Y679864D01*
X-1432024Y679604D01*
G01X-1414124Y664524D02*
X-1414514Y664784D01*
Y665304D01*
X-1414124Y665564D01*
X-1413734Y665304D01*
Y664784D01*
X-1414124Y664524D01*
G01X-1399149Y672064D02*
X-1392909D01*
X-1393494Y673884D01*
X-1394469Y674924D01*
X-1395834Y675444D01*
X-1397199Y675184D01*
X-1398369Y674404D01*
X-1399149Y672584D01*
X-1399539Y671024D01*
Y669464D01*
X-1399149Y667904D01*
X-1398174Y666344D01*
X-1397004Y665304D01*
X-1395639Y665044D01*
X-1394274Y665564D01*
X-1392909Y667124D01*
G01X-1378324Y664524D02*
X-1378714Y664784D01*
Y665304D01*
X-1378324Y665564D01*
X-1377934Y665304D01*
Y664784D01*
X-1378324Y664524D01*
G01X-1346034Y675444D02*
X-1342524Y665044D01*
X-1339014Y675444D01*
G01X-1324624D02*
Y665044D01*
G01Y679604D02*
X-1325014Y679864D01*
Y680384D01*
X-1324624Y680644D01*
X-1324234Y680384D01*
Y679864D01*
X-1324624Y679604D01*
G01X-1303214Y665044D02*
Y675444D01*
G01Y673624D02*
X-1303994Y674664D01*
X-1305164Y675184D01*
X-1306529Y675444D01*
X-1307894Y674924D01*
X-1309064Y673884D01*
X-1309844Y672324D01*
X-1310234Y670244D01*
X-1309844Y668164D01*
X-1309064Y666604D01*
X-1307894Y665564D01*
X-1306529Y665044D01*
X-1305164Y665304D01*
X-1303994Y666084D01*
X-1303214Y667124D01*
G01X-1291749Y666864D02*
X-1290774Y665824D01*
X-1289409Y665044D01*
X-1288239D01*
X-1287069Y665564D01*
X-1286289Y666344D01*
X-1285899Y667384D01*
X-1286094Y668944D01*
X-1286874Y669724D01*
X-1290384Y671284D01*
X-1291164Y673104D01*
X-1290774Y674404D01*
X-1289994Y675184D01*
X-1288824Y675444D01*
X-1287654Y675184D01*
X-1286484Y674404D01*
G01X-1271314Y662184D02*
X-1270534Y665564D01*
G01X-1238634Y659844D02*
Y675444D01*
G01Y673104D02*
X-1237659Y674404D01*
X-1236684Y675184D01*
X-1235124Y675444D01*
X-1233759Y675184D01*
X-1232394Y673884D01*
X-1231809Y672064D01*
X-1231614Y670244D01*
X-1231809Y668424D01*
X-1232394Y666604D01*
X-1233564Y665564D01*
X-1235124Y665044D01*
X-1236489Y665304D01*
X-1237854Y666084D01*
X-1238634Y667124D01*
G01X-1213714Y665044D02*
Y675444D01*
G01Y673624D02*
X-1214494Y674664D01*
X-1215664Y675184D01*
X-1217029Y675444D01*
X-1218394Y674924D01*
X-1219564Y673884D01*
X-1220344Y672324D01*
X-1220734Y670244D01*
X-1220344Y668164D01*
X-1219564Y666604D01*
X-1218394Y665564D01*
X-1217029Y665044D01*
X-1215664Y665304D01*
X-1214494Y666084D01*
X-1213714Y667124D01*
G01X-1195814Y680644D02*
Y665044D01*
G01Y667384D02*
X-1196594Y666084D01*
X-1197764Y665304D01*
X-1199129Y665044D01*
X-1200689Y665564D01*
X-1201859Y666864D01*
X-1202639Y668424D01*
X-1202834Y670244D01*
X-1202639Y672064D01*
X-1201859Y673624D01*
X-1200689Y674924D01*
X-1199129Y675444D01*
X-1197764Y675184D01*
X-1196789Y674664D01*
X-1195814Y673624D01*
G01X-1184349Y666864D02*
X-1183374Y665824D01*
X-1182009Y665044D01*
X-1180839D01*
X-1179669Y665564D01*
X-1178889Y666344D01*
X-1178499Y667384D01*
X-1178694Y668944D01*
X-1179474Y669724D01*
X-1182984Y671284D01*
X-1183764Y673104D01*
X-1183374Y674404D01*
X-1182594Y675184D01*
X-1181424Y675444D01*
X-1180254Y675184D01*
X-1179084Y674404D01*
G01X-1163914Y662184D02*
X-1163134Y665564D01*
G01X-1127724Y680644D02*
Y665044D01*
G01X-1130454Y675444D02*
X-1124994D01*
G01X-1112554Y665044D02*
Y675444D01*
G01Y673364D02*
X-1111579Y674404D01*
X-1110604Y675184D01*
X-1109239Y675444D01*
X-1108264Y675184D01*
X-1107094Y674404D01*
G01X-1088414Y665044D02*
Y675444D01*
G01Y673624D02*
X-1089194Y674664D01*
X-1090364Y675184D01*
X-1091729Y675444D01*
X-1093094Y674924D01*
X-1094264Y673884D01*
X-1095044Y672324D01*
X-1095434Y670244D01*
X-1095044Y668164D01*
X-1094264Y666604D01*
X-1093094Y665564D01*
X-1091729Y665044D01*
X-1090364Y665304D01*
X-1089194Y666084D01*
X-1088414Y667124D01*
G01X-1070904Y674144D02*
X-1072269Y675184D01*
X-1073439Y675444D01*
X-1074999Y674924D01*
X-1076169Y673884D01*
X-1076949Y672064D01*
X-1077144Y670244D01*
X-1076949Y668424D01*
X-1076169Y666864D01*
X-1074999Y665564D01*
X-1073439Y665044D01*
X-1072074Y665564D01*
X-1070904Y666604D01*
G01X-1059049Y672064D02*
X-1052809D01*
X-1053394Y673884D01*
X-1054369Y674924D01*
X-1055734Y675444D01*
X-1057099Y675184D01*
X-1058269Y674404D01*
X-1059049Y672584D01*
X-1059439Y671024D01*
Y669464D01*
X-1059049Y667904D01*
X-1058074Y666344D01*
X-1056904Y665304D01*
X-1055539Y665044D01*
X-1054174Y665564D01*
X-1052809Y667124D01*
G01X-1041149Y666864D02*
X-1040174Y665824D01*
X-1038809Y665044D01*
X-1037639D01*
X-1036469Y665564D01*
X-1035689Y666344D01*
X-1035299Y667384D01*
X-1035494Y668944D01*
X-1036274Y669724D01*
X-1039784Y671284D01*
X-1040564Y673104D01*
X-1040174Y674404D01*
X-1039394Y675184D01*
X-1038224Y675444D01*
X-1037054Y675184D01*
X-1035884Y674404D01*
G01X-1020714Y662184D02*
X-1019934Y665564D01*
G01X-987449Y672064D02*
X-981209D01*
X-981794Y673884D01*
X-982769Y674924D01*
X-984134Y675444D01*
X-985499Y675184D01*
X-986669Y674404D01*
X-987449Y672584D01*
X-987839Y671024D01*
Y669464D01*
X-987449Y667904D01*
X-986474Y666344D01*
X-985304Y665304D01*
X-983939Y665044D01*
X-982574Y665564D01*
X-981209Y667124D01*
G01X-966624Y680644D02*
Y665044D01*
G01X-969354Y675444D02*
X-963894D01*
G01X-945604Y674144D02*
X-946969Y675184D01*
X-948139Y675444D01*
X-949699Y674924D01*
X-950869Y673884D01*
X-951649Y672064D01*
X-951844Y670244D01*
X-951649Y668424D01*
X-950869Y666864D01*
X-949699Y665564D01*
X-948139Y665044D01*
X-946774Y665564D01*
X-945604Y666604D01*
G01X-930824Y664524D02*
X-931214Y664784D01*
Y665304D01*
X-930824Y665564D01*
X-930434Y665304D01*
Y664784D01*
X-930824Y664524D01*
G01X-911949Y659844D02*
X-909999Y662444D01*
X-909024Y665044D01*
Y675444D01*
X-909999Y678044D01*
X-911949Y680644D01*
G01X-895024Y664524D02*
X-895414Y664784D01*
Y665304D01*
X-895024Y665564D01*
X-894634Y665304D01*
Y664784D01*
X-895024Y664524D01*
G01X-2026819Y735124D02*
X-2025259Y733824D01*
X-2023504Y733044D01*
X-2021944D01*
X-2020384Y733824D01*
X-2019214Y735124D01*
X-2018629Y736944D01*
X-2019019Y738764D01*
X-2019994Y740324D01*
X-2021749Y741364D01*
X-2024089Y741884D01*
X-2025454Y742924D01*
X-2026039Y744744D01*
X-2025649Y746564D01*
X-2024674Y747864D01*
X-2023309Y748644D01*
X-2021944D01*
X-2020579Y748124D01*
X-2019409Y746824D01*
G01X-2008139Y743444D02*
Y736164D01*
X-2007359Y734344D01*
X-2006189Y733304D01*
X-2004824Y733044D01*
X-2003459Y733304D01*
X-2002289Y734344D01*
X-2001509Y736164D01*
G01Y733044D02*
Y743444D01*
G01X-1990434Y733044D02*
Y748644D01*
G01Y740844D02*
X-1989459Y742404D01*
X-1988289Y743184D01*
X-1987119Y743444D01*
X-1985364Y742924D01*
X-1984194Y741884D01*
X-1983414Y740064D01*
Y737984D01*
X-1983804Y735904D01*
X-1984584Y734344D01*
X-1985949Y733304D01*
X-1987119Y733044D01*
X-1988289Y733304D01*
X-1989459Y734084D01*
X-1990434Y735384D01*
G01X-1971949Y734864D02*
X-1970974Y733824D01*
X-1969609Y733044D01*
X-1968439D01*
X-1967269Y733564D01*
X-1966489Y734344D01*
X-1966099Y735384D01*
X-1966294Y736944D01*
X-1967074Y737724D01*
X-1970584Y739284D01*
X-1971364Y741104D01*
X-1970974Y742404D01*
X-1970194Y743184D01*
X-1969024Y743444D01*
X-1967854Y743184D01*
X-1966684Y742404D01*
G01X-1951124Y748644D02*
Y733044D01*
G01X-1953854Y743444D02*
X-1948394D01*
G01X-1929714Y733044D02*
Y743444D01*
G01Y741624D02*
X-1930494Y742664D01*
X-1931664Y743184D01*
X-1933029Y743444D01*
X-1934394Y742924D01*
X-1935564Y741884D01*
X-1936344Y740324D01*
X-1936734Y738244D01*
X-1936344Y736164D01*
X-1935564Y734604D01*
X-1934394Y733564D01*
X-1933029Y733044D01*
X-1931664Y733304D01*
X-1930494Y734084D01*
X-1929714Y735124D01*
G01X-1918639Y733044D02*
Y743444D01*
G01Y740844D02*
X-1917859Y742144D01*
X-1916689Y743184D01*
X-1915129Y743444D01*
X-1913764Y743184D01*
X-1912594Y742144D01*
X-1912009Y740324D01*
Y733044D01*
G01X-1894304Y742144D02*
X-1895669Y743184D01*
X-1896839Y743444D01*
X-1898399Y742924D01*
X-1899569Y741884D01*
X-1900349Y740064D01*
X-1900544Y738244D01*
X-1900349Y736424D01*
X-1899569Y734864D01*
X-1898399Y733564D01*
X-1896839Y733044D01*
X-1895474Y733564D01*
X-1894304Y734604D01*
G01X-1882449Y740064D02*
X-1876209D01*
X-1876794Y741884D01*
X-1877769Y742924D01*
X-1879134Y743444D01*
X-1880499Y743184D01*
X-1881669Y742404D01*
X-1882449Y740584D01*
X-1882839Y739024D01*
Y737464D01*
X-1882449Y735904D01*
X-1881474Y734344D01*
X-1880304Y733304D01*
X-1878939Y733044D01*
X-1877574Y733564D01*
X-1876209Y735124D01*
G01X-1864549Y734864D02*
X-1863574Y733824D01*
X-1862209Y733044D01*
X-1861039D01*
X-1859869Y733564D01*
X-1859089Y734344D01*
X-1858699Y735384D01*
X-1858894Y736944D01*
X-1859674Y737724D01*
X-1863184Y739284D01*
X-1863964Y741104D01*
X-1863574Y742404D01*
X-1862794Y743184D01*
X-1861624Y743444D01*
X-1860454Y743184D01*
X-1859284Y742404D01*
G01X-1826799Y727844D02*
X-1828749Y730444D01*
X-1829724Y733044D01*
Y743444D01*
X-1828749Y746044D01*
X-1826799Y748644D01*
G01X-1811824Y733044D02*
Y748644D01*
X-1806949D01*
X-1805389Y747864D01*
X-1804414Y746824D01*
X-1804024Y744744D01*
X-1804414Y742664D01*
X-1805584Y741364D01*
X-1806949Y740584D01*
X-1811824D01*
G01X-1806949D02*
X-1804024Y733044D01*
G01X-1790024D02*
X-1791194Y733304D01*
X-1792364Y734344D01*
X-1793144Y736164D01*
X-1793534Y738244D01*
X-1793144Y740324D01*
X-1792364Y742144D01*
X-1791194Y743184D01*
X-1790024Y743444D01*
X-1788854Y743184D01*
X-1787684Y742144D01*
X-1786904Y740324D01*
X-1786709Y738244D01*
X-1786904Y736164D01*
X-1787684Y734344D01*
X-1788854Y733304D01*
X-1790024Y733044D01*
G01X-1776219D02*
Y748644D01*
G01X-1768029D02*
Y733044D01*
G01Y740844D02*
X-1776219D01*
G01X-1758319Y735124D02*
X-1756759Y733824D01*
X-1755004Y733044D01*
X-1753444D01*
X-1751884Y733824D01*
X-1750714Y735124D01*
X-1750129Y736944D01*
X-1750519Y738764D01*
X-1751494Y740324D01*
X-1753249Y741364D01*
X-1755589Y741884D01*
X-1756954Y742924D01*
X-1757539Y744744D01*
X-1757149Y746564D01*
X-1756174Y747864D01*
X-1754809Y748644D01*
X-1753444D01*
X-1752079Y748124D01*
X-1750909Y746824D01*
G01X-1735349Y727844D02*
X-1733399Y730444D01*
X-1732424Y733044D01*
Y743444D01*
X-1733399Y746044D01*
X-1735349Y748644D01*
G01X-1704814Y733044D02*
Y748644D01*
X-1700914D01*
X-1699354Y747864D01*
X-1698184Y746824D01*
X-1697209Y745264D01*
X-1696429Y743444D01*
X-1696234Y740844D01*
X-1696429Y738244D01*
X-1697209Y736424D01*
X-1698184Y734864D01*
X-1699354Y733824D01*
X-1700914Y733044D01*
X-1704814D01*
G01X-1682624Y743444D02*
Y733044D01*
G01Y747604D02*
X-1683014Y747864D01*
Y748384D01*
X-1682624Y748644D01*
X-1682234Y748384D01*
Y747864D01*
X-1682624Y747604D01*
G01X-1667454Y733044D02*
Y743444D01*
G01Y741364D02*
X-1666479Y742404D01*
X-1665504Y743184D01*
X-1664139Y743444D01*
X-1663164Y743184D01*
X-1661994Y742404D01*
G01X-1649749Y740064D02*
X-1643509D01*
X-1644094Y741884D01*
X-1645069Y742924D01*
X-1646434Y743444D01*
X-1647799Y743184D01*
X-1648969Y742404D01*
X-1649749Y740584D01*
X-1650139Y739024D01*
Y737464D01*
X-1649749Y735904D01*
X-1648774Y734344D01*
X-1647604Y733304D01*
X-1646239Y733044D01*
X-1644874Y733564D01*
X-1643509Y735124D01*
G01X-1625804Y742144D02*
X-1627169Y743184D01*
X-1628339Y743444D01*
X-1629899Y742924D01*
X-1631069Y741884D01*
X-1631849Y740064D01*
X-1632044Y738244D01*
X-1631849Y736424D01*
X-1631069Y734864D01*
X-1629899Y733564D01*
X-1628339Y733044D01*
X-1626974Y733564D01*
X-1625804Y734604D01*
G01X-1611024Y748644D02*
Y733044D01*
G01X-1613754Y743444D02*
X-1608294D01*
G01X-1593124D02*
Y733044D01*
G01Y747604D02*
X-1593514Y747864D01*
Y748384D01*
X-1593124Y748644D01*
X-1592734Y748384D01*
Y747864D01*
X-1593124Y747604D01*
G01X-1578734Y743444D02*
X-1575224Y733044D01*
X-1571714Y743444D01*
G01X-1560249Y740064D02*
X-1554009D01*
X-1554594Y741884D01*
X-1555569Y742924D01*
X-1556934Y743444D01*
X-1558299Y743184D01*
X-1559469Y742404D01*
X-1560249Y740584D01*
X-1560639Y739024D01*
Y737464D01*
X-1560249Y735904D01*
X-1559274Y734344D01*
X-1558104Y733304D01*
X-1556739Y733044D01*
X-1555374Y733564D01*
X-1554009Y735124D01*
G01X-1518014Y733044D02*
Y743444D01*
G01Y741624D02*
X-1518794Y742664D01*
X-1519964Y743184D01*
X-1521329Y743444D01*
X-1522694Y742924D01*
X-1523864Y741884D01*
X-1524644Y740324D01*
X-1525034Y738244D01*
X-1524644Y736164D01*
X-1523864Y734604D01*
X-1522694Y733564D01*
X-1521329Y733044D01*
X-1519964Y733304D01*
X-1518794Y734084D01*
X-1518014Y735124D01*
G01X-1506939Y733044D02*
Y743444D01*
G01Y740844D02*
X-1506159Y742144D01*
X-1504989Y743184D01*
X-1503429Y743444D01*
X-1502064Y743184D01*
X-1500894Y742144D01*
X-1500309Y740324D01*
Y733044D01*
G01X-1482214Y748644D02*
Y733044D01*
G01Y735384D02*
X-1482994Y734084D01*
X-1484164Y733304D01*
X-1485529Y733044D01*
X-1487089Y733564D01*
X-1488259Y734864D01*
X-1489039Y736424D01*
X-1489234Y738244D01*
X-1489039Y740064D01*
X-1488259Y741624D01*
X-1487089Y742924D01*
X-1485529Y743444D01*
X-1484164Y743184D01*
X-1483189Y742664D01*
X-1482214Y741624D01*
G01X-1446804Y742144D02*
X-1448169Y743184D01*
X-1449339Y743444D01*
X-1450899Y742924D01*
X-1452069Y741884D01*
X-1452849Y740064D01*
X-1453044Y738244D01*
X-1452849Y736424D01*
X-1452069Y734864D01*
X-1450899Y733564D01*
X-1449339Y733044D01*
X-1447974Y733564D01*
X-1446804Y734604D01*
G01X-1432024Y733044D02*
X-1433194Y733304D01*
X-1434364Y734344D01*
X-1435144Y736164D01*
X-1435534Y738244D01*
X-1435144Y740324D01*
X-1434364Y742144D01*
X-1433194Y743184D01*
X-1432024Y743444D01*
X-1430854Y743184D01*
X-1429684Y742144D01*
X-1428904Y740324D01*
X-1428709Y738244D01*
X-1428904Y736164D01*
X-1429684Y734344D01*
X-1430854Y733304D01*
X-1432024Y733044D01*
G01X-1419974D02*
Y743444D01*
G01Y740584D02*
X-1419389Y741884D01*
X-1418414Y742924D01*
X-1417049Y743444D01*
X-1415684Y742924D01*
X-1414709Y741884D01*
X-1414124Y740584D01*
Y733044D01*
G01Y740584D02*
X-1413539Y741884D01*
X-1412564Y742924D01*
X-1411199Y743444D01*
X-1409834Y742924D01*
X-1408859Y741884D01*
X-1408274Y740324D01*
Y733044D01*
G01X-1399734Y727844D02*
Y743444D01*
G01Y741104D02*
X-1398759Y742404D01*
X-1397784Y743184D01*
X-1396224Y743444D01*
X-1394859Y743184D01*
X-1393494Y741884D01*
X-1392909Y740064D01*
X-1392714Y738244D01*
X-1392909Y736424D01*
X-1393494Y734604D01*
X-1394664Y733564D01*
X-1396224Y733044D01*
X-1397589Y733304D01*
X-1398954Y734084D01*
X-1399734Y735124D01*
G01X-1374814Y733044D02*
Y743444D01*
G01Y741624D02*
X-1375594Y742664D01*
X-1376764Y743184D01*
X-1378129Y743444D01*
X-1379494Y742924D01*
X-1380664Y741884D01*
X-1381444Y740324D01*
X-1381834Y738244D01*
X-1381444Y736164D01*
X-1380664Y734604D01*
X-1379494Y733564D01*
X-1378129Y733044D01*
X-1376764Y733304D01*
X-1375594Y734084D01*
X-1374814Y735124D01*
G01X-1360424Y748644D02*
Y733044D01*
G01X-1363154Y743444D02*
X-1357694D01*
G01X-1342524D02*
Y733044D01*
G01Y747604D02*
X-1342914Y747864D01*
Y748384D01*
X-1342524Y748644D01*
X-1342134Y748384D01*
Y747864D01*
X-1342524Y747604D01*
G01X-1328134Y733044D02*
Y748644D01*
G01Y740844D02*
X-1327159Y742404D01*
X-1325989Y743184D01*
X-1324819Y743444D01*
X-1323064Y742924D01*
X-1321894Y741884D01*
X-1321114Y740064D01*
Y737984D01*
X-1321504Y735904D01*
X-1322284Y734344D01*
X-1323649Y733304D01*
X-1324819Y733044D01*
X-1325989Y733304D01*
X-1327159Y734084D01*
X-1328134Y735384D01*
G01X-1306724Y733044D02*
Y748644D01*
G01X-1291749Y740064D02*
X-1285509D01*
X-1286094Y741884D01*
X-1287069Y742924D01*
X-1288434Y743444D01*
X-1289799Y743184D01*
X-1290969Y742404D01*
X-1291749Y740584D01*
X-1292139Y739024D01*
Y737464D01*
X-1291749Y735904D01*
X-1290774Y734344D01*
X-1289604Y733304D01*
X-1288239Y733044D01*
X-1286874Y733564D01*
X-1285509Y735124D01*
G01X-1257899Y743444D02*
X-1255559Y733044D01*
X-1253024Y743444D01*
X-1250489Y733044D01*
X-1248149Y743444D01*
G01X-1235124D02*
Y733044D01*
G01Y747604D02*
X-1235514Y747864D01*
Y748384D01*
X-1235124Y748644D01*
X-1234734Y748384D01*
Y747864D01*
X-1235124Y747604D01*
G01X-1217224Y748644D02*
Y733044D01*
G01X-1219954Y743444D02*
X-1214494D01*
G01X-1202639Y733044D02*
Y748644D01*
G01Y741104D02*
X-1201664Y742404D01*
X-1200689Y743184D01*
X-1199129Y743444D01*
X-1197959Y743184D01*
X-1196594Y742144D01*
X-1196009Y740584D01*
Y733044D01*
G01X-1167424D02*
Y748644D01*
X-1162744D01*
X-1161184Y747864D01*
X-1160014Y746044D01*
X-1159624Y743964D01*
X-1160014Y741884D01*
X-1160989Y740324D01*
X-1162744Y739544D01*
X-1167424D01*
G01X-1149134Y733044D02*
Y748644D01*
G01Y740844D02*
X-1148159Y742404D01*
X-1146989Y743184D01*
X-1145819Y743444D01*
X-1144064Y742924D01*
X-1142894Y741884D01*
X-1142114Y740064D01*
Y737984D01*
X-1142504Y735904D01*
X-1143284Y734344D01*
X-1144649Y733304D01*
X-1145819Y733044D01*
X-1146989Y733304D01*
X-1148159Y734084D01*
X-1149134Y735384D01*
G01X-1113529Y733044D02*
Y748644D01*
X-1106119D01*
G01X-1108849Y741104D02*
X-1113529D01*
G01X-1094654Y733044D02*
Y743444D01*
G01Y741364D02*
X-1093679Y742404D01*
X-1092704Y743184D01*
X-1091339Y743444D01*
X-1090364Y743184D01*
X-1089194Y742404D01*
G01X-1076949Y740064D02*
X-1070709D01*
X-1071294Y741884D01*
X-1072269Y742924D01*
X-1073634Y743444D01*
X-1074999Y743184D01*
X-1076169Y742404D01*
X-1076949Y740584D01*
X-1077339Y739024D01*
Y737464D01*
X-1076949Y735904D01*
X-1075974Y734344D01*
X-1074804Y733304D01*
X-1073439Y733044D01*
X-1072074Y733564D01*
X-1070709Y735124D01*
G01X-1059049Y740064D02*
X-1052809D01*
X-1053394Y741884D01*
X-1054369Y742924D01*
X-1055734Y743444D01*
X-1057099Y743184D01*
X-1058269Y742404D01*
X-1059049Y740584D01*
X-1059439Y739024D01*
Y737464D01*
X-1059049Y735904D01*
X-1058074Y734344D01*
X-1056904Y733304D01*
X-1055539Y733044D01*
X-1054174Y733564D01*
X-1052809Y735124D01*
G01X-1016814Y733044D02*
Y743444D01*
G01Y741624D02*
X-1017594Y742664D01*
X-1018764Y743184D01*
X-1020129Y743444D01*
X-1021494Y742924D01*
X-1022664Y741884D01*
X-1023444Y740324D01*
X-1023834Y738244D01*
X-1023444Y736164D01*
X-1022664Y734604D01*
X-1021494Y733564D01*
X-1020129Y733044D01*
X-1018764Y733304D01*
X-1017594Y734084D01*
X-1016814Y735124D01*
G01X-1005349Y734864D02*
X-1004374Y733824D01*
X-1003009Y733044D01*
X-1001839D01*
X-1000669Y733564D01*
X-999889Y734344D01*
X-999499Y735384D01*
X-999694Y736944D01*
X-1000474Y737724D01*
X-1003984Y739284D01*
X-1004764Y741104D01*
X-1004374Y742404D01*
X-1003594Y743184D01*
X-1002424Y743444D01*
X-1001254Y743184D01*
X-1000084Y742404D01*
G01X-987449Y734864D02*
X-986474Y733824D01*
X-985109Y733044D01*
X-983939D01*
X-982769Y733564D01*
X-981989Y734344D01*
X-981599Y735384D01*
X-981794Y736944D01*
X-982574Y737724D01*
X-986084Y739284D01*
X-986864Y741104D01*
X-986474Y742404D01*
X-985694Y743184D01*
X-984524Y743444D01*
X-983354Y743184D01*
X-982184Y742404D01*
G01X-969549Y740064D02*
X-963309D01*
X-963894Y741884D01*
X-964869Y742924D01*
X-966234Y743444D01*
X-967599Y743184D01*
X-968769Y742404D01*
X-969549Y740584D01*
X-969939Y739024D01*
Y737464D01*
X-969549Y735904D01*
X-968574Y734344D01*
X-967404Y733304D01*
X-966039Y733044D01*
X-964674Y733564D01*
X-963309Y735124D01*
G01X-954574Y733044D02*
Y743444D01*
G01Y740584D02*
X-953989Y741884D01*
X-953014Y742924D01*
X-951649Y743444D01*
X-950284Y742924D01*
X-949309Y741884D01*
X-948724Y740584D01*
Y733044D01*
G01Y740584D02*
X-948139Y741884D01*
X-947164Y742924D01*
X-945799Y743444D01*
X-944434Y742924D01*
X-943459Y741884D01*
X-942874Y740324D01*
Y733044D01*
G01X-934334D02*
Y748644D01*
G01Y740844D02*
X-933359Y742404D01*
X-932189Y743184D01*
X-931019Y743444D01*
X-929264Y742924D01*
X-928094Y741884D01*
X-927314Y740064D01*
Y737984D01*
X-927704Y735904D01*
X-928484Y734344D01*
X-929849Y733304D01*
X-931019Y733044D01*
X-932189Y733304D01*
X-933359Y734084D01*
X-934334Y735384D01*
G01X-912924Y733044D02*
Y748644D01*
G01X-899119Y728364D02*
X-897949Y727844D01*
X-896389Y728364D01*
X-895414Y729404D01*
X-894634Y730704D01*
X-893464Y734864D01*
X-890929Y743444D01*
G01X-897169D02*
X-893464Y734864D01*
G01X-862734Y727844D02*
Y743444D01*
G01Y741104D02*
X-861759Y742404D01*
X-860784Y743184D01*
X-859224Y743444D01*
X-857859Y743184D01*
X-856494Y741884D01*
X-855909Y740064D01*
X-855714Y738244D01*
X-855909Y736424D01*
X-856494Y734604D01*
X-857664Y733564D01*
X-859224Y733044D01*
X-860589Y733304D01*
X-861954Y734084D01*
X-862734Y735124D01*
G01X-844054Y733044D02*
Y743444D01*
G01Y741364D02*
X-843079Y742404D01*
X-842104Y743184D01*
X-840739Y743444D01*
X-839764Y743184D01*
X-838594Y742404D01*
G01X-823424Y733044D02*
X-824594Y733304D01*
X-825764Y734344D01*
X-826544Y736164D01*
X-826934Y738244D01*
X-826544Y740324D01*
X-825764Y742144D01*
X-824594Y743184D01*
X-823424Y743444D01*
X-822254Y743184D01*
X-821084Y742144D01*
X-820304Y740324D01*
X-820109Y738244D01*
X-820304Y736164D01*
X-821084Y734344D01*
X-822254Y733304D01*
X-823424Y733044D01*
G01X-802404Y742144D02*
X-803769Y743184D01*
X-804939Y743444D01*
X-806499Y742924D01*
X-807669Y741884D01*
X-808449Y740064D01*
X-808644Y738244D01*
X-808449Y736424D01*
X-807669Y734864D01*
X-806499Y733564D01*
X-804939Y733044D01*
X-803574Y733564D01*
X-802404Y734604D01*
G01X-790549Y740064D02*
X-784309D01*
X-784894Y741884D01*
X-785869Y742924D01*
X-787234Y743444D01*
X-788599Y743184D01*
X-789769Y742404D01*
X-790549Y740584D01*
X-790939Y739024D01*
Y737464D01*
X-790549Y735904D01*
X-789574Y734344D01*
X-788404Y733304D01*
X-787039Y733044D01*
X-785674Y733564D01*
X-784309Y735124D01*
G01X-772649Y734864D02*
X-771674Y733824D01*
X-770309Y733044D01*
X-769139D01*
X-767969Y733564D01*
X-767189Y734344D01*
X-766799Y735384D01*
X-766994Y736944D01*
X-767774Y737724D01*
X-771284Y739284D01*
X-772064Y741104D01*
X-771674Y742404D01*
X-770894Y743184D01*
X-769724Y743444D01*
X-768554Y743184D01*
X-767384Y742404D01*
G01X-754749Y734864D02*
X-753774Y733824D01*
X-752409Y733044D01*
X-751239D01*
X-750069Y733564D01*
X-749289Y734344D01*
X-748899Y735384D01*
X-749094Y736944D01*
X-749874Y737724D01*
X-753384Y739284D01*
X-754164Y741104D01*
X-753774Y742404D01*
X-752994Y743184D01*
X-751824Y743444D01*
X-750654Y743184D01*
X-749484Y742404D01*
G01X-733924Y732524D02*
X-734314Y732784D01*
Y733304D01*
X-733924Y733564D01*
X-733534Y733304D01*
Y732784D01*
X-733924Y732524D01*
G01X-2022724Y816644D02*
Y801044D01*
G01X-2025454Y811444D02*
X-2019994D01*
G01X-2008139Y801044D02*
Y816644D01*
G01Y809104D02*
X-2007164Y810404D01*
X-2006189Y811184D01*
X-2004629Y811444D01*
X-2003459Y811184D01*
X-2002094Y810144D01*
X-2001509Y808584D01*
Y801044D01*
G01X-1983414D02*
Y811444D01*
G01Y809624D02*
X-1984194Y810664D01*
X-1985364Y811184D01*
X-1986729Y811444D01*
X-1988094Y810924D01*
X-1989264Y809884D01*
X-1990044Y808324D01*
X-1990434Y806244D01*
X-1990044Y804164D01*
X-1989264Y802604D01*
X-1988094Y801564D01*
X-1986729Y801044D01*
X-1985364Y801304D01*
X-1984194Y802084D01*
X-1983414Y803124D01*
G01X-1972339Y801044D02*
Y811444D01*
G01Y808844D02*
X-1971559Y810144D01*
X-1970389Y811184D01*
X-1968829Y811444D01*
X-1967464Y811184D01*
X-1966294Y810144D01*
X-1965709Y808324D01*
Y801044D01*
G01X-1933224Y816644D02*
Y801044D01*
G01X-1935954Y811444D02*
X-1930494D01*
G01X-1918639Y801044D02*
Y816644D01*
G01Y809104D02*
X-1917664Y810404D01*
X-1916689Y811184D01*
X-1915129Y811444D01*
X-1913959Y811184D01*
X-1912594Y810144D01*
X-1912009Y808584D01*
Y801044D01*
G01X-1900349Y808064D02*
X-1894109D01*
X-1894694Y809884D01*
X-1895669Y810924D01*
X-1897034Y811444D01*
X-1898399Y811184D01*
X-1899569Y810404D01*
X-1900349Y808584D01*
X-1900739Y807024D01*
Y805464D01*
X-1900349Y803904D01*
X-1899374Y802344D01*
X-1898204Y801304D01*
X-1896839Y801044D01*
X-1895474Y801564D01*
X-1894109Y803124D01*
G01X-1864549Y802864D02*
X-1863574Y801824D01*
X-1862209Y801044D01*
X-1861039D01*
X-1859869Y801564D01*
X-1859089Y802344D01*
X-1858699Y803384D01*
X-1858894Y804944D01*
X-1859674Y805724D01*
X-1863184Y807284D01*
X-1863964Y809104D01*
X-1863574Y810404D01*
X-1862794Y811184D01*
X-1861624Y811444D01*
X-1860454Y811184D01*
X-1859284Y810404D01*
G01X-1849574Y801044D02*
Y811444D01*
G01Y808584D02*
X-1848989Y809884D01*
X-1848014Y810924D01*
X-1846649Y811444D01*
X-1845284Y810924D01*
X-1844309Y809884D01*
X-1843724Y808584D01*
Y801044D01*
G01Y808584D02*
X-1843139Y809884D01*
X-1842164Y810924D01*
X-1840799Y811444D01*
X-1839434Y810924D01*
X-1838459Y809884D01*
X-1837874Y808324D01*
Y801044D01*
G01X-1822314D02*
Y811444D01*
G01Y809624D02*
X-1823094Y810664D01*
X-1824264Y811184D01*
X-1825629Y811444D01*
X-1826994Y810924D01*
X-1828164Y809884D01*
X-1828944Y808324D01*
X-1829334Y806244D01*
X-1828944Y804164D01*
X-1828164Y802604D01*
X-1826994Y801564D01*
X-1825629Y801044D01*
X-1824264Y801304D01*
X-1823094Y802084D01*
X-1822314Y803124D01*
G01X-1807924Y801044D02*
Y816644D01*
G01X-1790024Y801044D02*
Y816644D01*
G01X-1775049Y808064D02*
X-1768809D01*
X-1769394Y809884D01*
X-1770369Y810924D01*
X-1771734Y811444D01*
X-1773099Y811184D01*
X-1774269Y810404D01*
X-1775049Y808584D01*
X-1775439Y807024D01*
Y805464D01*
X-1775049Y803904D01*
X-1774074Y802344D01*
X-1772904Y801304D01*
X-1771539Y801044D01*
X-1770174Y801564D01*
X-1768809Y803124D01*
G01X-1756954Y801044D02*
Y811444D01*
G01Y809364D02*
X-1755979Y810404D01*
X-1755004Y811184D01*
X-1753639Y811444D01*
X-1752664Y811184D01*
X-1751494Y810404D01*
G01X-1718424Y801044D02*
X-1719594Y801304D01*
X-1720764Y802344D01*
X-1721544Y804164D01*
X-1721934Y806244D01*
X-1721544Y808324D01*
X-1720764Y810144D01*
X-1719594Y811184D01*
X-1718424Y811444D01*
X-1717254Y811184D01*
X-1716084Y810144D01*
X-1715304Y808324D01*
X-1715109Y806244D01*
X-1715304Y804164D01*
X-1716084Y802344D01*
X-1717254Y801304D01*
X-1718424Y801044D01*
G01X-1701694D02*
Y814304D01*
X-1701304Y815604D01*
X-1700524Y816384D01*
X-1699354Y816644D01*
X-1698184Y816124D01*
X-1697599Y814824D01*
G01X-1699939Y810404D02*
X-1703839D01*
G01X-1664724Y800524D02*
X-1665114Y800784D01*
Y801304D01*
X-1664724Y801564D01*
X-1664334Y801304D01*
Y800784D01*
X-1664724Y800524D01*
G01X-1646824Y816644D02*
X-1648384Y816124D01*
X-1649554Y814824D01*
X-1650334Y813264D01*
X-1650919Y811184D01*
X-1651114Y808844D01*
X-1650919Y806504D01*
X-1650334Y804424D01*
X-1649554Y802864D01*
X-1648384Y801564D01*
X-1646824Y801044D01*
X-1645264Y801564D01*
X-1644094Y802864D01*
X-1643314Y804424D01*
X-1642729Y806504D01*
X-1642534Y808844D01*
X-1642729Y811184D01*
X-1643314Y813264D01*
X-1644094Y814824D01*
X-1645264Y816124D01*
X-1646824Y816644D01*
G01X-1628924D02*
X-1630484Y816124D01*
X-1631654Y814824D01*
X-1632434Y813264D01*
X-1633019Y811184D01*
X-1633214Y808844D01*
X-1633019Y806504D01*
X-1632434Y804424D01*
X-1631654Y802864D01*
X-1630484Y801564D01*
X-1628924Y801044D01*
X-1627364Y801564D01*
X-1626194Y802864D01*
X-1625414Y804424D01*
X-1624829Y806504D01*
X-1624634Y808844D01*
X-1624829Y811184D01*
X-1625414Y813264D01*
X-1626194Y814824D01*
X-1627364Y816124D01*
X-1628924Y816644D01*
G01X-1611024Y801044D02*
Y816644D01*
X-1613364Y813524D01*
G01Y801044D02*
X-1608684D01*
G01X-1594879Y813264D02*
X-1593904Y816644D01*
G01X-1591369D02*
X-1592344Y813264D01*
G01X-1557324Y801044D02*
X-1558494Y801304D01*
X-1559664Y802344D01*
X-1560444Y804164D01*
X-1560834Y806244D01*
X-1560444Y808324D01*
X-1559664Y810144D01*
X-1558494Y811184D01*
X-1557324Y811444D01*
X-1556154Y811184D01*
X-1554984Y810144D01*
X-1554204Y808324D01*
X-1554009Y806244D01*
X-1554204Y804164D01*
X-1554984Y802344D01*
X-1556154Y801304D01*
X-1557324Y801044D01*
G01X-1542154D02*
Y811444D01*
G01Y809364D02*
X-1541179Y810404D01*
X-1540204Y811184D01*
X-1538839Y811444D01*
X-1537864Y811184D01*
X-1536694Y810404D01*
G01X-1507329Y814044D02*
X-1506159Y815604D01*
X-1504794Y816384D01*
X-1503234Y816644D01*
X-1501284Y816124D01*
X-1499919Y814824D01*
X-1499529Y813264D01*
X-1499724Y811704D01*
X-1500504Y810404D01*
X-1504404Y807804D01*
X-1506159Y805984D01*
X-1507329Y803384D01*
X-1507719Y801044D01*
X-1499529D01*
G01X-1485724Y816644D02*
X-1487284Y816124D01*
X-1488454Y814824D01*
X-1489234Y813264D01*
X-1489819Y811184D01*
X-1490014Y808844D01*
X-1489819Y806504D01*
X-1489234Y804424D01*
X-1488454Y802864D01*
X-1487284Y801564D01*
X-1485724Y801044D01*
X-1484164Y801564D01*
X-1482994Y802864D01*
X-1482214Y804424D01*
X-1481629Y806504D01*
X-1481434Y808844D01*
X-1481629Y811184D01*
X-1482214Y813264D01*
X-1482994Y814824D01*
X-1484164Y816124D01*
X-1485724Y816644D01*
G01X-1471334Y800524D02*
X-1464314Y816644D01*
G01X-1471334D02*
X-1472504Y816124D01*
X-1473089Y815344D01*
X-1473479Y813784D01*
X-1473089Y812224D01*
X-1472504Y811444D01*
X-1471334Y810924D01*
X-1470164Y811444D01*
X-1469579Y812224D01*
X-1469189Y813784D01*
X-1469579Y815344D01*
X-1470164Y816124D01*
X-1471334Y816644D01*
G01X-1464314Y806244D02*
X-1465484Y805724D01*
X-1466069Y804944D01*
X-1466459Y803384D01*
X-1466069Y801824D01*
X-1465484Y801044D01*
X-1464314Y800524D01*
X-1463144Y801044D01*
X-1462559Y801824D01*
X-1462169Y803384D01*
X-1462559Y804944D01*
X-1463144Y805724D01*
X-1464314Y806244D01*
G01X-1432024Y801044D02*
X-1433194Y801304D01*
X-1434364Y802344D01*
X-1435144Y804164D01*
X-1435534Y806244D01*
X-1435144Y808324D01*
X-1434364Y810144D01*
X-1433194Y811184D01*
X-1432024Y811444D01*
X-1430854Y811184D01*
X-1429684Y810144D01*
X-1428904Y808324D01*
X-1428709Y806244D01*
X-1428904Y804164D01*
X-1429684Y802344D01*
X-1430854Y801304D01*
X-1432024Y801044D01*
G01X-1415294D02*
Y814304D01*
X-1414904Y815604D01*
X-1414124Y816384D01*
X-1412954Y816644D01*
X-1411784Y816124D01*
X-1411199Y814824D01*
G01X-1413539Y810404D02*
X-1417439D01*
G01X-1378324Y816644D02*
Y801044D01*
G01X-1381054Y811444D02*
X-1375594D01*
G01X-1363739Y801044D02*
Y816644D01*
G01Y809104D02*
X-1362764Y810404D01*
X-1361789Y811184D01*
X-1360229Y811444D01*
X-1359059Y811184D01*
X-1357694Y810144D01*
X-1357109Y808584D01*
Y801044D01*
G01X-1345449Y808064D02*
X-1339209D01*
X-1339794Y809884D01*
X-1340769Y810924D01*
X-1342134Y811444D01*
X-1343499Y811184D01*
X-1344669Y810404D01*
X-1345449Y808584D01*
X-1345839Y807024D01*
Y805464D01*
X-1345449Y803904D01*
X-1344474Y802344D01*
X-1343304Y801304D01*
X-1341939Y801044D01*
X-1340574Y801564D01*
X-1339209Y803124D01*
G01X-1306724Y816644D02*
Y801044D01*
G01X-1309454Y811444D02*
X-1303994D01*
G01X-1291554Y801044D02*
Y811444D01*
G01Y809364D02*
X-1290579Y810404D01*
X-1289604Y811184D01*
X-1288239Y811444D01*
X-1287264Y811184D01*
X-1286094Y810404D01*
G01X-1267414Y801044D02*
Y811444D01*
G01Y809624D02*
X-1268194Y810664D01*
X-1269364Y811184D01*
X-1270729Y811444D01*
X-1272094Y810924D01*
X-1273264Y809884D01*
X-1274044Y808324D01*
X-1274434Y806244D01*
X-1274044Y804164D01*
X-1273264Y802604D01*
X-1272094Y801564D01*
X-1270729Y801044D01*
X-1269364Y801304D01*
X-1268194Y802084D01*
X-1267414Y803124D01*
G01X-1249904Y810144D02*
X-1251269Y811184D01*
X-1252439Y811444D01*
X-1253999Y810924D01*
X-1255169Y809884D01*
X-1255949Y808064D01*
X-1256144Y806244D01*
X-1255949Y804424D01*
X-1255169Y802864D01*
X-1253999Y801564D01*
X-1252439Y801044D01*
X-1251074Y801564D01*
X-1249904Y802604D01*
G01X-1238049Y808064D02*
X-1231809D01*
X-1232394Y809884D01*
X-1233369Y810924D01*
X-1234734Y811444D01*
X-1236099Y811184D01*
X-1237269Y810404D01*
X-1238049Y808584D01*
X-1238439Y807024D01*
Y805464D01*
X-1238049Y803904D01*
X-1237074Y802344D01*
X-1235904Y801304D01*
X-1234539Y801044D01*
X-1233174Y801564D01*
X-1231809Y803124D01*
G01X-1204199Y811444D02*
X-1201859Y801044D01*
X-1199324Y811444D01*
X-1196789Y801044D01*
X-1194449Y811444D01*
G01X-1181424D02*
Y801044D01*
G01Y815604D02*
X-1181814Y815864D01*
Y816384D01*
X-1181424Y816644D01*
X-1181034Y816384D01*
Y815864D01*
X-1181424Y815604D01*
G01X-1160014Y816644D02*
Y801044D01*
G01Y803384D02*
X-1160794Y802084D01*
X-1161964Y801304D01*
X-1163329Y801044D01*
X-1164889Y801564D01*
X-1166059Y802864D01*
X-1166839Y804424D01*
X-1167034Y806244D01*
X-1166839Y808064D01*
X-1166059Y809624D01*
X-1164889Y810924D01*
X-1163329Y811444D01*
X-1161964Y811184D01*
X-1160989Y810664D01*
X-1160014Y809624D01*
G01X-1145624Y816644D02*
Y801044D01*
G01X-1148354Y811444D02*
X-1142894D01*
G01X-1131039Y801044D02*
Y816644D01*
G01Y809104D02*
X-1130064Y810404D01*
X-1129089Y811184D01*
X-1127529Y811444D01*
X-1126359Y811184D01*
X-1124994Y810144D01*
X-1124409Y808584D01*
Y801044D01*
G01X-1093094D02*
Y814304D01*
X-1092704Y815604D01*
X-1091924Y816384D01*
X-1090754Y816644D01*
X-1089584Y816124D01*
X-1088999Y814824D01*
G01X-1091339Y810404D02*
X-1095239D01*
G01X-1076754Y801044D02*
Y811444D01*
G01Y809364D02*
X-1075779Y810404D01*
X-1074804Y811184D01*
X-1073439Y811444D01*
X-1072464Y811184D01*
X-1071294Y810404D01*
G01X-1056124Y801044D02*
X-1057294Y801304D01*
X-1058464Y802344D01*
X-1059244Y804164D01*
X-1059634Y806244D01*
X-1059244Y808324D01*
X-1058464Y810144D01*
X-1057294Y811184D01*
X-1056124Y811444D01*
X-1054954Y811184D01*
X-1053784Y810144D01*
X-1053004Y808324D01*
X-1052809Y806244D01*
X-1053004Y804164D01*
X-1053784Y802344D01*
X-1054954Y801304D01*
X-1056124Y801044D01*
G01X-1044074D02*
Y811444D01*
G01Y808584D02*
X-1043489Y809884D01*
X-1042514Y810924D01*
X-1041149Y811444D01*
X-1039784Y810924D01*
X-1038809Y809884D01*
X-1038224Y808584D01*
Y801044D01*
G01Y808584D02*
X-1037639Y809884D01*
X-1036664Y810924D01*
X-1035299Y811444D01*
X-1033934Y810924D01*
X-1032959Y809884D01*
X-1032374Y808324D01*
Y801044D01*
G01X-1002424Y816644D02*
Y801044D01*
G01X-1005154Y811444D02*
X-999694D01*
G01X-987839Y801044D02*
Y816644D01*
G01Y809104D02*
X-986864Y810404D01*
X-985889Y811184D01*
X-984329Y811444D01*
X-983159Y811184D01*
X-981794Y810144D01*
X-981209Y808584D01*
Y801044D01*
G01X-969549Y808064D02*
X-963309D01*
X-963894Y809884D01*
X-964869Y810924D01*
X-966234Y811444D01*
X-967599Y811184D01*
X-968769Y810404D01*
X-969549Y808584D01*
X-969939Y807024D01*
Y805464D01*
X-969549Y803904D01*
X-968574Y802344D01*
X-967404Y801304D01*
X-966039Y801044D01*
X-964674Y801564D01*
X-963309Y803124D01*
G01X-933554Y797144D02*
X-932189Y796104D01*
X-930629Y795844D01*
X-929264Y796104D01*
X-928094Y797404D01*
X-927314Y799224D01*
Y811444D01*
G01Y809364D02*
X-928094Y810404D01*
X-929264Y811184D01*
X-930629Y811444D01*
X-932189Y810924D01*
X-933164Y809884D01*
X-933944Y808064D01*
X-934334Y806244D01*
X-934139Y804684D01*
X-933359Y802864D01*
X-932189Y801564D01*
X-930629Y801044D01*
X-929459Y801304D01*
X-928094Y802344D01*
X-927314Y803384D01*
G01X-915849Y808064D02*
X-909609D01*
X-910194Y809884D01*
X-911169Y810924D01*
X-912534Y811444D01*
X-913899Y811184D01*
X-915069Y810404D01*
X-915849Y808584D01*
X-916239Y807024D01*
Y805464D01*
X-915849Y803904D01*
X-914874Y802344D01*
X-913704Y801304D01*
X-912339Y801044D01*
X-910974Y801564D01*
X-909609Y803124D01*
G01X-897754Y801044D02*
Y811444D01*
G01Y809364D02*
X-896779Y810404D01*
X-895804Y811184D01*
X-894439Y811444D01*
X-893464Y811184D01*
X-892294Y810404D01*
G01X-880634Y801044D02*
Y816644D01*
G01Y808844D02*
X-879659Y810404D01*
X-878489Y811184D01*
X-877319Y811444D01*
X-875564Y810924D01*
X-874394Y809884D01*
X-873614Y808064D01*
Y805984D01*
X-874004Y803904D01*
X-874784Y802344D01*
X-876149Y801304D01*
X-877319Y801044D01*
X-878489Y801304D01*
X-879659Y802084D01*
X-880634Y803384D01*
G01X-862149Y808064D02*
X-855909D01*
X-856494Y809884D01*
X-857469Y810924D01*
X-858834Y811444D01*
X-860199Y811184D01*
X-861369Y810404D01*
X-862149Y808584D01*
X-862539Y807024D01*
Y805464D01*
X-862149Y803904D01*
X-861174Y802344D01*
X-860004Y801304D01*
X-858639Y801044D01*
X-857274Y801564D01*
X-855909Y803124D01*
G01X-844054Y801044D02*
Y811444D01*
G01Y809364D02*
X-843079Y810404D01*
X-842104Y811184D01*
X-840739Y811444D01*
X-839764Y811184D01*
X-838594Y810404D01*
G01X-802014Y816644D02*
Y801044D01*
G01Y803384D02*
X-802794Y802084D01*
X-803964Y801304D01*
X-805329Y801044D01*
X-806889Y801564D01*
X-808059Y802864D01*
X-808839Y804424D01*
X-809034Y806244D01*
X-808839Y808064D01*
X-808059Y809624D01*
X-806889Y810924D01*
X-805329Y811444D01*
X-803964Y811184D01*
X-802989Y810664D01*
X-802014Y809624D01*
G01X-784114Y801044D02*
Y811444D01*
G01Y809624D02*
X-784894Y810664D01*
X-786064Y811184D01*
X-787429Y811444D01*
X-788794Y810924D01*
X-789964Y809884D01*
X-790744Y808324D01*
X-791134Y806244D01*
X-790744Y804164D01*
X-789964Y802604D01*
X-788794Y801564D01*
X-787429Y801044D01*
X-786064Y801304D01*
X-784894Y802084D01*
X-784114Y803124D01*
G01X-769724Y816644D02*
Y801044D01*
G01X-772454Y811444D02*
X-766994D01*
G01X-748314Y801044D02*
Y811444D01*
G01Y809624D02*
X-749094Y810664D01*
X-750264Y811184D01*
X-751629Y811444D01*
X-752994Y810924D01*
X-754164Y809884D01*
X-754944Y808324D01*
X-755334Y806244D01*
X-754944Y804164D01*
X-754164Y802604D01*
X-752994Y801564D01*
X-751629Y801044D01*
X-750264Y801304D01*
X-749094Y802084D01*
X-748314Y803124D01*
G01X-733924Y800524D02*
X-734314Y800784D01*
Y801304D01*
X-733924Y801564D01*
X-733534Y801304D01*
Y800784D01*
X-733924Y800524D01*
G01X-2019214Y918644D02*
Y903044D01*
G01Y905384D02*
X-2019994Y904084D01*
X-2021164Y903304D01*
X-2022529Y903044D01*
X-2024089Y903564D01*
X-2025259Y904864D01*
X-2026039Y906424D01*
X-2026234Y908244D01*
X-2026039Y910064D01*
X-2025259Y911624D01*
X-2024089Y912924D01*
X-2022529Y913444D01*
X-2021164Y913184D01*
X-2020189Y912664D01*
X-2019214Y911624D01*
G01X-2007554Y903044D02*
Y913444D01*
G01Y911364D02*
X-2006579Y912404D01*
X-2005604Y913184D01*
X-2004239Y913444D01*
X-2003264Y913184D01*
X-2002094Y912404D01*
G01X-1983414Y903044D02*
Y913444D01*
G01Y911624D02*
X-1984194Y912664D01*
X-1985364Y913184D01*
X-1986729Y913444D01*
X-1988094Y912924D01*
X-1989264Y911884D01*
X-1990044Y910324D01*
X-1990434Y908244D01*
X-1990044Y906164D01*
X-1989264Y904604D01*
X-1988094Y903564D01*
X-1986729Y903044D01*
X-1985364Y903304D01*
X-1984194Y904084D01*
X-1983414Y905124D01*
G01X-1973899Y913444D02*
X-1971559Y903044D01*
X-1969024Y913444D01*
X-1966489Y903044D01*
X-1964149Y913444D01*
G01X-1951124D02*
Y903044D01*
G01Y917604D02*
X-1951514Y917864D01*
Y918384D01*
X-1951124Y918644D01*
X-1950734Y918384D01*
Y917864D01*
X-1951124Y917604D01*
G01X-1936539Y903044D02*
Y913444D01*
G01Y910844D02*
X-1935759Y912144D01*
X-1934589Y913184D01*
X-1933029Y913444D01*
X-1931664Y913184D01*
X-1930494Y912144D01*
X-1929909Y910324D01*
Y903044D01*
G01X-1918054Y899144D02*
X-1916689Y898104D01*
X-1915129Y897844D01*
X-1913764Y898104D01*
X-1912594Y899404D01*
X-1911814Y901224D01*
Y913444D01*
G01Y911364D02*
X-1912594Y912404D01*
X-1913764Y913184D01*
X-1915129Y913444D01*
X-1916689Y912924D01*
X-1917664Y911884D01*
X-1918444Y910064D01*
X-1918834Y908244D01*
X-1918639Y906684D01*
X-1917859Y904864D01*
X-1916689Y903564D01*
X-1915129Y903044D01*
X-1913959Y903304D01*
X-1912594Y904344D01*
X-1911814Y905384D01*
G01X-1882449Y904864D02*
X-1881474Y903824D01*
X-1880109Y903044D01*
X-1878939D01*
X-1877769Y903564D01*
X-1876989Y904344D01*
X-1876599Y905384D01*
X-1876794Y906944D01*
X-1877574Y907724D01*
X-1881084Y909284D01*
X-1881864Y911104D01*
X-1881474Y912404D01*
X-1880694Y913184D01*
X-1879524Y913444D01*
X-1878354Y913184D01*
X-1877184Y912404D01*
G01X-1864939Y903044D02*
Y918644D01*
G01Y911104D02*
X-1863964Y912404D01*
X-1862989Y913184D01*
X-1861429Y913444D01*
X-1860259Y913184D01*
X-1858894Y912144D01*
X-1858309Y910584D01*
Y903044D01*
G01X-1840214D02*
Y913444D01*
G01Y911624D02*
X-1840994Y912664D01*
X-1842164Y913184D01*
X-1843529Y913444D01*
X-1844894Y912924D01*
X-1846064Y911884D01*
X-1846844Y910324D01*
X-1847234Y908244D01*
X-1846844Y906164D01*
X-1846064Y904604D01*
X-1844894Y903564D01*
X-1843529Y903044D01*
X-1842164Y903304D01*
X-1840994Y904084D01*
X-1840214Y905124D01*
G01X-1825824Y903044D02*
Y918644D01*
G01X-1807924Y903044D02*
Y918644D01*
G01X-1775634Y903044D02*
Y918644D01*
G01Y910844D02*
X-1774659Y912404D01*
X-1773489Y913184D01*
X-1772319Y913444D01*
X-1770564Y912924D01*
X-1769394Y911884D01*
X-1768614Y910064D01*
Y907984D01*
X-1769004Y905904D01*
X-1769784Y904344D01*
X-1771149Y903304D01*
X-1772319Y903044D01*
X-1773489Y903304D01*
X-1774659Y904084D01*
X-1775634Y905384D01*
G01X-1757149Y910064D02*
X-1750909D01*
X-1751494Y911884D01*
X-1752469Y912924D01*
X-1753834Y913444D01*
X-1755199Y913184D01*
X-1756369Y912404D01*
X-1757149Y910584D01*
X-1757539Y909024D01*
Y907464D01*
X-1757149Y905904D01*
X-1756174Y904344D01*
X-1755004Y903304D01*
X-1753639Y903044D01*
X-1752274Y903564D01*
X-1750909Y905124D01*
G01X-1715304Y912144D02*
X-1716669Y913184D01*
X-1717839Y913444D01*
X-1719399Y912924D01*
X-1720569Y911884D01*
X-1721349Y910064D01*
X-1721544Y908244D01*
X-1721349Y906424D01*
X-1720569Y904864D01*
X-1719399Y903564D01*
X-1717839Y903044D01*
X-1716474Y903564D01*
X-1715304Y904604D01*
G01X-1700524Y903044D02*
X-1701694Y903304D01*
X-1702864Y904344D01*
X-1703644Y906164D01*
X-1704034Y908244D01*
X-1703644Y910324D01*
X-1702864Y912144D01*
X-1701694Y913184D01*
X-1700524Y913444D01*
X-1699354Y913184D01*
X-1698184Y912144D01*
X-1697404Y910324D01*
X-1697209Y908244D01*
X-1697404Y906164D01*
X-1698184Y904344D01*
X-1699354Y903304D01*
X-1700524Y903044D01*
G01X-1685939D02*
Y913444D01*
G01Y910844D02*
X-1685159Y912144D01*
X-1683989Y913184D01*
X-1682429Y913444D01*
X-1681064Y913184D01*
X-1679894Y912144D01*
X-1679309Y910324D01*
Y903044D01*
G01X-1664724Y918644D02*
Y903044D01*
G01X-1667454Y913444D02*
X-1661994D01*
G01X-1649554Y903044D02*
Y913444D01*
G01Y911364D02*
X-1648579Y912404D01*
X-1647604Y913184D01*
X-1646239Y913444D01*
X-1645264Y913184D01*
X-1644094Y912404D01*
G01X-1628924Y903044D02*
X-1630094Y903304D01*
X-1631264Y904344D01*
X-1632044Y906164D01*
X-1632434Y908244D01*
X-1632044Y910324D01*
X-1631264Y912144D01*
X-1630094Y913184D01*
X-1628924Y913444D01*
X-1627754Y913184D01*
X-1626584Y912144D01*
X-1625804Y910324D01*
X-1625609Y908244D01*
X-1625804Y906164D01*
X-1626584Y904344D01*
X-1627754Y903304D01*
X-1628924Y903044D01*
G01X-1611024D02*
Y918644D01*
G01X-1593124Y903044D02*
Y918644D01*
G01X-1578149Y910064D02*
X-1571909D01*
X-1572494Y911884D01*
X-1573469Y912924D01*
X-1574834Y913444D01*
X-1576199Y913184D01*
X-1577369Y912404D01*
X-1578149Y910584D01*
X-1578539Y909024D01*
Y907464D01*
X-1578149Y905904D01*
X-1577174Y904344D01*
X-1576004Y903304D01*
X-1574639Y903044D01*
X-1573274Y903564D01*
X-1571909Y905124D01*
G01X-1553814Y918644D02*
Y903044D01*
G01Y905384D02*
X-1554594Y904084D01*
X-1555764Y903304D01*
X-1557129Y903044D01*
X-1558689Y903564D01*
X-1559859Y904864D01*
X-1560639Y906424D01*
X-1560834Y908244D01*
X-1560639Y910064D01*
X-1559859Y911624D01*
X-1558689Y912924D01*
X-1557129Y913444D01*
X-1555764Y913184D01*
X-1554789Y912664D01*
X-1553814Y911624D01*
G01X-1525034Y903044D02*
Y918644D01*
G01Y910844D02*
X-1524059Y912404D01*
X-1522889Y913184D01*
X-1521719Y913444D01*
X-1519964Y912924D01*
X-1518794Y911884D01*
X-1518014Y910064D01*
Y907984D01*
X-1518404Y905904D01*
X-1519184Y904344D01*
X-1520549Y903304D01*
X-1521719Y903044D01*
X-1522889Y903304D01*
X-1524059Y904084D01*
X-1525034Y905384D01*
G01X-1507719Y898364D02*
X-1506549Y897844D01*
X-1504989Y898364D01*
X-1504014Y899404D01*
X-1503234Y900704D01*
X-1502064Y904864D01*
X-1499529Y913444D01*
G01X-1505769D02*
X-1502064Y904864D01*
G01X-1467824Y918644D02*
Y903044D01*
G01X-1470554Y913444D02*
X-1465094D01*
G01X-1453239Y903044D02*
Y918644D01*
G01Y911104D02*
X-1452264Y912404D01*
X-1451289Y913184D01*
X-1449729Y913444D01*
X-1448559Y913184D01*
X-1447194Y912144D01*
X-1446609Y910584D01*
Y903044D01*
G01X-1434949Y910064D02*
X-1428709D01*
X-1429294Y911884D01*
X-1430269Y912924D01*
X-1431634Y913444D01*
X-1432999Y913184D01*
X-1434169Y912404D01*
X-1434949Y910584D01*
X-1435339Y909024D01*
Y907464D01*
X-1434949Y905904D01*
X-1433974Y904344D01*
X-1432804Y903304D01*
X-1431439Y903044D01*
X-1430074Y903564D01*
X-1428709Y905124D01*
G01X-1398954Y899144D02*
X-1397589Y898104D01*
X-1396029Y897844D01*
X-1394664Y898104D01*
X-1393494Y899404D01*
X-1392714Y901224D01*
Y913444D01*
G01Y911364D02*
X-1393494Y912404D01*
X-1394664Y913184D01*
X-1396029Y913444D01*
X-1397589Y912924D01*
X-1398564Y911884D01*
X-1399344Y910064D01*
X-1399734Y908244D01*
X-1399539Y906684D01*
X-1398759Y904864D01*
X-1397589Y903564D01*
X-1396029Y903044D01*
X-1394859Y903304D01*
X-1393494Y904344D01*
X-1392714Y905384D01*
G01X-1381249Y910064D02*
X-1375009D01*
X-1375594Y911884D01*
X-1376569Y912924D01*
X-1377934Y913444D01*
X-1379299Y913184D01*
X-1380469Y912404D01*
X-1381249Y910584D01*
X-1381639Y909024D01*
Y907464D01*
X-1381249Y905904D01*
X-1380274Y904344D01*
X-1379104Y903304D01*
X-1377739Y903044D01*
X-1376374Y903564D01*
X-1375009Y905124D01*
G01X-1363154Y903044D02*
Y913444D01*
G01Y911364D02*
X-1362179Y912404D01*
X-1361204Y913184D01*
X-1359839Y913444D01*
X-1358864Y913184D01*
X-1357694Y912404D01*
G01X-1346034Y903044D02*
Y918644D01*
G01Y910844D02*
X-1345059Y912404D01*
X-1343889Y913184D01*
X-1342719Y913444D01*
X-1340964Y912924D01*
X-1339794Y911884D01*
X-1339014Y910064D01*
Y907984D01*
X-1339404Y905904D01*
X-1340184Y904344D01*
X-1341549Y903304D01*
X-1342719Y903044D01*
X-1343889Y903304D01*
X-1345059Y904084D01*
X-1346034Y905384D01*
G01X-1327549Y910064D02*
X-1321309D01*
X-1321894Y911884D01*
X-1322869Y912924D01*
X-1324234Y913444D01*
X-1325599Y913184D01*
X-1326769Y912404D01*
X-1327549Y910584D01*
X-1327939Y909024D01*
Y907464D01*
X-1327549Y905904D01*
X-1326574Y904344D01*
X-1325404Y903304D01*
X-1324039Y903044D01*
X-1322674Y903564D01*
X-1321309Y905124D01*
G01X-1309454Y903044D02*
Y913444D01*
G01Y911364D02*
X-1308479Y912404D01*
X-1307504Y913184D01*
X-1306139Y913444D01*
X-1305164Y913184D01*
X-1303994Y912404D01*
G01X-1267414Y918644D02*
Y903044D01*
G01Y905384D02*
X-1268194Y904084D01*
X-1269364Y903304D01*
X-1270729Y903044D01*
X-1272289Y903564D01*
X-1273459Y904864D01*
X-1274239Y906424D01*
X-1274434Y908244D01*
X-1274239Y910064D01*
X-1273459Y911624D01*
X-1272289Y912924D01*
X-1270729Y913444D01*
X-1269364Y913184D01*
X-1268389Y912664D01*
X-1267414Y911624D01*
G01X-1249514Y903044D02*
Y913444D01*
G01Y911624D02*
X-1250294Y912664D01*
X-1251464Y913184D01*
X-1252829Y913444D01*
X-1254194Y912924D01*
X-1255364Y911884D01*
X-1256144Y910324D01*
X-1256534Y908244D01*
X-1256144Y906164D01*
X-1255364Y904604D01*
X-1254194Y903564D01*
X-1252829Y903044D01*
X-1251464Y903304D01*
X-1250294Y904084D01*
X-1249514Y905124D01*
G01X-1235124Y918644D02*
Y903044D01*
G01X-1237854Y913444D02*
X-1232394D01*
G01X-1213714Y903044D02*
Y913444D01*
G01Y911624D02*
X-1214494Y912664D01*
X-1215664Y913184D01*
X-1217029Y913444D01*
X-1218394Y912924D01*
X-1219564Y911884D01*
X-1220344Y910324D01*
X-1220734Y908244D01*
X-1220344Y906164D01*
X-1219564Y904604D01*
X-1218394Y903564D01*
X-1217029Y903044D01*
X-1215664Y903304D01*
X-1214494Y904084D01*
X-1213714Y905124D01*
G01X-1199324Y902524D02*
X-1199714Y902784D01*
Y903304D01*
X-1199324Y903564D01*
X-1198934Y903304D01*
Y902784D01*
X-1199324Y902524D01*
G01X-2019604Y980144D02*
X-2020969Y981184D01*
X-2022139Y981444D01*
X-2023699Y980924D01*
X-2024869Y979884D01*
X-2025649Y978064D01*
X-2025844Y976244D01*
X-2025649Y974424D01*
X-2024869Y972864D01*
X-2023699Y971564D01*
X-2022139Y971044D01*
X-2020774Y971564D01*
X-2019604Y972604D01*
G01X-2004824Y981444D02*
Y971044D01*
G01Y985604D02*
X-2005214Y985864D01*
Y986384D01*
X-2004824Y986644D01*
X-2004434Y986384D01*
Y985864D01*
X-2004824Y985604D01*
G01X-1989654Y971044D02*
Y981444D01*
G01Y979364D02*
X-1988679Y980404D01*
X-1987704Y981184D01*
X-1986339Y981444D01*
X-1985364Y981184D01*
X-1984194Y980404D01*
G01X-1965904Y980144D02*
X-1967269Y981184D01*
X-1968439Y981444D01*
X-1969999Y980924D01*
X-1971169Y979884D01*
X-1971949Y978064D01*
X-1972144Y976244D01*
X-1971949Y974424D01*
X-1971169Y972864D01*
X-1969999Y971564D01*
X-1968439Y971044D01*
X-1967074Y971564D01*
X-1965904Y972604D01*
G01X-1954439Y981444D02*
Y974164D01*
X-1953659Y972344D01*
X-1952489Y971304D01*
X-1951124Y971044D01*
X-1949759Y971304D01*
X-1948589Y972344D01*
X-1947809Y974164D01*
G01Y971044D02*
Y981444D01*
G01X-1933224D02*
Y971044D01*
G01Y985604D02*
X-1933614Y985864D01*
Y986384D01*
X-1933224Y986644D01*
X-1932834Y986384D01*
Y985864D01*
X-1933224Y985604D01*
G01X-1915324Y986644D02*
Y971044D01*
G01X-1918054Y981444D02*
X-1912594D01*
G01X-1900154Y971044D02*
Y981444D01*
G01Y979364D02*
X-1899179Y980404D01*
X-1898204Y981184D01*
X-1896839Y981444D01*
X-1895864Y981184D01*
X-1894694Y980404D01*
G01X-1883619Y966364D02*
X-1882449Y965844D01*
X-1880889Y966364D01*
X-1879914Y967404D01*
X-1879134Y968704D01*
X-1877964Y972864D01*
X-1875429Y981444D01*
G01X-1881669D02*
X-1877964Y972864D01*
G01X-1840214Y971044D02*
Y981444D01*
G01Y979624D02*
X-1840994Y980664D01*
X-1842164Y981184D01*
X-1843529Y981444D01*
X-1844894Y980924D01*
X-1846064Y979884D01*
X-1846844Y978324D01*
X-1847234Y976244D01*
X-1846844Y974164D01*
X-1846064Y972604D01*
X-1844894Y971564D01*
X-1843529Y971044D01*
X-1842164Y971304D01*
X-1840994Y972084D01*
X-1840214Y973124D01*
G01X-1829139Y971044D02*
Y981444D01*
G01Y978844D02*
X-1828359Y980144D01*
X-1827189Y981184D01*
X-1825629Y981444D01*
X-1824264Y981184D01*
X-1823094Y980144D01*
X-1822509Y978324D01*
Y971044D01*
G01X-1804414Y986644D02*
Y971044D01*
G01Y973384D02*
X-1805194Y972084D01*
X-1806364Y971304D01*
X-1807729Y971044D01*
X-1809289Y971564D01*
X-1810459Y972864D01*
X-1811239Y974424D01*
X-1811434Y976244D01*
X-1811239Y978064D01*
X-1810459Y979624D01*
X-1809289Y980924D01*
X-1807729Y981444D01*
X-1806364Y981184D01*
X-1805389Y980664D01*
X-1804414Y979624D01*
G01X-1772124Y986644D02*
Y971044D01*
G01X-1774854Y981444D02*
X-1769394D01*
G01X-1757539Y971044D02*
Y986644D01*
G01Y979104D02*
X-1756564Y980404D01*
X-1755589Y981184D01*
X-1754029Y981444D01*
X-1752859Y981184D01*
X-1751494Y980144D01*
X-1750909Y978584D01*
Y971044D01*
G01X-1739249Y978064D02*
X-1733009D01*
X-1733594Y979884D01*
X-1734569Y980924D01*
X-1735934Y981444D01*
X-1737299Y981184D01*
X-1738469Y980404D01*
X-1739249Y978584D01*
X-1739639Y977024D01*
Y975464D01*
X-1739249Y973904D01*
X-1738274Y972344D01*
X-1737104Y971304D01*
X-1735739Y971044D01*
X-1734374Y971564D01*
X-1733009Y973124D01*
G01X-1706374Y971044D02*
Y981444D01*
G01Y978584D02*
X-1705789Y979884D01*
X-1704814Y980924D01*
X-1703449Y981444D01*
X-1702084Y980924D01*
X-1701109Y979884D01*
X-1700524Y978584D01*
Y971044D01*
G01Y978584D02*
X-1699939Y979884D01*
X-1698964Y980924D01*
X-1697599Y981444D01*
X-1696234Y980924D01*
X-1695259Y979884D01*
X-1694674Y978324D01*
Y971044D01*
G01X-1679114D02*
Y981444D01*
G01Y979624D02*
X-1679894Y980664D01*
X-1681064Y981184D01*
X-1682429Y981444D01*
X-1683794Y980924D01*
X-1684964Y979884D01*
X-1685744Y978324D01*
X-1686134Y976244D01*
X-1685744Y974164D01*
X-1684964Y972604D01*
X-1683794Y971564D01*
X-1682429Y971044D01*
X-1681064Y971304D01*
X-1679894Y972084D01*
X-1679114Y973124D01*
G01X-1668039Y971044D02*
Y981444D01*
G01Y978844D02*
X-1667259Y980144D01*
X-1666089Y981184D01*
X-1664529Y981444D01*
X-1663164Y981184D01*
X-1661994Y980144D01*
X-1661409Y978324D01*
Y971044D01*
G01X-1650139Y981444D02*
Y974164D01*
X-1649359Y972344D01*
X-1648189Y971304D01*
X-1646824Y971044D01*
X-1645459Y971304D01*
X-1644289Y972344D01*
X-1643509Y974164D01*
G01Y971044D02*
Y981444D01*
G01X-1630094Y971044D02*
Y984304D01*
X-1629704Y985604D01*
X-1628924Y986384D01*
X-1627754Y986644D01*
X-1626584Y986124D01*
X-1625999Y984824D01*
G01X-1628339Y980404D02*
X-1632239D01*
G01X-1607514Y971044D02*
Y981444D01*
G01Y979624D02*
X-1608294Y980664D01*
X-1609464Y981184D01*
X-1610829Y981444D01*
X-1612194Y980924D01*
X-1613364Y979884D01*
X-1614144Y978324D01*
X-1614534Y976244D01*
X-1614144Y974164D01*
X-1613364Y972604D01*
X-1612194Y971564D01*
X-1610829Y971044D01*
X-1609464Y971304D01*
X-1608294Y972084D01*
X-1607514Y973124D01*
G01X-1590004Y980144D02*
X-1591369Y981184D01*
X-1592539Y981444D01*
X-1594099Y980924D01*
X-1595269Y979884D01*
X-1596049Y978064D01*
X-1596244Y976244D01*
X-1596049Y974424D01*
X-1595269Y972864D01*
X-1594099Y971564D01*
X-1592539Y971044D01*
X-1591174Y971564D01*
X-1590004Y972604D01*
G01X-1575224Y986644D02*
Y971044D01*
G01X-1577954Y981444D02*
X-1572494D01*
G01X-1560639D02*
Y974164D01*
X-1559859Y972344D01*
X-1558689Y971304D01*
X-1557324Y971044D01*
X-1555959Y971304D01*
X-1554789Y972344D01*
X-1554009Y974164D01*
G01Y971044D02*
Y981444D01*
G01X-1542154Y971044D02*
Y981444D01*
G01Y979364D02*
X-1541179Y980404D01*
X-1540204Y981184D01*
X-1538839Y981444D01*
X-1537864Y981184D01*
X-1536694Y980404D01*
G01X-1521524Y981444D02*
Y971044D01*
G01Y985604D02*
X-1521914Y985864D01*
Y986384D01*
X-1521524Y986644D01*
X-1521134Y986384D01*
Y985864D01*
X-1521524Y985604D01*
G01X-1506939Y971044D02*
Y981444D01*
G01Y978844D02*
X-1506159Y980144D01*
X-1504989Y981184D01*
X-1503429Y981444D01*
X-1502064Y981184D01*
X-1500894Y980144D01*
X-1500309Y978324D01*
Y971044D01*
G01X-1488454Y967144D02*
X-1487089Y966104D01*
X-1485529Y965844D01*
X-1484164Y966104D01*
X-1482994Y967404D01*
X-1482214Y969224D01*
Y981444D01*
G01Y979364D02*
X-1482994Y980404D01*
X-1484164Y981184D01*
X-1485529Y981444D01*
X-1487089Y980924D01*
X-1488064Y979884D01*
X-1488844Y978064D01*
X-1489234Y976244D01*
X-1489039Y974684D01*
X-1488259Y972864D01*
X-1487089Y971564D01*
X-1485529Y971044D01*
X-1484359Y971304D01*
X-1482994Y972344D01*
X-1482214Y973384D01*
G01X-1453239Y971044D02*
Y986644D01*
G01Y979104D02*
X-1452264Y980404D01*
X-1451289Y981184D01*
X-1449729Y981444D01*
X-1448559Y981184D01*
X-1447194Y980144D01*
X-1446609Y978584D01*
Y971044D01*
G01X-1432024Y981444D02*
Y971044D01*
G01Y985604D02*
X-1432414Y985864D01*
Y986384D01*
X-1432024Y986644D01*
X-1431634Y986384D01*
Y985864D01*
X-1432024Y985604D01*
G01X-1417049Y972864D02*
X-1416074Y971824D01*
X-1414709Y971044D01*
X-1413539D01*
X-1412369Y971564D01*
X-1411589Y972344D01*
X-1411199Y973384D01*
X-1411394Y974944D01*
X-1412174Y975724D01*
X-1415684Y977284D01*
X-1416464Y979104D01*
X-1416074Y980404D01*
X-1415294Y981184D01*
X-1414124Y981444D01*
X-1412954Y981184D01*
X-1411784Y980404D01*
G01X-1396224Y986644D02*
Y971044D01*
G01X-1398954Y981444D02*
X-1393494D01*
G01X-1378324Y971044D02*
X-1379494Y971304D01*
X-1380664Y972344D01*
X-1381444Y974164D01*
X-1381834Y976244D01*
X-1381444Y978324D01*
X-1380664Y980144D01*
X-1379494Y981184D01*
X-1378324Y981444D01*
X-1377154Y981184D01*
X-1375984Y980144D01*
X-1375204Y978324D01*
X-1375009Y976244D01*
X-1375204Y974164D01*
X-1375984Y972344D01*
X-1377154Y971304D01*
X-1378324Y971044D01*
G01X-1363154D02*
Y981444D01*
G01Y979364D02*
X-1362179Y980404D01*
X-1361204Y981184D01*
X-1359839Y981444D01*
X-1358864Y981184D01*
X-1357694Y980404D01*
G01X-1346619Y966364D02*
X-1345449Y965844D01*
X-1343889Y966364D01*
X-1342914Y967404D01*
X-1342134Y968704D01*
X-1340964Y972864D01*
X-1338429Y981444D01*
G01X-1344669D02*
X-1340964Y972864D01*
G01X-1324624Y970524D02*
X-1325014Y970784D01*
Y971304D01*
X-1324624Y971564D01*
X-1324234Y971304D01*
Y970784D01*
X-1324624Y970524D01*
G01X-2026624Y1005044D02*
Y1020644D01*
X-2021944D01*
X-2020384Y1019864D01*
X-2019214Y1018044D01*
X-2018824Y1015964D01*
X-2019214Y1013884D01*
X-2020189Y1012324D01*
X-2021944Y1011544D01*
X-2026624D01*
G01X-2000534Y1019344D02*
X-2001704Y1020124D01*
X-2003069Y1020644D01*
X-2004629D01*
X-2006384Y1019864D01*
X-2007749Y1018564D01*
X-2008724Y1017004D01*
X-2009504Y1014404D01*
X-2009699Y1012064D01*
X-2009309Y1009724D01*
X-2008724Y1008164D01*
X-2007554Y1006604D01*
X-2006189Y1005564D01*
X-2004824Y1005044D01*
X-2003459D01*
X-2002094Y1005564D01*
X-2000924Y1006344D01*
X-1999949Y1007384D01*
G01X-1985364Y1013364D02*
X-1984584Y1014144D01*
X-1983999Y1015444D01*
X-1983609Y1017264D01*
X-1983999Y1018824D01*
X-1984779Y1019864D01*
X-1986144Y1020644D01*
X-1991409D01*
Y1005044D01*
X-1984974D01*
X-1983609Y1006084D01*
X-1982829Y1007644D01*
X-1982439Y1009464D01*
X-1982829Y1011284D01*
X-1983999Y1012844D01*
X-1985364Y1013364D01*
X-1991409D01*
G01X-1954634Y1015444D02*
X-1951124Y1005044D01*
X-1947614Y1015444D01*
G01X-1936149Y1012064D02*
X-1929909D01*
X-1930494Y1013884D01*
X-1931469Y1014924D01*
X-1932834Y1015444D01*
X-1934199Y1015184D01*
X-1935369Y1014404D01*
X-1936149Y1012584D01*
X-1936539Y1011024D01*
Y1009464D01*
X-1936149Y1007904D01*
X-1935174Y1006344D01*
X-1934004Y1005304D01*
X-1932639Y1005044D01*
X-1931274Y1005564D01*
X-1929909Y1007124D01*
G01X-1918639Y1005044D02*
Y1015444D01*
G01Y1012844D02*
X-1917859Y1014144D01*
X-1916689Y1015184D01*
X-1915129Y1015444D01*
X-1913764Y1015184D01*
X-1912594Y1014144D01*
X-1912009Y1012324D01*
Y1005044D01*
G01X-1893914Y1020644D02*
Y1005044D01*
G01Y1007384D02*
X-1894694Y1006084D01*
X-1895864Y1005304D01*
X-1897229Y1005044D01*
X-1898789Y1005564D01*
X-1899959Y1006864D01*
X-1900739Y1008424D01*
X-1900934Y1010244D01*
X-1900739Y1012064D01*
X-1899959Y1013624D01*
X-1898789Y1014924D01*
X-1897229Y1015444D01*
X-1895864Y1015184D01*
X-1894889Y1014664D01*
X-1893914Y1013624D01*
G01X-1879524Y1005044D02*
X-1880694Y1005304D01*
X-1881864Y1006344D01*
X-1882644Y1008164D01*
X-1883034Y1010244D01*
X-1882644Y1012324D01*
X-1881864Y1014144D01*
X-1880694Y1015184D01*
X-1879524Y1015444D01*
X-1878354Y1015184D01*
X-1877184Y1014144D01*
X-1876404Y1012324D01*
X-1876209Y1010244D01*
X-1876404Y1008164D01*
X-1877184Y1006344D01*
X-1878354Y1005304D01*
X-1879524Y1005044D01*
G01X-1864354D02*
Y1015444D01*
G01Y1013364D02*
X-1863379Y1014404D01*
X-1862404Y1015184D01*
X-1861039Y1015444D01*
X-1860064Y1015184D01*
X-1858894Y1014404D01*
G01X-1828749Y1006864D02*
X-1827774Y1005824D01*
X-1826409Y1005044D01*
X-1825239D01*
X-1824069Y1005564D01*
X-1823289Y1006344D01*
X-1822899Y1007384D01*
X-1823094Y1008944D01*
X-1823874Y1009724D01*
X-1827384Y1011284D01*
X-1828164Y1013104D01*
X-1827774Y1014404D01*
X-1826994Y1015184D01*
X-1825824Y1015444D01*
X-1824654Y1015184D01*
X-1823484Y1014404D01*
G01X-1811239Y1005044D02*
Y1020644D01*
G01Y1013104D02*
X-1810264Y1014404D01*
X-1809289Y1015184D01*
X-1807729Y1015444D01*
X-1806559Y1015184D01*
X-1805194Y1014144D01*
X-1804609Y1012584D01*
Y1005044D01*
G01X-1786514D02*
Y1015444D01*
G01Y1013624D02*
X-1787294Y1014664D01*
X-1788464Y1015184D01*
X-1789829Y1015444D01*
X-1791194Y1014924D01*
X-1792364Y1013884D01*
X-1793144Y1012324D01*
X-1793534Y1010244D01*
X-1793144Y1008164D01*
X-1792364Y1006604D01*
X-1791194Y1005564D01*
X-1789829Y1005044D01*
X-1788464Y1005304D01*
X-1787294Y1006084D01*
X-1786514Y1007124D01*
G01X-1772124Y1005044D02*
Y1020644D01*
G01X-1754224Y1005044D02*
Y1020644D01*
G01X-1721349Y1012064D02*
X-1715109D01*
X-1715694Y1013884D01*
X-1716669Y1014924D01*
X-1718034Y1015444D01*
X-1719399Y1015184D01*
X-1720569Y1014404D01*
X-1721349Y1012584D01*
X-1721739Y1011024D01*
Y1009464D01*
X-1721349Y1007904D01*
X-1720374Y1006344D01*
X-1719204Y1005304D01*
X-1717839Y1005044D01*
X-1716474Y1005564D01*
X-1715109Y1007124D01*
G01X-1703839Y1005044D02*
Y1015444D01*
G01Y1012844D02*
X-1703059Y1014144D01*
X-1701889Y1015184D01*
X-1700329Y1015444D01*
X-1698964Y1015184D01*
X-1697794Y1014144D01*
X-1697209Y1012324D01*
Y1005044D01*
G01X-1685549Y1006864D02*
X-1684574Y1005824D01*
X-1683209Y1005044D01*
X-1682039D01*
X-1680869Y1005564D01*
X-1680089Y1006344D01*
X-1679699Y1007384D01*
X-1679894Y1008944D01*
X-1680674Y1009724D01*
X-1684184Y1011284D01*
X-1684964Y1013104D01*
X-1684574Y1014404D01*
X-1683794Y1015184D01*
X-1682624Y1015444D01*
X-1681454Y1015184D01*
X-1680284Y1014404D01*
G01X-1668039Y1015444D02*
Y1008164D01*
X-1667259Y1006344D01*
X-1666089Y1005304D01*
X-1664724Y1005044D01*
X-1663359Y1005304D01*
X-1662189Y1006344D01*
X-1661409Y1008164D01*
G01Y1005044D02*
Y1015444D01*
G01X-1649554Y1005044D02*
Y1015444D01*
G01Y1013364D02*
X-1648579Y1014404D01*
X-1647604Y1015184D01*
X-1646239Y1015444D01*
X-1645264Y1015184D01*
X-1644094Y1014404D01*
G01X-1631849Y1012064D02*
X-1625609D01*
X-1626194Y1013884D01*
X-1627169Y1014924D01*
X-1628534Y1015444D01*
X-1629899Y1015184D01*
X-1631069Y1014404D01*
X-1631849Y1012584D01*
X-1632239Y1011024D01*
Y1009464D01*
X-1631849Y1007904D01*
X-1630874Y1006344D01*
X-1629704Y1005304D01*
X-1628339Y1005044D01*
X-1626974Y1005564D01*
X-1625609Y1007124D01*
G01X-1589224Y1005044D02*
X-1597024D01*
Y1020644D01*
X-1589224D01*
G01X-1592344Y1013104D02*
X-1597024D01*
G01X-1575224Y1020644D02*
Y1005044D01*
G01X-1577954Y1015444D02*
X-1572494D01*
G01X-1560249Y1012064D02*
X-1554009D01*
X-1554594Y1013884D01*
X-1555569Y1014924D01*
X-1556934Y1015444D01*
X-1558299Y1015184D01*
X-1559469Y1014404D01*
X-1560249Y1012584D01*
X-1560639Y1011024D01*
Y1009464D01*
X-1560249Y1007904D01*
X-1559274Y1006344D01*
X-1558104Y1005304D01*
X-1556739Y1005044D01*
X-1555374Y1005564D01*
X-1554009Y1007124D01*
G01X-1542349Y1006864D02*
X-1541374Y1005824D01*
X-1540009Y1005044D01*
X-1538839D01*
X-1537669Y1005564D01*
X-1536889Y1006344D01*
X-1536499Y1007384D01*
X-1536694Y1008944D01*
X-1537474Y1009724D01*
X-1540984Y1011284D01*
X-1541764Y1013104D01*
X-1541374Y1014404D01*
X-1540594Y1015184D01*
X-1539424Y1015444D01*
X-1538254Y1015184D01*
X-1537084Y1014404D01*
G01X-1521524Y1020644D02*
Y1005044D01*
G01X-1524254Y1015444D02*
X-1518794D01*
G01X-1491574Y1005044D02*
Y1015444D01*
G01Y1012584D02*
X-1490989Y1013884D01*
X-1490014Y1014924D01*
X-1488649Y1015444D01*
X-1487284Y1014924D01*
X-1486309Y1013884D01*
X-1485724Y1012584D01*
Y1005044D01*
G01Y1012584D02*
X-1485139Y1013884D01*
X-1484164Y1014924D01*
X-1482799Y1015444D01*
X-1481434Y1014924D01*
X-1480459Y1013884D01*
X-1479874Y1012324D01*
Y1005044D01*
G01X-1464314D02*
Y1015444D01*
G01Y1013624D02*
X-1465094Y1014664D01*
X-1466264Y1015184D01*
X-1467629Y1015444D01*
X-1468994Y1014924D01*
X-1470164Y1013884D01*
X-1470944Y1012324D01*
X-1471334Y1010244D01*
X-1470944Y1008164D01*
X-1470164Y1006604D01*
X-1468994Y1005564D01*
X-1467629Y1005044D01*
X-1466264Y1005304D01*
X-1465094Y1006084D01*
X-1464314Y1007124D01*
G01X-1452654Y1005044D02*
Y1015444D01*
G01Y1013364D02*
X-1451679Y1014404D01*
X-1450704Y1015184D01*
X-1449339Y1015444D01*
X-1448364Y1015184D01*
X-1447194Y1014404D01*
G01X-1435339Y1005044D02*
Y1020644D01*
G01X-1429099Y1015444D02*
X-1435339Y1009464D01*
G01X-1432804Y1011804D02*
X-1428709Y1005044D01*
G01X-1414124Y1015444D02*
Y1005044D01*
G01Y1019604D02*
X-1414514Y1019864D01*
Y1020384D01*
X-1414124Y1020644D01*
X-1413734Y1020384D01*
Y1019864D01*
X-1414124Y1019604D01*
G01X-1399539Y1005044D02*
Y1015444D01*
G01Y1012844D02*
X-1398759Y1014144D01*
X-1397589Y1015184D01*
X-1396029Y1015444D01*
X-1394664Y1015184D01*
X-1393494Y1014144D01*
X-1392909Y1012324D01*
Y1005044D01*
G01X-1381054Y1001144D02*
X-1379689Y1000104D01*
X-1378129Y999844D01*
X-1376764Y1000104D01*
X-1375594Y1001404D01*
X-1374814Y1003224D01*
Y1015444D01*
G01Y1013364D02*
X-1375594Y1014404D01*
X-1376764Y1015184D01*
X-1378129Y1015444D01*
X-1379689Y1014924D01*
X-1380664Y1013884D01*
X-1381444Y1012064D01*
X-1381834Y1010244D01*
X-1381639Y1008684D01*
X-1380859Y1006864D01*
X-1379689Y1005564D01*
X-1378129Y1005044D01*
X-1376959Y1005304D01*
X-1375594Y1006344D01*
X-1374814Y1007384D01*
G01X-1342524Y1020644D02*
Y1005044D01*
G01X-1345254Y1015444D02*
X-1339794D01*
G01X-1327354Y1005044D02*
Y1015444D01*
G01Y1013364D02*
X-1326379Y1014404D01*
X-1325404Y1015184D01*
X-1324039Y1015444D01*
X-1323064Y1015184D01*
X-1321894Y1014404D01*
G01X-1303214Y1005044D02*
Y1015444D01*
G01Y1013624D02*
X-1303994Y1014664D01*
X-1305164Y1015184D01*
X-1306529Y1015444D01*
X-1307894Y1014924D01*
X-1309064Y1013884D01*
X-1309844Y1012324D01*
X-1310234Y1010244D01*
X-1309844Y1008164D01*
X-1309064Y1006604D01*
X-1307894Y1005564D01*
X-1306529Y1005044D01*
X-1305164Y1005304D01*
X-1303994Y1006084D01*
X-1303214Y1007124D01*
G01X-1285704Y1014144D02*
X-1287069Y1015184D01*
X-1288239Y1015444D01*
X-1289799Y1014924D01*
X-1290969Y1013884D01*
X-1291749Y1012064D01*
X-1291944Y1010244D01*
X-1291749Y1008424D01*
X-1290969Y1006864D01*
X-1289799Y1005564D01*
X-1288239Y1005044D01*
X-1286874Y1005564D01*
X-1285704Y1006604D01*
G01X-1273849Y1012064D02*
X-1267609D01*
X-1268194Y1013884D01*
X-1269169Y1014924D01*
X-1270534Y1015444D01*
X-1271899Y1015184D01*
X-1273069Y1014404D01*
X-1273849Y1012584D01*
X-1274239Y1011024D01*
Y1009464D01*
X-1273849Y1007904D01*
X-1272874Y1006344D01*
X-1271704Y1005304D01*
X-1270339Y1005044D01*
X-1268974Y1005564D01*
X-1267609Y1007124D01*
G01X-1249514Y1005044D02*
Y1015444D01*
G01Y1013624D02*
X-1250294Y1014664D01*
X-1251464Y1015184D01*
X-1252829Y1015444D01*
X-1254194Y1014924D01*
X-1255364Y1013884D01*
X-1256144Y1012324D01*
X-1256534Y1010244D01*
X-1256144Y1008164D01*
X-1255364Y1006604D01*
X-1254194Y1005564D01*
X-1252829Y1005044D01*
X-1251464Y1005304D01*
X-1250294Y1006084D01*
X-1249514Y1007124D01*
G01X-1238634Y1005044D02*
Y1020644D01*
G01Y1012844D02*
X-1237659Y1014404D01*
X-1236489Y1015184D01*
X-1235319Y1015444D01*
X-1233564Y1014924D01*
X-1232394Y1013884D01*
X-1231614Y1012064D01*
Y1009984D01*
X-1232004Y1007904D01*
X-1232784Y1006344D01*
X-1234149Y1005304D01*
X-1235319Y1005044D01*
X-1236489Y1005304D01*
X-1237659Y1006084D01*
X-1238634Y1007384D01*
G01X-1217224Y1015444D02*
Y1005044D01*
G01Y1019604D02*
X-1217614Y1019864D01*
Y1020384D01*
X-1217224Y1020644D01*
X-1216834Y1020384D01*
Y1019864D01*
X-1217224Y1019604D01*
G01X-1199324Y1005044D02*
Y1020644D01*
G01X-1181424Y1015444D02*
Y1005044D01*
G01Y1019604D02*
X-1181814Y1019864D01*
Y1020384D01*
X-1181424Y1020644D01*
X-1181034Y1020384D01*
Y1019864D01*
X-1181424Y1019604D01*
G01X-1163524Y1020644D02*
Y1005044D01*
G01X-1166254Y1015444D02*
X-1160794D01*
G01X-1149719Y1000364D02*
X-1148549Y999844D01*
X-1146989Y1000364D01*
X-1146014Y1001404D01*
X-1145234Y1002704D01*
X-1144064Y1006864D01*
X-1141529Y1015444D01*
G01X-1147769D02*
X-1144064Y1006864D01*
G01X-1113334Y1005044D02*
Y1020644D01*
G01Y1012844D02*
X-1112359Y1014404D01*
X-1111189Y1015184D01*
X-1110019Y1015444D01*
X-1108264Y1014924D01*
X-1107094Y1013884D01*
X-1106314Y1012064D01*
Y1009984D01*
X-1106704Y1007904D01*
X-1107484Y1006344D01*
X-1108849Y1005304D01*
X-1110019Y1005044D01*
X-1111189Y1005304D01*
X-1112359Y1006084D01*
X-1113334Y1007384D01*
G01X-1094849Y1012064D02*
X-1088609D01*
X-1089194Y1013884D01*
X-1090169Y1014924D01*
X-1091534Y1015444D01*
X-1092899Y1015184D01*
X-1094069Y1014404D01*
X-1094849Y1012584D01*
X-1095239Y1011024D01*
Y1009464D01*
X-1094849Y1007904D01*
X-1093874Y1006344D01*
X-1092704Y1005304D01*
X-1091339Y1005044D01*
X-1089974Y1005564D01*
X-1088609Y1007124D01*
G01X-1074024Y1020644D02*
Y1005044D01*
G01X-1076754Y1015444D02*
X-1071294D01*
G01X-1060999D02*
X-1058659Y1005044D01*
X-1056124Y1015444D01*
X-1053589Y1005044D01*
X-1051249Y1015444D01*
G01X-1041149Y1012064D02*
X-1034909D01*
X-1035494Y1013884D01*
X-1036469Y1014924D01*
X-1037834Y1015444D01*
X-1039199Y1015184D01*
X-1040369Y1014404D01*
X-1041149Y1012584D01*
X-1041539Y1011024D01*
Y1009464D01*
X-1041149Y1007904D01*
X-1040174Y1006344D01*
X-1039004Y1005304D01*
X-1037639Y1005044D01*
X-1036274Y1005564D01*
X-1034909Y1007124D01*
G01X-1023249Y1012064D02*
X-1017009D01*
X-1017594Y1013884D01*
X-1018569Y1014924D01*
X-1019934Y1015444D01*
X-1021299Y1015184D01*
X-1022469Y1014404D01*
X-1023249Y1012584D01*
X-1023639Y1011024D01*
Y1009464D01*
X-1023249Y1007904D01*
X-1022274Y1006344D01*
X-1021104Y1005304D01*
X-1019739Y1005044D01*
X-1018374Y1005564D01*
X-1017009Y1007124D01*
G01X-1005739Y1005044D02*
Y1015444D01*
G01Y1012844D02*
X-1004959Y1014144D01*
X-1003789Y1015184D01*
X-1002229Y1015444D01*
X-1000864Y1015184D01*
X-999694Y1014144D01*
X-999109Y1012324D01*
Y1005044D01*
G01X-963114Y999844D02*
Y1015444D01*
G01Y1013104D02*
X-964089Y1014404D01*
X-965259Y1015184D01*
X-966624Y1015444D01*
X-967794Y1015184D01*
X-969159Y1013884D01*
X-969939Y1012064D01*
X-970134Y1010244D01*
X-969939Y1008424D01*
X-969159Y1006604D01*
X-967794Y1005304D01*
X-966624Y1005044D01*
X-965259Y1005304D01*
X-964089Y1006084D01*
X-963114Y1007384D01*
G01X-952039Y1015444D02*
Y1008164D01*
X-951259Y1006344D01*
X-950089Y1005304D01*
X-948724Y1005044D01*
X-947359Y1005304D01*
X-946189Y1006344D01*
X-945409Y1008164D01*
G01Y1005044D02*
Y1015444D01*
G01X-927314Y1005044D02*
Y1015444D01*
G01Y1013624D02*
X-928094Y1014664D01*
X-929264Y1015184D01*
X-930629Y1015444D01*
X-931994Y1014924D01*
X-933164Y1013884D01*
X-933944Y1012324D01*
X-934334Y1010244D01*
X-933944Y1008164D01*
X-933164Y1006604D01*
X-931994Y1005564D01*
X-930629Y1005044D01*
X-929264Y1005304D01*
X-928094Y1006084D01*
X-927314Y1007124D01*
G01X-912924Y1005044D02*
Y1020644D01*
G01X-895024Y1015444D02*
Y1005044D01*
G01Y1019604D02*
X-895414Y1019864D01*
Y1020384D01*
X-895024Y1020644D01*
X-894634Y1020384D01*
Y1019864D01*
X-895024Y1019604D01*
G01X-877124Y1020644D02*
Y1005044D01*
G01X-879854Y1015444D02*
X-874394D01*
G01X-863319Y1000364D02*
X-862149Y999844D01*
X-860589Y1000364D01*
X-859614Y1001404D01*
X-858834Y1002704D01*
X-857664Y1006864D01*
X-855129Y1015444D01*
G01X-861369D02*
X-857664Y1006864D01*
G01X-820304Y1014144D02*
X-821669Y1015184D01*
X-822839Y1015444D01*
X-824399Y1014924D01*
X-825569Y1013884D01*
X-826349Y1012064D01*
X-826544Y1010244D01*
X-826349Y1008424D01*
X-825569Y1006864D01*
X-824399Y1005564D01*
X-822839Y1005044D01*
X-821474Y1005564D01*
X-820304Y1006604D01*
G01X-805524Y1005044D02*
X-806694Y1005304D01*
X-807864Y1006344D01*
X-808644Y1008164D01*
X-809034Y1010244D01*
X-808644Y1012324D01*
X-807864Y1014144D01*
X-806694Y1015184D01*
X-805524Y1015444D01*
X-804354Y1015184D01*
X-803184Y1014144D01*
X-802404Y1012324D01*
X-802209Y1010244D01*
X-802404Y1008164D01*
X-803184Y1006344D01*
X-804354Y1005304D01*
X-805524Y1005044D01*
G01X-790939D02*
Y1015444D01*
G01Y1012844D02*
X-790159Y1014144D01*
X-788989Y1015184D01*
X-787429Y1015444D01*
X-786064Y1015184D01*
X-784894Y1014144D01*
X-784309Y1012324D01*
Y1005044D01*
G01X-770894D02*
Y1018304D01*
X-770504Y1019604D01*
X-769724Y1020384D01*
X-768554Y1020644D01*
X-767384Y1020124D01*
X-766799Y1018824D01*
G01X-769139Y1014404D02*
X-773039D01*
G01X-751824Y1005044D02*
X-752994Y1005304D01*
X-754164Y1006344D01*
X-754944Y1008164D01*
X-755334Y1010244D01*
X-754944Y1012324D01*
X-754164Y1014144D01*
X-752994Y1015184D01*
X-751824Y1015444D01*
X-750654Y1015184D01*
X-749484Y1014144D01*
X-748704Y1012324D01*
X-748509Y1010244D01*
X-748704Y1008164D01*
X-749484Y1006344D01*
X-750654Y1005304D01*
X-751824Y1005044D01*
G01X-736654D02*
Y1015444D01*
G01Y1013364D02*
X-735679Y1014404D01*
X-734704Y1015184D01*
X-733339Y1015444D01*
X-732364Y1015184D01*
X-731194Y1014404D01*
G01X-721874Y1005044D02*
Y1015444D01*
G01Y1012584D02*
X-721289Y1013884D01*
X-720314Y1014924D01*
X-718949Y1015444D01*
X-717584Y1014924D01*
X-716609Y1013884D01*
X-716024Y1012584D01*
Y1005044D01*
G01Y1012584D02*
X-715439Y1013884D01*
X-714464Y1014924D01*
X-713099Y1015444D01*
X-711734Y1014924D01*
X-710759Y1013884D01*
X-710174Y1012324D01*
Y1005044D01*
G01X-694614D02*
Y1015444D01*
G01Y1013624D02*
X-695394Y1014664D01*
X-696564Y1015184D01*
X-697929Y1015444D01*
X-699294Y1014924D01*
X-700464Y1013884D01*
X-701244Y1012324D01*
X-701634Y1010244D01*
X-701244Y1008164D01*
X-700464Y1006604D01*
X-699294Y1005564D01*
X-697929Y1005044D01*
X-696564Y1005304D01*
X-695394Y1006084D01*
X-694614Y1007124D01*
G01X-683539Y1005044D02*
Y1015444D01*
G01Y1012844D02*
X-682759Y1014144D01*
X-681589Y1015184D01*
X-680029Y1015444D01*
X-678664Y1015184D01*
X-677494Y1014144D01*
X-676909Y1012324D01*
Y1005044D01*
G01X-659204Y1014144D02*
X-660569Y1015184D01*
X-661739Y1015444D01*
X-663299Y1014924D01*
X-664469Y1013884D01*
X-665249Y1012064D01*
X-665444Y1010244D01*
X-665249Y1008424D01*
X-664469Y1006864D01*
X-663299Y1005564D01*
X-661739Y1005044D01*
X-660374Y1005564D01*
X-659204Y1006604D01*
G01X-647349Y1012064D02*
X-641109D01*
X-641694Y1013884D01*
X-642669Y1014924D01*
X-644034Y1015444D01*
X-645399Y1015184D01*
X-646569Y1014404D01*
X-647349Y1012584D01*
X-647739Y1011024D01*
Y1009464D01*
X-647349Y1007904D01*
X-646374Y1006344D01*
X-645204Y1005304D01*
X-643839Y1005044D01*
X-642474Y1005564D01*
X-641109Y1007124D01*
G01X-608624Y1020644D02*
Y1005044D01*
G01X-611354Y1015444D02*
X-605894D01*
G01X-593649Y1012064D02*
X-587409D01*
X-587994Y1013884D01*
X-588969Y1014924D01*
X-590334Y1015444D01*
X-591699Y1015184D01*
X-592869Y1014404D01*
X-593649Y1012584D01*
X-594039Y1011024D01*
Y1009464D01*
X-593649Y1007904D01*
X-592674Y1006344D01*
X-591504Y1005304D01*
X-590139Y1005044D01*
X-588774Y1005564D01*
X-587409Y1007124D01*
G01X-575749Y1006864D02*
X-574774Y1005824D01*
X-573409Y1005044D01*
X-572239D01*
X-571069Y1005564D01*
X-570289Y1006344D01*
X-569899Y1007384D01*
X-570094Y1008944D01*
X-570874Y1009724D01*
X-574384Y1011284D01*
X-575164Y1013104D01*
X-574774Y1014404D01*
X-573994Y1015184D01*
X-572824Y1015444D01*
X-571654Y1015184D01*
X-570484Y1014404D01*
G01X-554924Y1020644D02*
Y1005044D01*
G01X-557654Y1015444D02*
X-552194D01*
G01X-2019214Y1039044D02*
Y1049444D01*
G01Y1047624D02*
X-2019994Y1048664D01*
X-2021164Y1049184D01*
X-2022529Y1049444D01*
X-2023894Y1048924D01*
X-2025064Y1047884D01*
X-2025844Y1046324D01*
X-2026234Y1044244D01*
X-2025844Y1042164D01*
X-2025064Y1040604D01*
X-2023894Y1039564D01*
X-2022529Y1039044D01*
X-2021164Y1039304D01*
X-2019994Y1040084D01*
X-2019214Y1041124D01*
G01X-2008139Y1039044D02*
Y1049444D01*
G01Y1046844D02*
X-2007359Y1048144D01*
X-2006189Y1049184D01*
X-2004629Y1049444D01*
X-2003264Y1049184D01*
X-2002094Y1048144D01*
X-2001509Y1046324D01*
Y1039044D01*
G01X-1983414Y1054644D02*
Y1039044D01*
G01Y1041384D02*
X-1984194Y1040084D01*
X-1985364Y1039304D01*
X-1986729Y1039044D01*
X-1988289Y1039564D01*
X-1989459Y1040864D01*
X-1990239Y1042424D01*
X-1990434Y1044244D01*
X-1990239Y1046064D01*
X-1989459Y1047624D01*
X-1988289Y1048924D01*
X-1986729Y1049444D01*
X-1985364Y1049184D01*
X-1984389Y1048664D01*
X-1983414Y1047624D01*
G01X-1956974Y1039044D02*
Y1049444D01*
G01Y1046584D02*
X-1956389Y1047884D01*
X-1955414Y1048924D01*
X-1954049Y1049444D01*
X-1952684Y1048924D01*
X-1951709Y1047884D01*
X-1951124Y1046584D01*
Y1039044D01*
G01Y1046584D02*
X-1950539Y1047884D01*
X-1949564Y1048924D01*
X-1948199Y1049444D01*
X-1946834Y1048924D01*
X-1945859Y1047884D01*
X-1945274Y1046324D01*
Y1039044D01*
G01X-1936539Y1049444D02*
Y1042164D01*
X-1935759Y1040344D01*
X-1934589Y1039304D01*
X-1933224Y1039044D01*
X-1931859Y1039304D01*
X-1930689Y1040344D01*
X-1929909Y1042164D01*
G01Y1039044D02*
Y1049444D01*
G01X-1918249Y1040864D02*
X-1917274Y1039824D01*
X-1915909Y1039044D01*
X-1914739D01*
X-1913569Y1039564D01*
X-1912789Y1040344D01*
X-1912399Y1041384D01*
X-1912594Y1042944D01*
X-1913374Y1043724D01*
X-1916884Y1045284D01*
X-1917664Y1047104D01*
X-1917274Y1048404D01*
X-1916494Y1049184D01*
X-1915324Y1049444D01*
X-1914154Y1049184D01*
X-1912984Y1048404D01*
G01X-1897424Y1054644D02*
Y1039044D01*
G01X-1900154Y1049444D02*
X-1894694D01*
G01X-1864939Y1039044D02*
Y1049444D01*
G01Y1046844D02*
X-1864159Y1048144D01*
X-1862989Y1049184D01*
X-1861429Y1049444D01*
X-1860064Y1049184D01*
X-1858894Y1048144D01*
X-1858309Y1046324D01*
Y1039044D01*
G01X-1843724D02*
X-1844894Y1039304D01*
X-1846064Y1040344D01*
X-1846844Y1042164D01*
X-1847234Y1044244D01*
X-1846844Y1046324D01*
X-1846064Y1048144D01*
X-1844894Y1049184D01*
X-1843724Y1049444D01*
X-1842554Y1049184D01*
X-1841384Y1048144D01*
X-1840604Y1046324D01*
X-1840409Y1044244D01*
X-1840604Y1042164D01*
X-1841384Y1040344D01*
X-1842554Y1039304D01*
X-1843724Y1039044D01*
G01X-1825824Y1054644D02*
Y1039044D01*
G01X-1828554Y1049444D02*
X-1823094D01*
G01X-1792949Y1046064D02*
X-1786709D01*
X-1787294Y1047884D01*
X-1788269Y1048924D01*
X-1789634Y1049444D01*
X-1790999Y1049184D01*
X-1792169Y1048404D01*
X-1792949Y1046584D01*
X-1793339Y1045024D01*
Y1043464D01*
X-1792949Y1041904D01*
X-1791974Y1040344D01*
X-1790804Y1039304D01*
X-1789439Y1039044D01*
X-1788074Y1039564D01*
X-1786709Y1041124D01*
G01X-1775439Y1039044D02*
Y1049444D01*
G01Y1046844D02*
X-1774659Y1048144D01*
X-1773489Y1049184D01*
X-1771929Y1049444D01*
X-1770564Y1049184D01*
X-1769394Y1048144D01*
X-1768809Y1046324D01*
Y1039044D01*
G01X-1751104Y1048144D02*
X-1752469Y1049184D01*
X-1753639Y1049444D01*
X-1755199Y1048924D01*
X-1756369Y1047884D01*
X-1757149Y1046064D01*
X-1757344Y1044244D01*
X-1757149Y1042424D01*
X-1756369Y1040864D01*
X-1755199Y1039564D01*
X-1753639Y1039044D01*
X-1752274Y1039564D01*
X-1751104Y1040604D01*
G01X-1739054Y1039044D02*
Y1049444D01*
G01Y1047364D02*
X-1738079Y1048404D01*
X-1737104Y1049184D01*
X-1735739Y1049444D01*
X-1734764Y1049184D01*
X-1733594Y1048404D01*
G01X-1718424Y1039044D02*
X-1719594Y1039304D01*
X-1720764Y1040344D01*
X-1721544Y1042164D01*
X-1721934Y1044244D01*
X-1721544Y1046324D01*
X-1720764Y1048144D01*
X-1719594Y1049184D01*
X-1718424Y1049444D01*
X-1717254Y1049184D01*
X-1716084Y1048144D01*
X-1715304Y1046324D01*
X-1715109Y1044244D01*
X-1715304Y1042164D01*
X-1716084Y1040344D01*
X-1717254Y1039304D01*
X-1718424Y1039044D01*
G01X-1697014D02*
Y1049444D01*
G01Y1047624D02*
X-1697794Y1048664D01*
X-1698964Y1049184D01*
X-1700329Y1049444D01*
X-1701694Y1048924D01*
X-1702864Y1047884D01*
X-1703644Y1046324D01*
X-1704034Y1044244D01*
X-1703644Y1042164D01*
X-1702864Y1040604D01*
X-1701694Y1039564D01*
X-1700329Y1039044D01*
X-1698964Y1039304D01*
X-1697794Y1040084D01*
X-1697014Y1041124D01*
G01X-1679504Y1048144D02*
X-1680869Y1049184D01*
X-1682039Y1049444D01*
X-1683599Y1048924D01*
X-1684769Y1047884D01*
X-1685549Y1046064D01*
X-1685744Y1044244D01*
X-1685549Y1042424D01*
X-1684769Y1040864D01*
X-1683599Y1039564D01*
X-1682039Y1039044D01*
X-1680674Y1039564D01*
X-1679504Y1040604D01*
G01X-1668039Y1039044D02*
Y1054644D01*
G01Y1047104D02*
X-1667064Y1048404D01*
X-1666089Y1049184D01*
X-1664529Y1049444D01*
X-1663359Y1049184D01*
X-1661994Y1048144D01*
X-1661409Y1046584D01*
Y1039044D01*
G01X-1628924D02*
X-1630094Y1039304D01*
X-1631264Y1040344D01*
X-1632044Y1042164D01*
X-1632434Y1044244D01*
X-1632044Y1046324D01*
X-1631264Y1048144D01*
X-1630094Y1049184D01*
X-1628924Y1049444D01*
X-1627754Y1049184D01*
X-1626584Y1048144D01*
X-1625804Y1046324D01*
X-1625609Y1044244D01*
X-1625804Y1042164D01*
X-1626584Y1040344D01*
X-1627754Y1039304D01*
X-1628924Y1039044D01*
G01X-1614339D02*
Y1049444D01*
G01Y1046844D02*
X-1613559Y1048144D01*
X-1612389Y1049184D01*
X-1610829Y1049444D01*
X-1609464Y1049184D01*
X-1608294Y1048144D01*
X-1607709Y1046324D01*
Y1039044D01*
G01X-1593124Y1054644D02*
Y1039044D01*
G01X-1595854Y1049444D02*
X-1590394D01*
G01X-1575224Y1039044D02*
X-1576394Y1039304D01*
X-1577564Y1040344D01*
X-1578344Y1042164D01*
X-1578734Y1044244D01*
X-1578344Y1046324D01*
X-1577564Y1048144D01*
X-1576394Y1049184D01*
X-1575224Y1049444D01*
X-1574054Y1049184D01*
X-1572884Y1048144D01*
X-1572104Y1046324D01*
X-1571909Y1044244D01*
X-1572104Y1042164D01*
X-1572884Y1040344D01*
X-1574054Y1039304D01*
X-1575224Y1039044D01*
G01X-1535914D02*
Y1049444D01*
G01Y1047624D02*
X-1536694Y1048664D01*
X-1537864Y1049184D01*
X-1539229Y1049444D01*
X-1540594Y1048924D01*
X-1541764Y1047884D01*
X-1542544Y1046324D01*
X-1542934Y1044244D01*
X-1542544Y1042164D01*
X-1541764Y1040604D01*
X-1540594Y1039564D01*
X-1539229Y1039044D01*
X-1537864Y1039304D01*
X-1536694Y1040084D01*
X-1535914Y1041124D01*
G01X-1524839Y1039044D02*
Y1049444D01*
G01Y1046844D02*
X-1524059Y1048144D01*
X-1522889Y1049184D01*
X-1521329Y1049444D01*
X-1519964Y1049184D01*
X-1518794Y1048144D01*
X-1518209Y1046324D01*
Y1039044D01*
G01X-1507719Y1034364D02*
X-1506549Y1033844D01*
X-1504989Y1034364D01*
X-1504014Y1035404D01*
X-1503234Y1036704D01*
X-1502064Y1040864D01*
X-1499529Y1049444D01*
G01X-1505769D02*
X-1502064Y1040864D01*
G01X-1473674Y1039044D02*
Y1049444D01*
G01Y1046584D02*
X-1473089Y1047884D01*
X-1472114Y1048924D01*
X-1470749Y1049444D01*
X-1469384Y1048924D01*
X-1468409Y1047884D01*
X-1467824Y1046584D01*
Y1039044D01*
G01Y1046584D02*
X-1467239Y1047884D01*
X-1466264Y1048924D01*
X-1464899Y1049444D01*
X-1463534Y1048924D01*
X-1462559Y1047884D01*
X-1461974Y1046324D01*
Y1039044D01*
G01X-1452849Y1046064D02*
X-1446609D01*
X-1447194Y1047884D01*
X-1448169Y1048924D01*
X-1449534Y1049444D01*
X-1450899Y1049184D01*
X-1452069Y1048404D01*
X-1452849Y1046584D01*
X-1453239Y1045024D01*
Y1043464D01*
X-1452849Y1041904D01*
X-1451874Y1040344D01*
X-1450704Y1039304D01*
X-1449339Y1039044D01*
X-1447974Y1039564D01*
X-1446609Y1041124D01*
G01X-1432024Y1054644D02*
Y1039044D01*
G01X-1434754Y1049444D02*
X-1429294D01*
G01X-1410614Y1039044D02*
Y1049444D01*
G01Y1047624D02*
X-1411394Y1048664D01*
X-1412564Y1049184D01*
X-1413929Y1049444D01*
X-1415294Y1048924D01*
X-1416464Y1047884D01*
X-1417244Y1046324D01*
X-1417634Y1044244D01*
X-1417244Y1042164D01*
X-1416464Y1040604D01*
X-1415294Y1039564D01*
X-1413929Y1039044D01*
X-1412564Y1039304D01*
X-1411394Y1040084D01*
X-1410614Y1041124D01*
G01X-1396224Y1039044D02*
Y1054644D01*
G01X-1378324Y1039044D02*
Y1054644D01*
G01X-1360424Y1049444D02*
Y1039044D01*
G01Y1053604D02*
X-1360814Y1053864D01*
Y1054384D01*
X-1360424Y1054644D01*
X-1360034Y1054384D01*
Y1053864D01*
X-1360424Y1053604D01*
G01X-1339404Y1048144D02*
X-1340769Y1049184D01*
X-1341939Y1049444D01*
X-1343499Y1048924D01*
X-1344669Y1047884D01*
X-1345449Y1046064D01*
X-1345644Y1044244D01*
X-1345449Y1042424D01*
X-1344669Y1040864D01*
X-1343499Y1039564D01*
X-1341939Y1039044D01*
X-1340574Y1039564D01*
X-1339404Y1040604D01*
G01X-1309649Y1040864D02*
X-1308674Y1039824D01*
X-1307309Y1039044D01*
X-1306139D01*
X-1304969Y1039564D01*
X-1304189Y1040344D01*
X-1303799Y1041384D01*
X-1303994Y1042944D01*
X-1304774Y1043724D01*
X-1308284Y1045284D01*
X-1309064Y1047104D01*
X-1308674Y1048404D01*
X-1307894Y1049184D01*
X-1306724Y1049444D01*
X-1305554Y1049184D01*
X-1304384Y1048404D01*
G01X-1292139Y1049444D02*
Y1042164D01*
X-1291359Y1040344D01*
X-1290189Y1039304D01*
X-1288824Y1039044D01*
X-1287459Y1039304D01*
X-1286289Y1040344D01*
X-1285509Y1042164D01*
G01Y1039044D02*
Y1049444D01*
G01X-1273654Y1039044D02*
Y1049444D01*
G01Y1047364D02*
X-1272679Y1048404D01*
X-1271704Y1049184D01*
X-1270339Y1049444D01*
X-1269364Y1049184D01*
X-1268194Y1048404D01*
G01X-1254194Y1039044D02*
Y1052304D01*
X-1253804Y1053604D01*
X-1253024Y1054384D01*
X-1251854Y1054644D01*
X-1250684Y1054124D01*
X-1250099Y1052824D01*
G01X-1252439Y1048404D02*
X-1256339D01*
G01X-1231614Y1039044D02*
Y1049444D01*
G01Y1047624D02*
X-1232394Y1048664D01*
X-1233564Y1049184D01*
X-1234929Y1049444D01*
X-1236294Y1048924D01*
X-1237464Y1047884D01*
X-1238244Y1046324D01*
X-1238634Y1044244D01*
X-1238244Y1042164D01*
X-1237464Y1040604D01*
X-1236294Y1039564D01*
X-1234929Y1039044D01*
X-1233564Y1039304D01*
X-1232394Y1040084D01*
X-1231614Y1041124D01*
G01X-1214104Y1048144D02*
X-1215469Y1049184D01*
X-1216639Y1049444D01*
X-1218199Y1048924D01*
X-1219369Y1047884D01*
X-1220149Y1046064D01*
X-1220344Y1044244D01*
X-1220149Y1042424D01*
X-1219369Y1040864D01*
X-1218199Y1039564D01*
X-1216639Y1039044D01*
X-1215274Y1039564D01*
X-1214104Y1040604D01*
G01X-1202249Y1046064D02*
X-1196009D01*
X-1196594Y1047884D01*
X-1197569Y1048924D01*
X-1198934Y1049444D01*
X-1200299Y1049184D01*
X-1201469Y1048404D01*
X-1202249Y1046584D01*
X-1202639Y1045024D01*
Y1043464D01*
X-1202249Y1041904D01*
X-1201274Y1040344D01*
X-1200104Y1039304D01*
X-1198739Y1039044D01*
X-1197374Y1039564D01*
X-1196009Y1041124D01*
G01X-1181814Y1036184D02*
X-1181034Y1039564D01*
G01X-1145624Y1054644D02*
Y1039044D01*
G01X-1148354Y1049444D02*
X-1142894D01*
G01X-1127724Y1039044D02*
X-1128894Y1039304D01*
X-1130064Y1040344D01*
X-1130844Y1042164D01*
X-1131234Y1044244D01*
X-1130844Y1046324D01*
X-1130064Y1048144D01*
X-1128894Y1049184D01*
X-1127724Y1049444D01*
X-1126554Y1049184D01*
X-1125384Y1048144D01*
X-1124604Y1046324D01*
X-1124409Y1044244D01*
X-1124604Y1042164D01*
X-1125384Y1040344D01*
X-1126554Y1039304D01*
X-1127724Y1039044D01*
G01X-1109824D02*
X-1110994Y1039304D01*
X-1112164Y1040344D01*
X-1112944Y1042164D01*
X-1113334Y1044244D01*
X-1112944Y1046324D01*
X-1112164Y1048144D01*
X-1110994Y1049184D01*
X-1109824Y1049444D01*
X-1108654Y1049184D01*
X-1107484Y1048144D01*
X-1106704Y1046324D01*
X-1106509Y1044244D01*
X-1106704Y1042164D01*
X-1107484Y1040344D01*
X-1108654Y1039304D01*
X-1109824Y1039044D01*
G01X-1091924D02*
Y1054644D01*
G01X-1074024Y1049444D02*
Y1039044D01*
G01Y1053604D02*
X-1074414Y1053864D01*
Y1054384D01*
X-1074024Y1054644D01*
X-1073634Y1054384D01*
Y1053864D01*
X-1074024Y1053604D01*
G01X-1059439Y1039044D02*
Y1049444D01*
G01Y1046844D02*
X-1058659Y1048144D01*
X-1057489Y1049184D01*
X-1055929Y1049444D01*
X-1054564Y1049184D01*
X-1053394Y1048144D01*
X-1052809Y1046324D01*
Y1039044D01*
G01X-1040954Y1035144D02*
X-1039589Y1034104D01*
X-1038029Y1033844D01*
X-1036664Y1034104D01*
X-1035494Y1035404D01*
X-1034714Y1037224D01*
Y1049444D01*
G01Y1047364D02*
X-1035494Y1048404D01*
X-1036664Y1049184D01*
X-1038029Y1049444D01*
X-1039589Y1048924D01*
X-1040564Y1047884D01*
X-1041344Y1046064D01*
X-1041734Y1044244D01*
X-1041539Y1042684D01*
X-1040759Y1040864D01*
X-1039589Y1039564D01*
X-1038029Y1039044D01*
X-1036859Y1039304D01*
X-1035494Y1040344D01*
X-1034714Y1041384D01*
G01X-1005739Y1039044D02*
Y1054644D01*
G01Y1047104D02*
X-1004764Y1048404D01*
X-1003789Y1049184D01*
X-1002229Y1049444D01*
X-1001059Y1049184D01*
X-999694Y1048144D01*
X-999109Y1046584D01*
Y1039044D01*
G01X-984524D02*
X-985694Y1039304D01*
X-986864Y1040344D01*
X-987644Y1042164D01*
X-988034Y1044244D01*
X-987644Y1046324D01*
X-986864Y1048144D01*
X-985694Y1049184D01*
X-984524Y1049444D01*
X-983354Y1049184D01*
X-982184Y1048144D01*
X-981404Y1046324D01*
X-981209Y1044244D01*
X-981404Y1042164D01*
X-982184Y1040344D01*
X-983354Y1039304D01*
X-984524Y1039044D01*
G01X-966624D02*
Y1054644D01*
G01X-951649Y1046064D02*
X-945409D01*
X-945994Y1047884D01*
X-946969Y1048924D01*
X-948334Y1049444D01*
X-949699Y1049184D01*
X-950869Y1048404D01*
X-951649Y1046584D01*
X-952039Y1045024D01*
Y1043464D01*
X-951649Y1041904D01*
X-950674Y1040344D01*
X-949504Y1039304D01*
X-948139Y1039044D01*
X-946774Y1039564D01*
X-945409Y1041124D01*
G01X-933749Y1040864D02*
X-932774Y1039824D01*
X-931409Y1039044D01*
X-930239D01*
X-929069Y1039564D01*
X-928289Y1040344D01*
X-927899Y1041384D01*
X-928094Y1042944D01*
X-928874Y1043724D01*
X-932384Y1045284D01*
X-933164Y1047104D01*
X-932774Y1048404D01*
X-931994Y1049184D01*
X-930824Y1049444D01*
X-929654Y1049184D01*
X-928484Y1048404D01*
G01X-913314Y1036184D02*
X-912534Y1039564D01*
G01X-877124Y1039044D02*
X-878294Y1039304D01*
X-879464Y1040344D01*
X-880244Y1042164D01*
X-880634Y1044244D01*
X-880244Y1046324D01*
X-879464Y1048144D01*
X-878294Y1049184D01*
X-877124Y1049444D01*
X-875954Y1049184D01*
X-874784Y1048144D01*
X-874004Y1046324D01*
X-873809Y1044244D01*
X-874004Y1042164D01*
X-874784Y1040344D01*
X-875954Y1039304D01*
X-877124Y1039044D01*
G01X-861954D02*
Y1049444D01*
G01Y1047364D02*
X-860979Y1048404D01*
X-860004Y1049184D01*
X-858639Y1049444D01*
X-857664Y1049184D01*
X-856494Y1048404D01*
G01X-824594Y1039044D02*
Y1052304D01*
X-824204Y1053604D01*
X-823424Y1054384D01*
X-822254Y1054644D01*
X-821084Y1054124D01*
X-820499Y1052824D01*
G01X-822839Y1048404D02*
X-826739D01*
G01X-805524Y1049444D02*
Y1039044D01*
G01Y1053604D02*
X-805914Y1053864D01*
Y1054384D01*
X-805524Y1054644D01*
X-805134Y1054384D01*
Y1053864D01*
X-805524Y1053604D01*
G01X-784114Y1054644D02*
Y1039044D01*
G01Y1041384D02*
X-784894Y1040084D01*
X-786064Y1039304D01*
X-787429Y1039044D01*
X-788989Y1039564D01*
X-790159Y1040864D01*
X-790939Y1042424D01*
X-791134Y1044244D01*
X-790939Y1046064D01*
X-790159Y1047624D01*
X-788989Y1048924D01*
X-787429Y1049444D01*
X-786064Y1049184D01*
X-785089Y1048664D01*
X-784114Y1047624D01*
G01X-773039Y1049444D02*
Y1042164D01*
X-772259Y1040344D01*
X-771089Y1039304D01*
X-769724Y1039044D01*
X-768359Y1039304D01*
X-767189Y1040344D01*
X-766409Y1042164D01*
G01Y1039044D02*
Y1049444D01*
G01X-748704Y1048144D02*
X-750069Y1049184D01*
X-751239Y1049444D01*
X-752799Y1048924D01*
X-753969Y1047884D01*
X-754749Y1046064D01*
X-754944Y1044244D01*
X-754749Y1042424D01*
X-753969Y1040864D01*
X-752799Y1039564D01*
X-751239Y1039044D01*
X-749874Y1039564D01*
X-748704Y1040604D01*
G01X-733924Y1049444D02*
Y1039044D01*
G01Y1053604D02*
X-734314Y1053864D01*
Y1054384D01*
X-733924Y1054644D01*
X-733534Y1054384D01*
Y1053864D01*
X-733924Y1053604D01*
G01X-712514Y1039044D02*
Y1049444D01*
G01Y1047624D02*
X-713294Y1048664D01*
X-714464Y1049184D01*
X-715829Y1049444D01*
X-717194Y1048924D01*
X-718364Y1047884D01*
X-719144Y1046324D01*
X-719534Y1044244D01*
X-719144Y1042164D01*
X-718364Y1040604D01*
X-717194Y1039564D01*
X-715829Y1039044D01*
X-714464Y1039304D01*
X-713294Y1040084D01*
X-712514Y1041124D01*
G01X-698124Y1039044D02*
Y1054644D01*
G01X-659204Y1048144D02*
X-660569Y1049184D01*
X-661739Y1049444D01*
X-663299Y1048924D01*
X-664469Y1047884D01*
X-665249Y1046064D01*
X-665444Y1044244D01*
X-665249Y1042424D01*
X-664469Y1040864D01*
X-663299Y1039564D01*
X-661739Y1039044D01*
X-660374Y1039564D01*
X-659204Y1040604D01*
G01X-644424Y1039044D02*
Y1054644D01*
G01X-629449Y1046064D02*
X-623209D01*
X-623794Y1047884D01*
X-624769Y1048924D01*
X-626134Y1049444D01*
X-627499Y1049184D01*
X-628669Y1048404D01*
X-629449Y1046584D01*
X-629839Y1045024D01*
Y1043464D01*
X-629449Y1041904D01*
X-628474Y1040344D01*
X-627304Y1039304D01*
X-625939Y1039044D01*
X-624574Y1039564D01*
X-623209Y1041124D01*
G01X-605114Y1039044D02*
Y1049444D01*
G01Y1047624D02*
X-605894Y1048664D01*
X-607064Y1049184D01*
X-608429Y1049444D01*
X-609794Y1048924D01*
X-610964Y1047884D01*
X-611744Y1046324D01*
X-612134Y1044244D01*
X-611744Y1042164D01*
X-610964Y1040604D01*
X-609794Y1039564D01*
X-608429Y1039044D01*
X-607064Y1039304D01*
X-605894Y1040084D01*
X-605114Y1041124D01*
G01X-593454Y1039044D02*
Y1049444D01*
G01Y1047364D02*
X-592479Y1048404D01*
X-591504Y1049184D01*
X-590139Y1049444D01*
X-589164Y1049184D01*
X-587994Y1048404D01*
G01X-569314Y1039044D02*
Y1049444D01*
G01Y1047624D02*
X-570094Y1048664D01*
X-571264Y1049184D01*
X-572629Y1049444D01*
X-573994Y1048924D01*
X-575164Y1047884D01*
X-575944Y1046324D01*
X-576334Y1044244D01*
X-575944Y1042164D01*
X-575164Y1040604D01*
X-573994Y1039564D01*
X-572629Y1039044D01*
X-571264Y1039304D01*
X-570094Y1040084D01*
X-569314Y1041124D01*
G01X-558239Y1039044D02*
Y1049444D01*
G01Y1046844D02*
X-557459Y1048144D01*
X-556289Y1049184D01*
X-554729Y1049444D01*
X-553364Y1049184D01*
X-552194Y1048144D01*
X-551609Y1046324D01*
Y1039044D01*
G01X-533904Y1048144D02*
X-535269Y1049184D01*
X-536439Y1049444D01*
X-537999Y1048924D01*
X-539169Y1047884D01*
X-539949Y1046064D01*
X-540144Y1044244D01*
X-539949Y1042424D01*
X-539169Y1040864D01*
X-537999Y1039564D01*
X-536439Y1039044D01*
X-535074Y1039564D01*
X-533904Y1040604D01*
G01X-522049Y1046064D02*
X-515809D01*
X-516394Y1047884D01*
X-517369Y1048924D01*
X-518734Y1049444D01*
X-520099Y1049184D01*
X-521269Y1048404D01*
X-522049Y1046584D01*
X-522439Y1045024D01*
Y1043464D01*
X-522049Y1041904D01*
X-521074Y1040344D01*
X-519904Y1039304D01*
X-518539Y1039044D01*
X-517174Y1039564D01*
X-515809Y1041124D01*
G01X-504149Y1040864D02*
X-503174Y1039824D01*
X-501809Y1039044D01*
X-500639D01*
X-499469Y1039564D01*
X-498689Y1040344D01*
X-498299Y1041384D01*
X-498494Y1042944D01*
X-499274Y1043724D01*
X-502784Y1045284D01*
X-503564Y1047104D01*
X-503174Y1048404D01*
X-502394Y1049184D01*
X-501224Y1049444D01*
X-500054Y1049184D01*
X-498884Y1048404D01*
G01X-483324Y1038524D02*
X-483714Y1038784D01*
Y1039304D01*
X-483324Y1039564D01*
X-482934Y1039304D01*
Y1038784D01*
X-483324Y1038524D01*
G01X-2022724Y1088644D02*
Y1073044D01*
G01X-2027209Y1088644D02*
X-2018239D01*
G01X-2008139Y1073044D02*
Y1088644D01*
G01Y1081104D02*
X-2007164Y1082404D01*
X-2006189Y1083184D01*
X-2004629Y1083444D01*
X-2003459Y1083184D01*
X-2002094Y1082144D01*
X-2001509Y1080584D01*
Y1073044D01*
G01X-1986924Y1083444D02*
Y1073044D01*
G01Y1087604D02*
X-1987314Y1087864D01*
Y1088384D01*
X-1986924Y1088644D01*
X-1986534Y1088384D01*
Y1087864D01*
X-1986924Y1087604D01*
G01X-1971949Y1074864D02*
X-1970974Y1073824D01*
X-1969609Y1073044D01*
X-1968439D01*
X-1967269Y1073564D01*
X-1966489Y1074344D01*
X-1966099Y1075384D01*
X-1966294Y1076944D01*
X-1967074Y1077724D01*
X-1970584Y1079284D01*
X-1971364Y1081104D01*
X-1970974Y1082404D01*
X-1970194Y1083184D01*
X-1969024Y1083444D01*
X-1967854Y1083184D01*
X-1966684Y1082404D01*
G01X-1933224Y1083444D02*
Y1073044D01*
G01Y1087604D02*
X-1933614Y1087864D01*
Y1088384D01*
X-1933224Y1088644D01*
X-1932834Y1088384D01*
Y1087864D01*
X-1933224Y1087604D01*
G01X-1911814Y1088644D02*
Y1073044D01*
G01Y1075384D02*
X-1912594Y1074084D01*
X-1913764Y1073304D01*
X-1915129Y1073044D01*
X-1916689Y1073564D01*
X-1917859Y1074864D01*
X-1918639Y1076424D01*
X-1918834Y1078244D01*
X-1918639Y1080064D01*
X-1917859Y1081624D01*
X-1916689Y1082924D01*
X-1915129Y1083444D01*
X-1913764Y1083184D01*
X-1912789Y1082664D01*
X-1911814Y1081624D01*
G01X-1900349Y1080064D02*
X-1894109D01*
X-1894694Y1081884D01*
X-1895669Y1082924D01*
X-1897034Y1083444D01*
X-1898399Y1083184D01*
X-1899569Y1082404D01*
X-1900349Y1080584D01*
X-1900739Y1079024D01*
Y1077464D01*
X-1900349Y1075904D01*
X-1899374Y1074344D01*
X-1898204Y1073304D01*
X-1896839Y1073044D01*
X-1895474Y1073564D01*
X-1894109Y1075124D01*
G01X-1882839Y1073044D02*
Y1083444D01*
G01Y1080844D02*
X-1882059Y1082144D01*
X-1880889Y1083184D01*
X-1879329Y1083444D01*
X-1877964Y1083184D01*
X-1876794Y1082144D01*
X-1876209Y1080324D01*
Y1073044D01*
G01X-1861624Y1088644D02*
Y1073044D01*
G01X-1864354Y1083444D02*
X-1858894D01*
G01X-1843724D02*
Y1073044D01*
G01Y1087604D02*
X-1844114Y1087864D01*
Y1088384D01*
X-1843724Y1088644D01*
X-1843334Y1088384D01*
Y1087864D01*
X-1843724Y1087604D01*
G01X-1826994Y1073044D02*
Y1086304D01*
X-1826604Y1087604D01*
X-1825824Y1088384D01*
X-1824654Y1088644D01*
X-1823484Y1088124D01*
X-1822899Y1086824D01*
G01X-1825239Y1082404D02*
X-1829139D01*
G01X-1807924Y1083444D02*
Y1073044D01*
G01Y1087604D02*
X-1808314Y1087864D01*
Y1088384D01*
X-1807924Y1088644D01*
X-1807534Y1088384D01*
Y1087864D01*
X-1807924Y1087604D01*
G01X-1786904Y1082144D02*
X-1788269Y1083184D01*
X-1789439Y1083444D01*
X-1790999Y1082924D01*
X-1792169Y1081884D01*
X-1792949Y1080064D01*
X-1793144Y1078244D01*
X-1792949Y1076424D01*
X-1792169Y1074864D01*
X-1790999Y1073564D01*
X-1789439Y1073044D01*
X-1788074Y1073564D01*
X-1786904Y1074604D01*
G01X-1768614Y1073044D02*
Y1083444D01*
G01Y1081624D02*
X-1769394Y1082664D01*
X-1770564Y1083184D01*
X-1771929Y1083444D01*
X-1773294Y1082924D01*
X-1774464Y1081884D01*
X-1775244Y1080324D01*
X-1775634Y1078244D01*
X-1775244Y1076164D01*
X-1774464Y1074604D01*
X-1773294Y1073564D01*
X-1771929Y1073044D01*
X-1770564Y1073304D01*
X-1769394Y1074084D01*
X-1768614Y1075124D01*
G01X-1754224Y1088644D02*
Y1073044D01*
G01X-1756954Y1083444D02*
X-1751494D01*
G01X-1736324D02*
Y1073044D01*
G01Y1087604D02*
X-1736714Y1087864D01*
Y1088384D01*
X-1736324Y1088644D01*
X-1735934Y1088384D01*
Y1087864D01*
X-1736324Y1087604D01*
G01X-1718424Y1073044D02*
X-1719594Y1073304D01*
X-1720764Y1074344D01*
X-1721544Y1076164D01*
X-1721934Y1078244D01*
X-1721544Y1080324D01*
X-1720764Y1082144D01*
X-1719594Y1083184D01*
X-1718424Y1083444D01*
X-1717254Y1083184D01*
X-1716084Y1082144D01*
X-1715304Y1080324D01*
X-1715109Y1078244D01*
X-1715304Y1076164D01*
X-1716084Y1074344D01*
X-1717254Y1073304D01*
X-1718424Y1073044D01*
G01X-1703839D02*
Y1083444D01*
G01Y1080844D02*
X-1703059Y1082144D01*
X-1701889Y1083184D01*
X-1700329Y1083444D01*
X-1698964Y1083184D01*
X-1697794Y1082144D01*
X-1697209Y1080324D01*
Y1073044D01*
G01X-1667649Y1074864D02*
X-1666674Y1073824D01*
X-1665309Y1073044D01*
X-1664139D01*
X-1662969Y1073564D01*
X-1662189Y1074344D01*
X-1661799Y1075384D01*
X-1661994Y1076944D01*
X-1662774Y1077724D01*
X-1666284Y1079284D01*
X-1667064Y1081104D01*
X-1666674Y1082404D01*
X-1665894Y1083184D01*
X-1664724Y1083444D01*
X-1663554Y1083184D01*
X-1662384Y1082404D01*
G01X-1646824Y1088644D02*
Y1073044D01*
G01X-1649554Y1083444D02*
X-1644094D01*
G01X-1625414Y1073044D02*
Y1083444D01*
G01Y1081624D02*
X-1626194Y1082664D01*
X-1627364Y1083184D01*
X-1628729Y1083444D01*
X-1630094Y1082924D01*
X-1631264Y1081884D01*
X-1632044Y1080324D01*
X-1632434Y1078244D01*
X-1632044Y1076164D01*
X-1631264Y1074604D01*
X-1630094Y1073564D01*
X-1628729Y1073044D01*
X-1627364Y1073304D01*
X-1626194Y1074084D01*
X-1625414Y1075124D01*
G01X-1616874Y1073044D02*
Y1083444D01*
G01Y1080584D02*
X-1616289Y1081884D01*
X-1615314Y1082924D01*
X-1613949Y1083444D01*
X-1612584Y1082924D01*
X-1611609Y1081884D01*
X-1611024Y1080584D01*
Y1073044D01*
G01Y1080584D02*
X-1610439Y1081884D01*
X-1609464Y1082924D01*
X-1608099Y1083444D01*
X-1606734Y1082924D01*
X-1605759Y1081884D01*
X-1605174Y1080324D01*
Y1073044D01*
G01X-1596634Y1067844D02*
Y1083444D01*
G01Y1081104D02*
X-1595659Y1082404D01*
X-1594684Y1083184D01*
X-1593124Y1083444D01*
X-1591759Y1083184D01*
X-1590394Y1081884D01*
X-1589809Y1080064D01*
X-1589614Y1078244D01*
X-1589809Y1076424D01*
X-1590394Y1074604D01*
X-1591564Y1073564D01*
X-1593124Y1073044D01*
X-1594489Y1073304D01*
X-1595854Y1074084D01*
X-1596634Y1075124D01*
G01X-1557324Y1073044D02*
X-1558494Y1073304D01*
X-1559664Y1074344D01*
X-1560444Y1076164D01*
X-1560834Y1078244D01*
X-1560444Y1080324D01*
X-1559664Y1082144D01*
X-1558494Y1083184D01*
X-1557324Y1083444D01*
X-1556154Y1083184D01*
X-1554984Y1082144D01*
X-1554204Y1080324D01*
X-1554009Y1078244D01*
X-1554204Y1076164D01*
X-1554984Y1074344D01*
X-1556154Y1073304D01*
X-1557324Y1073044D01*
G01X-1542154D02*
Y1083444D01*
G01Y1081364D02*
X-1541179Y1082404D01*
X-1540204Y1083184D01*
X-1538839Y1083444D01*
X-1537864Y1083184D01*
X-1536694Y1082404D01*
G01X-1507524Y1088644D02*
Y1073044D01*
X-1499724D01*
G01X-1485724Y1083444D02*
Y1073044D01*
G01Y1087604D02*
X-1486114Y1087864D01*
Y1088384D01*
X-1485724Y1088644D01*
X-1485334Y1088384D01*
Y1087864D01*
X-1485724Y1087604D01*
G01X-1471139Y1073044D02*
Y1083444D01*
G01Y1080844D02*
X-1470359Y1082144D01*
X-1469189Y1083184D01*
X-1467629Y1083444D01*
X-1466264Y1083184D01*
X-1465094Y1082144D01*
X-1464509Y1080324D01*
Y1073044D01*
G01X-1452849Y1080064D02*
X-1446609D01*
X-1447194Y1081884D01*
X-1448169Y1082924D01*
X-1449534Y1083444D01*
X-1450899Y1083184D01*
X-1452069Y1082404D01*
X-1452849Y1080584D01*
X-1453239Y1079024D01*
Y1077464D01*
X-1452849Y1075904D01*
X-1451874Y1074344D01*
X-1450704Y1073304D01*
X-1449339Y1073044D01*
X-1447974Y1073564D01*
X-1446609Y1075124D01*
G01X-1419974Y1073044D02*
Y1083444D01*
G01Y1080584D02*
X-1419389Y1081884D01*
X-1418414Y1082924D01*
X-1417049Y1083444D01*
X-1415684Y1082924D01*
X-1414709Y1081884D01*
X-1414124Y1080584D01*
Y1073044D01*
G01Y1080584D02*
X-1413539Y1081884D01*
X-1412564Y1082924D01*
X-1411199Y1083444D01*
X-1409834Y1082924D01*
X-1408859Y1081884D01*
X-1408274Y1080324D01*
Y1073044D01*
G01X-1399539Y1083444D02*
Y1076164D01*
X-1398759Y1074344D01*
X-1397589Y1073304D01*
X-1396224Y1073044D01*
X-1394859Y1073304D01*
X-1393689Y1074344D01*
X-1392909Y1076164D01*
G01Y1073044D02*
Y1083444D01*
G01X-1381249Y1074864D02*
X-1380274Y1073824D01*
X-1378909Y1073044D01*
X-1377739D01*
X-1376569Y1073564D01*
X-1375789Y1074344D01*
X-1375399Y1075384D01*
X-1375594Y1076944D01*
X-1376374Y1077724D01*
X-1379884Y1079284D01*
X-1380664Y1081104D01*
X-1380274Y1082404D01*
X-1379494Y1083184D01*
X-1378324Y1083444D01*
X-1377154Y1083184D01*
X-1375984Y1082404D01*
G01X-1360424Y1088644D02*
Y1073044D01*
G01X-1363154Y1083444D02*
X-1357694D01*
G01X-1328134Y1073044D02*
Y1088644D01*
G01Y1080844D02*
X-1327159Y1082404D01*
X-1325989Y1083184D01*
X-1324819Y1083444D01*
X-1323064Y1082924D01*
X-1321894Y1081884D01*
X-1321114Y1080064D01*
Y1077984D01*
X-1321504Y1075904D01*
X-1322284Y1074344D01*
X-1323649Y1073304D01*
X-1324819Y1073044D01*
X-1325989Y1073304D01*
X-1327159Y1074084D01*
X-1328134Y1075384D01*
G01X-1309649Y1080064D02*
X-1303409D01*
X-1303994Y1081884D01*
X-1304969Y1082924D01*
X-1306334Y1083444D01*
X-1307699Y1083184D01*
X-1308869Y1082404D01*
X-1309649Y1080584D01*
X-1310039Y1079024D01*
Y1077464D01*
X-1309649Y1075904D01*
X-1308674Y1074344D01*
X-1307504Y1073304D01*
X-1306139Y1073044D01*
X-1304774Y1073564D01*
X-1303409Y1075124D01*
G01X-1270924Y1083444D02*
Y1073044D01*
G01Y1087604D02*
X-1271314Y1087864D01*
Y1088384D01*
X-1270924Y1088644D01*
X-1270534Y1088384D01*
Y1087864D01*
X-1270924Y1087604D01*
G01X-1256339Y1073044D02*
Y1083444D01*
G01Y1080844D02*
X-1255559Y1082144D01*
X-1254389Y1083184D01*
X-1252829Y1083444D01*
X-1251464Y1083184D01*
X-1250294Y1082144D01*
X-1249709Y1080324D01*
Y1073044D01*
G01X-1217224Y1088644D02*
Y1073044D01*
G01X-1219954Y1083444D02*
X-1214494D01*
G01X-1202639Y1073044D02*
Y1088644D01*
G01Y1081104D02*
X-1201664Y1082404D01*
X-1200689Y1083184D01*
X-1199129Y1083444D01*
X-1197959Y1083184D01*
X-1196594Y1082144D01*
X-1196009Y1080584D01*
Y1073044D01*
G01X-1184349Y1080064D02*
X-1178109D01*
X-1178694Y1081884D01*
X-1179669Y1082924D01*
X-1181034Y1083444D01*
X-1182399Y1083184D01*
X-1183569Y1082404D01*
X-1184349Y1080584D01*
X-1184739Y1079024D01*
Y1077464D01*
X-1184349Y1075904D01*
X-1183374Y1074344D01*
X-1182204Y1073304D01*
X-1180839Y1073044D01*
X-1179474Y1073564D01*
X-1178109Y1075124D01*
G01X-1148549Y1074864D02*
X-1147574Y1073824D01*
X-1146209Y1073044D01*
X-1145039D01*
X-1143869Y1073564D01*
X-1143089Y1074344D01*
X-1142699Y1075384D01*
X-1142894Y1076944D01*
X-1143674Y1077724D01*
X-1147184Y1079284D01*
X-1147964Y1081104D01*
X-1147574Y1082404D01*
X-1146794Y1083184D01*
X-1145624Y1083444D01*
X-1144454Y1083184D01*
X-1143284Y1082404D01*
G01X-1124214Y1073044D02*
Y1083444D01*
G01Y1081624D02*
X-1124994Y1082664D01*
X-1126164Y1083184D01*
X-1127529Y1083444D01*
X-1128894Y1082924D01*
X-1130064Y1081884D01*
X-1130844Y1080324D01*
X-1131234Y1078244D01*
X-1130844Y1076164D01*
X-1130064Y1074604D01*
X-1128894Y1073564D01*
X-1127529Y1073044D01*
X-1126164Y1073304D01*
X-1124994Y1074084D01*
X-1124214Y1075124D01*
G01X-1115674Y1073044D02*
Y1083444D01*
G01Y1080584D02*
X-1115089Y1081884D01*
X-1114114Y1082924D01*
X-1112749Y1083444D01*
X-1111384Y1082924D01*
X-1110409Y1081884D01*
X-1109824Y1080584D01*
Y1073044D01*
G01Y1080584D02*
X-1109239Y1081884D01*
X-1108264Y1082924D01*
X-1106899Y1083444D01*
X-1105534Y1082924D01*
X-1104559Y1081884D01*
X-1103974Y1080324D01*
Y1073044D01*
G01X-1094849Y1080064D02*
X-1088609D01*
X-1089194Y1081884D01*
X-1090169Y1082924D01*
X-1091534Y1083444D01*
X-1092899Y1083184D01*
X-1094069Y1082404D01*
X-1094849Y1080584D01*
X-1095239Y1079024D01*
Y1077464D01*
X-1094849Y1075904D01*
X-1093874Y1074344D01*
X-1092704Y1073304D01*
X-1091339Y1073044D01*
X-1089974Y1073564D01*
X-1088609Y1075124D01*
G01X-1056124Y1073044D02*
Y1088644D01*
G01X-1038224Y1073044D02*
X-1039394Y1073304D01*
X-1040564Y1074344D01*
X-1041344Y1076164D01*
X-1041734Y1078244D01*
X-1041344Y1080324D01*
X-1040564Y1082144D01*
X-1039394Y1083184D01*
X-1038224Y1083444D01*
X-1037054Y1083184D01*
X-1035884Y1082144D01*
X-1035104Y1080324D01*
X-1034909Y1078244D01*
X-1035104Y1076164D01*
X-1035884Y1074344D01*
X-1037054Y1073304D01*
X-1038224Y1073044D01*
G01X-1017204Y1082144D02*
X-1018569Y1083184D01*
X-1019739Y1083444D01*
X-1021299Y1082924D01*
X-1022469Y1081884D01*
X-1023249Y1080064D01*
X-1023444Y1078244D01*
X-1023249Y1076424D01*
X-1022469Y1074864D01*
X-1021299Y1073564D01*
X-1019739Y1073044D01*
X-1018374Y1073564D01*
X-1017204Y1074604D01*
G01X-998914Y1073044D02*
Y1083444D01*
G01Y1081624D02*
X-999694Y1082664D01*
X-1000864Y1083184D01*
X-1002229Y1083444D01*
X-1003594Y1082924D01*
X-1004764Y1081884D01*
X-1005544Y1080324D01*
X-1005934Y1078244D01*
X-1005544Y1076164D01*
X-1004764Y1074604D01*
X-1003594Y1073564D01*
X-1002229Y1073044D01*
X-1000864Y1073304D01*
X-999694Y1074084D01*
X-998914Y1075124D01*
G01X-984524Y1088644D02*
Y1073044D01*
G01X-987254Y1083444D02*
X-981794D01*
G01X-966624D02*
Y1073044D01*
G01Y1087604D02*
X-967014Y1087864D01*
Y1088384D01*
X-966624Y1088644D01*
X-966234Y1088384D01*
Y1087864D01*
X-966624Y1087604D01*
G01X-948724Y1073044D02*
X-949894Y1073304D01*
X-951064Y1074344D01*
X-951844Y1076164D01*
X-952234Y1078244D01*
X-951844Y1080324D01*
X-951064Y1082144D01*
X-949894Y1083184D01*
X-948724Y1083444D01*
X-947554Y1083184D01*
X-946384Y1082144D01*
X-945604Y1080324D01*
X-945409Y1078244D01*
X-945604Y1076164D01*
X-946384Y1074344D01*
X-947554Y1073304D01*
X-948724Y1073044D01*
G01X-934139D02*
Y1083444D01*
G01Y1080844D02*
X-933359Y1082144D01*
X-932189Y1083184D01*
X-930629Y1083444D01*
X-929264Y1083184D01*
X-928094Y1082144D01*
X-927509Y1080324D01*
Y1073044D01*
G01X-895024D02*
X-896194Y1073304D01*
X-897364Y1074344D01*
X-898144Y1076164D01*
X-898534Y1078244D01*
X-898144Y1080324D01*
X-897364Y1082144D01*
X-896194Y1083184D01*
X-895024Y1083444D01*
X-893854Y1083184D01*
X-892684Y1082144D01*
X-891904Y1080324D01*
X-891709Y1078244D01*
X-891904Y1076164D01*
X-892684Y1074344D01*
X-893854Y1073304D01*
X-895024Y1073044D01*
G01X-880439D02*
Y1083444D01*
G01Y1080844D02*
X-879659Y1082144D01*
X-878489Y1083184D01*
X-876929Y1083444D01*
X-875564Y1083184D01*
X-874394Y1082144D01*
X-873809Y1080324D01*
Y1073044D01*
G01X-844249Y1080064D02*
X-838009D01*
X-838594Y1081884D01*
X-839569Y1082924D01*
X-840934Y1083444D01*
X-842299Y1083184D01*
X-843469Y1082404D01*
X-844249Y1080584D01*
X-844639Y1079024D01*
Y1077464D01*
X-844249Y1075904D01*
X-843274Y1074344D01*
X-842104Y1073304D01*
X-840739Y1073044D01*
X-839374Y1073564D01*
X-838009Y1075124D01*
G01X-826934Y1083444D02*
X-823424Y1073044D01*
X-819914Y1083444D01*
G01X-808449Y1080064D02*
X-802209D01*
X-802794Y1081884D01*
X-803769Y1082924D01*
X-805134Y1083444D01*
X-806499Y1083184D01*
X-807669Y1082404D01*
X-808449Y1080584D01*
X-808839Y1079024D01*
Y1077464D01*
X-808449Y1075904D01*
X-807474Y1074344D01*
X-806304Y1073304D01*
X-804939Y1073044D01*
X-803574Y1073564D01*
X-802209Y1075124D01*
G01X-790354Y1073044D02*
Y1083444D01*
G01Y1081364D02*
X-789379Y1082404D01*
X-788404Y1083184D01*
X-787039Y1083444D01*
X-786064Y1083184D01*
X-784894Y1082404D01*
G01X-773819Y1068364D02*
X-772649Y1067844D01*
X-771089Y1068364D01*
X-770114Y1069404D01*
X-769334Y1070704D01*
X-768164Y1074864D01*
X-765629Y1083444D01*
G01X-771869D02*
X-768164Y1074864D01*
G01X-737434Y1073044D02*
Y1088644D01*
G01Y1080844D02*
X-736459Y1082404D01*
X-735289Y1083184D01*
X-734119Y1083444D01*
X-732364Y1082924D01*
X-731194Y1081884D01*
X-730414Y1080064D01*
Y1077984D01*
X-730804Y1075904D01*
X-731584Y1074344D01*
X-732949Y1073304D01*
X-734119Y1073044D01*
X-735289Y1073304D01*
X-736459Y1074084D01*
X-737434Y1075384D01*
G01X-716024Y1073044D02*
X-717194Y1073304D01*
X-718364Y1074344D01*
X-719144Y1076164D01*
X-719534Y1078244D01*
X-719144Y1080324D01*
X-718364Y1082144D01*
X-717194Y1083184D01*
X-716024Y1083444D01*
X-714854Y1083184D01*
X-713684Y1082144D01*
X-712904Y1080324D01*
X-712709Y1078244D01*
X-712904Y1076164D01*
X-713684Y1074344D01*
X-714854Y1073304D01*
X-716024Y1073044D01*
G01X-694614D02*
Y1083444D01*
G01Y1081624D02*
X-695394Y1082664D01*
X-696564Y1083184D01*
X-697929Y1083444D01*
X-699294Y1082924D01*
X-700464Y1081884D01*
X-701244Y1080324D01*
X-701634Y1078244D01*
X-701244Y1076164D01*
X-700464Y1074604D01*
X-699294Y1073564D01*
X-697929Y1073044D01*
X-696564Y1073304D01*
X-695394Y1074084D01*
X-694614Y1075124D01*
G01X-682954Y1073044D02*
Y1083444D01*
G01Y1081364D02*
X-681979Y1082404D01*
X-681004Y1083184D01*
X-679639Y1083444D01*
X-678664Y1083184D01*
X-677494Y1082404D01*
G01X-658814Y1088644D02*
Y1073044D01*
G01Y1075384D02*
X-659594Y1074084D01*
X-660764Y1073304D01*
X-662129Y1073044D01*
X-663689Y1073564D01*
X-664859Y1074864D01*
X-665639Y1076424D01*
X-665834Y1078244D01*
X-665639Y1080064D01*
X-664859Y1081624D01*
X-663689Y1082924D01*
X-662129Y1083444D01*
X-660764Y1083184D01*
X-659789Y1082664D01*
X-658814Y1081624D01*
G01X-644814Y1070184D02*
X-644034Y1073564D01*
G01X-2018434Y1121344D02*
X-2019604Y1122124D01*
X-2020969Y1122644D01*
X-2022529D01*
X-2024284Y1121864D01*
X-2025649Y1120564D01*
X-2026624Y1119004D01*
X-2027404Y1116404D01*
X-2027599Y1114064D01*
X-2027209Y1111724D01*
X-2026624Y1110164D01*
X-2025454Y1108604D01*
X-2024089Y1107564D01*
X-2022724Y1107044D01*
X-2021359D01*
X-2019994Y1107564D01*
X-2018824Y1108344D01*
X-2017849Y1109384D01*
G01X-2004824Y1107044D02*
X-2005994Y1107304D01*
X-2007164Y1108344D01*
X-2007944Y1110164D01*
X-2008334Y1112244D01*
X-2007944Y1114324D01*
X-2007164Y1116144D01*
X-2005994Y1117184D01*
X-2004824Y1117444D01*
X-2003654Y1117184D01*
X-2002484Y1116144D01*
X-2001704Y1114324D01*
X-2001509Y1112244D01*
X-2001704Y1110164D01*
X-2002484Y1108344D01*
X-2003654Y1107304D01*
X-2004824Y1107044D01*
G01X-1992774D02*
Y1117444D01*
G01Y1114584D02*
X-1992189Y1115884D01*
X-1991214Y1116924D01*
X-1989849Y1117444D01*
X-1988484Y1116924D01*
X-1987509Y1115884D01*
X-1986924Y1114584D01*
Y1107044D01*
G01Y1114584D02*
X-1986339Y1115884D01*
X-1985364Y1116924D01*
X-1983999Y1117444D01*
X-1982634Y1116924D01*
X-1981659Y1115884D01*
X-1981074Y1114324D01*
Y1107044D01*
G01X-1972534Y1101844D02*
Y1117444D01*
G01Y1115104D02*
X-1971559Y1116404D01*
X-1970584Y1117184D01*
X-1969024Y1117444D01*
X-1967659Y1117184D01*
X-1966294Y1115884D01*
X-1965709Y1114064D01*
X-1965514Y1112244D01*
X-1965709Y1110424D01*
X-1966294Y1108604D01*
X-1967464Y1107564D01*
X-1969024Y1107044D01*
X-1970389Y1107304D01*
X-1971754Y1108084D01*
X-1972534Y1109124D01*
G01X-1951124Y1107044D02*
Y1122644D01*
G01X-1936149Y1114064D02*
X-1929909D01*
X-1930494Y1115884D01*
X-1931469Y1116924D01*
X-1932834Y1117444D01*
X-1934199Y1117184D01*
X-1935369Y1116404D01*
X-1936149Y1114584D01*
X-1936539Y1113024D01*
Y1111464D01*
X-1936149Y1109904D01*
X-1935174Y1108344D01*
X-1934004Y1107304D01*
X-1932639Y1107044D01*
X-1931274Y1107564D01*
X-1929909Y1109124D01*
G01X-1915324Y1122644D02*
Y1107044D01*
G01X-1918054Y1117444D02*
X-1912594D01*
G01X-1900349Y1114064D02*
X-1894109D01*
X-1894694Y1115884D01*
X-1895669Y1116924D01*
X-1897034Y1117444D01*
X-1898399Y1117184D01*
X-1899569Y1116404D01*
X-1900349Y1114584D01*
X-1900739Y1113024D01*
Y1111464D01*
X-1900349Y1109904D01*
X-1899374Y1108344D01*
X-1898204Y1107304D01*
X-1896839Y1107044D01*
X-1895474Y1107564D01*
X-1894109Y1109124D01*
G01X-1876014Y1122644D02*
Y1107044D01*
G01Y1109384D02*
X-1876794Y1108084D01*
X-1877964Y1107304D01*
X-1879329Y1107044D01*
X-1880889Y1107564D01*
X-1882059Y1108864D01*
X-1882839Y1110424D01*
X-1883034Y1112244D01*
X-1882839Y1114064D01*
X-1882059Y1115624D01*
X-1880889Y1116924D01*
X-1879329Y1117444D01*
X-1877964Y1117184D01*
X-1876989Y1116664D01*
X-1876014Y1115624D01*
G01X-1846649Y1114064D02*
X-1840409D01*
X-1840994Y1115884D01*
X-1841969Y1116924D01*
X-1843334Y1117444D01*
X-1844699Y1117184D01*
X-1845869Y1116404D01*
X-1846649Y1114584D01*
X-1847039Y1113024D01*
Y1111464D01*
X-1846649Y1109904D01*
X-1845674Y1108344D01*
X-1844504Y1107304D01*
X-1843139Y1107044D01*
X-1841774Y1107564D01*
X-1840409Y1109124D01*
G01X-1825824Y1107044D02*
Y1122644D01*
G01X-1810849Y1114064D02*
X-1804609D01*
X-1805194Y1115884D01*
X-1806169Y1116924D01*
X-1807534Y1117444D01*
X-1808899Y1117184D01*
X-1810069Y1116404D01*
X-1810849Y1114584D01*
X-1811239Y1113024D01*
Y1111464D01*
X-1810849Y1109904D01*
X-1809874Y1108344D01*
X-1808704Y1107304D01*
X-1807339Y1107044D01*
X-1805974Y1107564D01*
X-1804609Y1109124D01*
G01X-1786904Y1116144D02*
X-1788269Y1117184D01*
X-1789439Y1117444D01*
X-1790999Y1116924D01*
X-1792169Y1115884D01*
X-1792949Y1114064D01*
X-1793144Y1112244D01*
X-1792949Y1110424D01*
X-1792169Y1108864D01*
X-1790999Y1107564D01*
X-1789439Y1107044D01*
X-1788074Y1107564D01*
X-1786904Y1108604D01*
G01X-1772124Y1122644D02*
Y1107044D01*
G01X-1774854Y1117444D02*
X-1769394D01*
G01X-1756954Y1107044D02*
Y1117444D01*
G01Y1115364D02*
X-1755979Y1116404D01*
X-1755004Y1117184D01*
X-1753639Y1117444D01*
X-1752664Y1117184D01*
X-1751494Y1116404D01*
G01X-1736324Y1117444D02*
Y1107044D01*
G01Y1121604D02*
X-1736714Y1121864D01*
Y1122384D01*
X-1736324Y1122644D01*
X-1735934Y1122384D01*
Y1121864D01*
X-1736324Y1121604D01*
G01X-1715304Y1116144D02*
X-1716669Y1117184D01*
X-1717839Y1117444D01*
X-1719399Y1116924D01*
X-1720569Y1115884D01*
X-1721349Y1114064D01*
X-1721544Y1112244D01*
X-1721349Y1110424D01*
X-1720569Y1108864D01*
X-1719399Y1107564D01*
X-1717839Y1107044D01*
X-1716474Y1107564D01*
X-1715304Y1108604D01*
G01X-1697014Y1107044D02*
Y1117444D01*
G01Y1115624D02*
X-1697794Y1116664D01*
X-1698964Y1117184D01*
X-1700329Y1117444D01*
X-1701694Y1116924D01*
X-1702864Y1115884D01*
X-1703644Y1114324D01*
X-1704034Y1112244D01*
X-1703644Y1110164D01*
X-1702864Y1108604D01*
X-1701694Y1107564D01*
X-1700329Y1107044D01*
X-1698964Y1107304D01*
X-1697794Y1108084D01*
X-1697014Y1109124D01*
G01X-1682624Y1107044D02*
Y1122644D01*
G01X-1646824D02*
Y1107044D01*
G01X-1649554Y1117444D02*
X-1644094D01*
G01X-1631849Y1114064D02*
X-1625609D01*
X-1626194Y1115884D01*
X-1627169Y1116924D01*
X-1628534Y1117444D01*
X-1629899Y1117184D01*
X-1631069Y1116404D01*
X-1631849Y1114584D01*
X-1632239Y1113024D01*
Y1111464D01*
X-1631849Y1109904D01*
X-1630874Y1108344D01*
X-1629704Y1107304D01*
X-1628339Y1107044D01*
X-1626974Y1107564D01*
X-1625609Y1109124D01*
G01X-1613949Y1108864D02*
X-1612974Y1107824D01*
X-1611609Y1107044D01*
X-1610439D01*
X-1609269Y1107564D01*
X-1608489Y1108344D01*
X-1608099Y1109384D01*
X-1608294Y1110944D01*
X-1609074Y1111724D01*
X-1612584Y1113284D01*
X-1613364Y1115104D01*
X-1612974Y1116404D01*
X-1612194Y1117184D01*
X-1611024Y1117444D01*
X-1609854Y1117184D01*
X-1608684Y1116404D01*
G01X-1593124Y1122644D02*
Y1107044D01*
G01X-1595854Y1117444D02*
X-1590394D01*
G01X-1555764Y1115364D02*
X-1554984Y1116144D01*
X-1554399Y1117444D01*
X-1554009Y1119264D01*
X-1554399Y1120824D01*
X-1555179Y1121864D01*
X-1556544Y1122644D01*
X-1561809D01*
Y1107044D01*
X-1555374D01*
X-1554009Y1108084D01*
X-1553229Y1109644D01*
X-1552839Y1111464D01*
X-1553229Y1113284D01*
X-1554399Y1114844D01*
X-1555764Y1115364D01*
X-1561809D01*
G01X-1539424Y1107044D02*
X-1540594Y1107304D01*
X-1541764Y1108344D01*
X-1542544Y1110164D01*
X-1542934Y1112244D01*
X-1542544Y1114324D01*
X-1541764Y1116144D01*
X-1540594Y1117184D01*
X-1539424Y1117444D01*
X-1538254Y1117184D01*
X-1537084Y1116144D01*
X-1536304Y1114324D01*
X-1536109Y1112244D01*
X-1536304Y1110164D01*
X-1537084Y1108344D01*
X-1538254Y1107304D01*
X-1539424Y1107044D01*
G01X-1518014D02*
Y1117444D01*
G01Y1115624D02*
X-1518794Y1116664D01*
X-1519964Y1117184D01*
X-1521329Y1117444D01*
X-1522694Y1116924D01*
X-1523864Y1115884D01*
X-1524644Y1114324D01*
X-1525034Y1112244D01*
X-1524644Y1110164D01*
X-1523864Y1108604D01*
X-1522694Y1107564D01*
X-1521329Y1107044D01*
X-1519964Y1107304D01*
X-1518794Y1108084D01*
X-1518014Y1109124D01*
G01X-1506354Y1107044D02*
Y1117444D01*
G01Y1115364D02*
X-1505379Y1116404D01*
X-1504404Y1117184D01*
X-1503039Y1117444D01*
X-1502064Y1117184D01*
X-1500894Y1116404D01*
G01X-1482214Y1122644D02*
Y1107044D01*
G01Y1109384D02*
X-1482994Y1108084D01*
X-1484164Y1107304D01*
X-1485529Y1107044D01*
X-1487089Y1107564D01*
X-1488259Y1108864D01*
X-1489039Y1110424D01*
X-1489234Y1112244D01*
X-1489039Y1114064D01*
X-1488259Y1115624D01*
X-1487089Y1116924D01*
X-1485529Y1117444D01*
X-1484164Y1117184D01*
X-1483189Y1116664D01*
X-1482214Y1115624D01*
G01X-1470749Y1108864D02*
X-1469774Y1107824D01*
X-1468409Y1107044D01*
X-1467239D01*
X-1466069Y1107564D01*
X-1465289Y1108344D01*
X-1464899Y1109384D01*
X-1465094Y1110944D01*
X-1465874Y1111724D01*
X-1469384Y1113284D01*
X-1470164Y1115104D01*
X-1469774Y1116404D01*
X-1468994Y1117184D01*
X-1467824Y1117444D01*
X-1466654Y1117184D01*
X-1465484Y1116404D01*
G01X-1437874Y1107044D02*
Y1117444D01*
G01Y1114584D02*
X-1437289Y1115884D01*
X-1436314Y1116924D01*
X-1434949Y1117444D01*
X-1433584Y1116924D01*
X-1432609Y1115884D01*
X-1432024Y1114584D01*
Y1107044D01*
G01Y1114584D02*
X-1431439Y1115884D01*
X-1430464Y1116924D01*
X-1429099Y1117444D01*
X-1427734Y1116924D01*
X-1426759Y1115884D01*
X-1426174Y1114324D01*
Y1107044D01*
G01X-1417439Y1117444D02*
Y1110164D01*
X-1416659Y1108344D01*
X-1415489Y1107304D01*
X-1414124Y1107044D01*
X-1412759Y1107304D01*
X-1411589Y1108344D01*
X-1410809Y1110164D01*
G01Y1107044D02*
Y1117444D01*
G01X-1399149Y1108864D02*
X-1398174Y1107824D01*
X-1396809Y1107044D01*
X-1395639D01*
X-1394469Y1107564D01*
X-1393689Y1108344D01*
X-1393299Y1109384D01*
X-1393494Y1110944D01*
X-1394274Y1111724D01*
X-1397784Y1113284D01*
X-1398564Y1115104D01*
X-1398174Y1116404D01*
X-1397394Y1117184D01*
X-1396224Y1117444D01*
X-1395054Y1117184D01*
X-1393884Y1116404D01*
G01X-1378324Y1122644D02*
Y1107044D01*
G01X-1381054Y1117444D02*
X-1375594D01*
G01X-1346034Y1107044D02*
Y1122644D01*
G01Y1114844D02*
X-1345059Y1116404D01*
X-1343889Y1117184D01*
X-1342719Y1117444D01*
X-1340964Y1116924D01*
X-1339794Y1115884D01*
X-1339014Y1114064D01*
Y1111984D01*
X-1339404Y1109904D01*
X-1340184Y1108344D01*
X-1341549Y1107304D01*
X-1342719Y1107044D01*
X-1343889Y1107304D01*
X-1345059Y1108084D01*
X-1346034Y1109384D01*
G01X-1327549Y1114064D02*
X-1321309D01*
X-1321894Y1115884D01*
X-1322869Y1116924D01*
X-1324234Y1117444D01*
X-1325599Y1117184D01*
X-1326769Y1116404D01*
X-1327549Y1114584D01*
X-1327939Y1113024D01*
Y1111464D01*
X-1327549Y1109904D01*
X-1326574Y1108344D01*
X-1325404Y1107304D01*
X-1324039Y1107044D01*
X-1322674Y1107564D01*
X-1321309Y1109124D01*
G01X-1294674Y1107044D02*
Y1117444D01*
G01Y1114584D02*
X-1294089Y1115884D01*
X-1293114Y1116924D01*
X-1291749Y1117444D01*
X-1290384Y1116924D01*
X-1289409Y1115884D01*
X-1288824Y1114584D01*
Y1107044D01*
G01Y1114584D02*
X-1288239Y1115884D01*
X-1287264Y1116924D01*
X-1285899Y1117444D01*
X-1284534Y1116924D01*
X-1283559Y1115884D01*
X-1282974Y1114324D01*
Y1107044D01*
G01X-1267414D02*
Y1117444D01*
G01Y1115624D02*
X-1268194Y1116664D01*
X-1269364Y1117184D01*
X-1270729Y1117444D01*
X-1272094Y1116924D01*
X-1273264Y1115884D01*
X-1274044Y1114324D01*
X-1274434Y1112244D01*
X-1274044Y1110164D01*
X-1273264Y1108604D01*
X-1272094Y1107564D01*
X-1270729Y1107044D01*
X-1269364Y1107304D01*
X-1268194Y1108084D01*
X-1267414Y1109124D01*
G01X-1255754Y1107044D02*
Y1117444D01*
G01Y1115364D02*
X-1254779Y1116404D01*
X-1253804Y1117184D01*
X-1252439Y1117444D01*
X-1251464Y1117184D01*
X-1250294Y1116404D01*
G01X-1238439Y1107044D02*
Y1122644D01*
G01X-1232199Y1117444D02*
X-1238439Y1111464D01*
G01X-1235904Y1113804D02*
X-1231809Y1107044D01*
G01X-1220149Y1114064D02*
X-1213909D01*
X-1214494Y1115884D01*
X-1215469Y1116924D01*
X-1216834Y1117444D01*
X-1218199Y1117184D01*
X-1219369Y1116404D01*
X-1220149Y1114584D01*
X-1220539Y1113024D01*
Y1111464D01*
X-1220149Y1109904D01*
X-1219174Y1108344D01*
X-1218004Y1107304D01*
X-1216639Y1107044D01*
X-1215274Y1107564D01*
X-1213909Y1109124D01*
G01X-1195814Y1122644D02*
Y1107044D01*
G01Y1109384D02*
X-1196594Y1108084D01*
X-1197764Y1107304D01*
X-1199129Y1107044D01*
X-1200689Y1107564D01*
X-1201859Y1108864D01*
X-1202639Y1110424D01*
X-1202834Y1112244D01*
X-1202639Y1114064D01*
X-1201859Y1115624D01*
X-1200689Y1116924D01*
X-1199129Y1117444D01*
X-1197764Y1117184D01*
X-1196789Y1116664D01*
X-1195814Y1115624D01*
G01X-1163524Y1117444D02*
Y1107044D01*
G01Y1121604D02*
X-1163914Y1121864D01*
Y1122384D01*
X-1163524Y1122644D01*
X-1163134Y1122384D01*
Y1121864D01*
X-1163524Y1121604D01*
G01X-1148939Y1107044D02*
Y1117444D01*
G01Y1114844D02*
X-1148159Y1116144D01*
X-1146989Y1117184D01*
X-1145429Y1117444D01*
X-1144064Y1117184D01*
X-1142894Y1116144D01*
X-1142309Y1114324D01*
Y1107044D01*
G01X-1113334Y1101844D02*
Y1117444D01*
G01Y1115104D02*
X-1112359Y1116404D01*
X-1111384Y1117184D01*
X-1109824Y1117444D01*
X-1108459Y1117184D01*
X-1107094Y1115884D01*
X-1106509Y1114064D01*
X-1106314Y1112244D01*
X-1106509Y1110424D01*
X-1107094Y1108604D01*
X-1108264Y1107564D01*
X-1109824Y1107044D01*
X-1111189Y1107304D01*
X-1112554Y1108084D01*
X-1113334Y1109124D01*
G01X-1094849Y1114064D02*
X-1088609D01*
X-1089194Y1115884D01*
X-1090169Y1116924D01*
X-1091534Y1117444D01*
X-1092899Y1117184D01*
X-1094069Y1116404D01*
X-1094849Y1114584D01*
X-1095239Y1113024D01*
Y1111464D01*
X-1094849Y1109904D01*
X-1093874Y1108344D01*
X-1092704Y1107304D01*
X-1091339Y1107044D01*
X-1089974Y1107564D01*
X-1088609Y1109124D01*
G01X-1076754Y1107044D02*
Y1117444D01*
G01Y1115364D02*
X-1075779Y1116404D01*
X-1074804Y1117184D01*
X-1073439Y1117444D01*
X-1072464Y1117184D01*
X-1071294Y1116404D01*
G01X-1061974Y1107044D02*
Y1117444D01*
G01Y1114584D02*
X-1061389Y1115884D01*
X-1060414Y1116924D01*
X-1059049Y1117444D01*
X-1057684Y1116924D01*
X-1056709Y1115884D01*
X-1056124Y1114584D01*
Y1107044D01*
G01Y1114584D02*
X-1055539Y1115884D01*
X-1054564Y1116924D01*
X-1053199Y1117444D01*
X-1051834Y1116924D01*
X-1050859Y1115884D01*
X-1050274Y1114324D01*
Y1107044D01*
G01X-1034714D02*
Y1117444D01*
G01Y1115624D02*
X-1035494Y1116664D01*
X-1036664Y1117184D01*
X-1038029Y1117444D01*
X-1039394Y1116924D01*
X-1040564Y1115884D01*
X-1041344Y1114324D01*
X-1041734Y1112244D01*
X-1041344Y1110164D01*
X-1040564Y1108604D01*
X-1039394Y1107564D01*
X-1038029Y1107044D01*
X-1036664Y1107304D01*
X-1035494Y1108084D01*
X-1034714Y1109124D01*
G01X-1023639Y1107044D02*
Y1117444D01*
G01Y1114844D02*
X-1022859Y1116144D01*
X-1021689Y1117184D01*
X-1020129Y1117444D01*
X-1018764Y1117184D01*
X-1017594Y1116144D01*
X-1017009Y1114324D01*
Y1107044D01*
G01X-1005349Y1114064D02*
X-999109D01*
X-999694Y1115884D01*
X-1000669Y1116924D01*
X-1002034Y1117444D01*
X-1003399Y1117184D01*
X-1004569Y1116404D01*
X-1005349Y1114584D01*
X-1005739Y1113024D01*
Y1111464D01*
X-1005349Y1109904D01*
X-1004374Y1108344D01*
X-1003204Y1107304D01*
X-1001839Y1107044D01*
X-1000474Y1107564D01*
X-999109Y1109124D01*
G01X-987839Y1107044D02*
Y1117444D01*
G01Y1114844D02*
X-987059Y1116144D01*
X-985889Y1117184D01*
X-984329Y1117444D01*
X-982964Y1117184D01*
X-981794Y1116144D01*
X-981209Y1114324D01*
Y1107044D01*
G01X-966624Y1122644D02*
Y1107044D01*
G01X-969354Y1117444D02*
X-963894D01*
G01X-934139Y1107044D02*
Y1117444D01*
G01Y1114844D02*
X-933359Y1116144D01*
X-932189Y1117184D01*
X-930629Y1117444D01*
X-929264Y1117184D01*
X-928094Y1116144D01*
X-927509Y1114324D01*
Y1107044D01*
G01X-912924D02*
X-914094Y1107304D01*
X-915264Y1108344D01*
X-916044Y1110164D01*
X-916434Y1112244D01*
X-916044Y1114324D01*
X-915264Y1116144D01*
X-914094Y1117184D01*
X-912924Y1117444D01*
X-911754Y1117184D01*
X-910584Y1116144D01*
X-909804Y1114324D01*
X-909609Y1112244D01*
X-909804Y1110164D01*
X-910584Y1108344D01*
X-911754Y1107304D01*
X-912924Y1107044D01*
G01X-898339D02*
Y1117444D01*
G01Y1114844D02*
X-897559Y1116144D01*
X-896389Y1117184D01*
X-894829Y1117444D01*
X-893464Y1117184D01*
X-892294Y1116144D01*
X-891709Y1114324D01*
Y1107044D01*
G01X-879659Y1112244D02*
X-874589D01*
G01X-856104Y1116144D02*
X-857469Y1117184D01*
X-858639Y1117444D01*
X-860199Y1116924D01*
X-861369Y1115884D01*
X-862149Y1114064D01*
X-862344Y1112244D01*
X-862149Y1110424D01*
X-861369Y1108864D01*
X-860199Y1107564D01*
X-858639Y1107044D01*
X-857274Y1107564D01*
X-856104Y1108604D01*
G01X-841324Y1107044D02*
X-842494Y1107304D01*
X-843664Y1108344D01*
X-844444Y1110164D01*
X-844834Y1112244D01*
X-844444Y1114324D01*
X-843664Y1116144D01*
X-842494Y1117184D01*
X-841324Y1117444D01*
X-840154Y1117184D01*
X-838984Y1116144D01*
X-838204Y1114324D01*
X-838009Y1112244D01*
X-838204Y1110164D01*
X-838984Y1108344D01*
X-840154Y1107304D01*
X-841324Y1107044D01*
G01X-826739D02*
Y1117444D01*
G01Y1114844D02*
X-825959Y1116144D01*
X-824789Y1117184D01*
X-823229Y1117444D01*
X-821864Y1117184D01*
X-820694Y1116144D01*
X-820109Y1114324D01*
Y1107044D01*
G01X-802014Y1122644D02*
Y1107044D01*
G01Y1109384D02*
X-802794Y1108084D01*
X-803964Y1107304D01*
X-805329Y1107044D01*
X-806889Y1107564D01*
X-808059Y1108864D01*
X-808839Y1110424D01*
X-809034Y1112244D01*
X-808839Y1114064D01*
X-808059Y1115624D01*
X-806889Y1116924D01*
X-805329Y1117444D01*
X-803964Y1117184D01*
X-802989Y1116664D01*
X-802014Y1115624D01*
G01X-790939Y1117444D02*
Y1110164D01*
X-790159Y1108344D01*
X-788989Y1107304D01*
X-787624Y1107044D01*
X-786259Y1107304D01*
X-785089Y1108344D01*
X-784309Y1110164D01*
G01Y1107044D02*
Y1117444D01*
G01X-766604Y1116144D02*
X-767969Y1117184D01*
X-769139Y1117444D01*
X-770699Y1116924D01*
X-771869Y1115884D01*
X-772649Y1114064D01*
X-772844Y1112244D01*
X-772649Y1110424D01*
X-771869Y1108864D01*
X-770699Y1107564D01*
X-769139Y1107044D01*
X-767774Y1107564D01*
X-766604Y1108604D01*
G01X-751824Y1122644D02*
Y1107044D01*
G01X-754554Y1117444D02*
X-749094D01*
G01X-733924D02*
Y1107044D01*
G01Y1121604D02*
X-734314Y1121864D01*
Y1122384D01*
X-733924Y1122644D01*
X-733534Y1122384D01*
Y1121864D01*
X-733924Y1121604D01*
G01X-719534Y1117444D02*
X-716024Y1107044D01*
X-712514Y1117444D01*
G01X-701049Y1114064D02*
X-694809D01*
X-695394Y1115884D01*
X-696369Y1116924D01*
X-697734Y1117444D01*
X-699099Y1117184D01*
X-700269Y1116404D01*
X-701049Y1114584D01*
X-701439Y1113024D01*
Y1111464D01*
X-701049Y1109904D01*
X-700074Y1108344D01*
X-698904Y1107304D01*
X-697539Y1107044D01*
X-696174Y1107564D01*
X-694809Y1109124D01*
G01X-662324Y1117444D02*
Y1107044D01*
G01Y1121604D02*
X-662714Y1121864D01*
Y1122384D01*
X-662324Y1122644D01*
X-661934Y1122384D01*
Y1121864D01*
X-662324Y1121604D01*
G01X-647739Y1107044D02*
Y1117444D01*
G01Y1114844D02*
X-646959Y1116144D01*
X-645789Y1117184D01*
X-644229Y1117444D01*
X-642864Y1117184D01*
X-641694Y1116144D01*
X-641109Y1114324D01*
Y1107044D01*
G01X-629839D02*
Y1122644D01*
G01X-623599Y1117444D02*
X-629839Y1111464D01*
G01X-627304Y1113804D02*
X-623209Y1107044D01*
G01X-608624Y1106524D02*
X-609014Y1106784D01*
Y1107304D01*
X-608624Y1107564D01*
X-608234Y1107304D01*
Y1106784D01*
X-608624Y1106524D01*
G01X-2026624Y1175044D02*
Y1190644D01*
X-2021944D01*
X-2020384Y1189864D01*
X-2019214Y1188044D01*
X-2018824Y1185964D01*
X-2019214Y1183884D01*
X-2020189Y1182324D01*
X-2021944Y1181544D01*
X-2026624D01*
G01X-2004824Y1175044D02*
Y1190644D01*
G01X-1983414Y1175044D02*
Y1185444D01*
G01Y1183624D02*
X-1984194Y1184664D01*
X-1985364Y1185184D01*
X-1986729Y1185444D01*
X-1988094Y1184924D01*
X-1989264Y1183884D01*
X-1990044Y1182324D01*
X-1990434Y1180244D01*
X-1990044Y1178164D01*
X-1989264Y1176604D01*
X-1988094Y1175564D01*
X-1986729Y1175044D01*
X-1985364Y1175304D01*
X-1984194Y1176084D01*
X-1983414Y1177124D01*
G01X-1969024Y1190644D02*
Y1175044D01*
G01X-1971754Y1185444D02*
X-1966294D01*
G01X-1951124D02*
Y1175044D01*
G01Y1189604D02*
X-1951514Y1189864D01*
Y1190384D01*
X-1951124Y1190644D01*
X-1950734Y1190384D01*
Y1189864D01*
X-1951124Y1189604D01*
G01X-1936539Y1175044D02*
Y1185444D01*
G01Y1182844D02*
X-1935759Y1184144D01*
X-1934589Y1185184D01*
X-1933029Y1185444D01*
X-1931664Y1185184D01*
X-1930494Y1184144D01*
X-1929909Y1182324D01*
Y1175044D01*
G01X-1918054Y1171144D02*
X-1916689Y1170104D01*
X-1915129Y1169844D01*
X-1913764Y1170104D01*
X-1912594Y1171404D01*
X-1911814Y1173224D01*
Y1185444D01*
G01Y1183364D02*
X-1912594Y1184404D01*
X-1913764Y1185184D01*
X-1915129Y1185444D01*
X-1916689Y1184924D01*
X-1917664Y1183884D01*
X-1918444Y1182064D01*
X-1918834Y1180244D01*
X-1918639Y1178684D01*
X-1917859Y1176864D01*
X-1916689Y1175564D01*
X-1915129Y1175044D01*
X-1913959Y1175304D01*
X-1912594Y1176344D01*
X-1911814Y1177384D01*
G01X-1876014Y1175044D02*
Y1185444D01*
G01Y1183624D02*
X-1876794Y1184664D01*
X-1877964Y1185184D01*
X-1879329Y1185444D01*
X-1880694Y1184924D01*
X-1881864Y1183884D01*
X-1882644Y1182324D01*
X-1883034Y1180244D01*
X-1882644Y1178164D01*
X-1881864Y1176604D01*
X-1880694Y1175564D01*
X-1879329Y1175044D01*
X-1877964Y1175304D01*
X-1876794Y1176084D01*
X-1876014Y1177124D01*
G01X-1864939Y1175044D02*
Y1185444D01*
G01Y1182844D02*
X-1864159Y1184144D01*
X-1862989Y1185184D01*
X-1861429Y1185444D01*
X-1860064Y1185184D01*
X-1858894Y1184144D01*
X-1858309Y1182324D01*
Y1175044D01*
G01X-1840214Y1190644D02*
Y1175044D01*
G01Y1177384D02*
X-1840994Y1176084D01*
X-1842164Y1175304D01*
X-1843529Y1175044D01*
X-1845089Y1175564D01*
X-1846259Y1176864D01*
X-1847039Y1178424D01*
X-1847234Y1180244D01*
X-1847039Y1182064D01*
X-1846259Y1183624D01*
X-1845089Y1184924D01*
X-1843529Y1185444D01*
X-1842164Y1185184D01*
X-1841189Y1184664D01*
X-1840214Y1183624D01*
G01X-1804414Y1175044D02*
Y1185444D01*
G01Y1183624D02*
X-1805194Y1184664D01*
X-1806364Y1185184D01*
X-1807729Y1185444D01*
X-1809094Y1184924D01*
X-1810264Y1183884D01*
X-1811044Y1182324D01*
X-1811434Y1180244D01*
X-1811044Y1178164D01*
X-1810264Y1176604D01*
X-1809094Y1175564D01*
X-1807729Y1175044D01*
X-1806364Y1175304D01*
X-1805194Y1176084D01*
X-1804414Y1177124D01*
G01X-1793339Y1175044D02*
Y1185444D01*
G01Y1182844D02*
X-1792559Y1184144D01*
X-1791389Y1185184D01*
X-1789829Y1185444D01*
X-1788464Y1185184D01*
X-1787294Y1184144D01*
X-1786709Y1182324D01*
Y1175044D01*
G01X-1775439D02*
Y1185444D01*
G01Y1182844D02*
X-1774659Y1184144D01*
X-1773489Y1185184D01*
X-1771929Y1185444D01*
X-1770564Y1185184D01*
X-1769394Y1184144D01*
X-1768809Y1182324D01*
Y1175044D01*
G01X-1757539Y1185444D02*
Y1178164D01*
X-1756759Y1176344D01*
X-1755589Y1175304D01*
X-1754224Y1175044D01*
X-1752859Y1175304D01*
X-1751689Y1176344D01*
X-1750909Y1178164D01*
G01Y1175044D02*
Y1185444D01*
G01X-1736324Y1175044D02*
Y1190644D01*
G01X-1714914Y1175044D02*
Y1185444D01*
G01Y1183624D02*
X-1715694Y1184664D01*
X-1716864Y1185184D01*
X-1718229Y1185444D01*
X-1719594Y1184924D01*
X-1720764Y1183884D01*
X-1721544Y1182324D01*
X-1721934Y1180244D01*
X-1721544Y1178164D01*
X-1720764Y1176604D01*
X-1719594Y1175564D01*
X-1718229Y1175044D01*
X-1716864Y1175304D01*
X-1715694Y1176084D01*
X-1714914Y1177124D01*
G01X-1703254Y1175044D02*
Y1185444D01*
G01Y1183364D02*
X-1702279Y1184404D01*
X-1701304Y1185184D01*
X-1699939Y1185444D01*
X-1698964Y1185184D01*
X-1697794Y1184404D01*
G01X-1667454Y1175044D02*
Y1185444D01*
G01Y1183364D02*
X-1666479Y1184404D01*
X-1665504Y1185184D01*
X-1664139Y1185444D01*
X-1663164Y1185184D01*
X-1661994Y1184404D01*
G01X-1646824Y1185444D02*
Y1175044D01*
G01Y1189604D02*
X-1647214Y1189864D01*
Y1190384D01*
X-1646824Y1190644D01*
X-1646434Y1190384D01*
Y1189864D01*
X-1646824Y1189604D01*
G01X-1632239Y1175044D02*
Y1185444D01*
G01Y1182844D02*
X-1631459Y1184144D01*
X-1630289Y1185184D01*
X-1628729Y1185444D01*
X-1627364Y1185184D01*
X-1626194Y1184144D01*
X-1625609Y1182324D01*
Y1175044D01*
G01X-1613754Y1171144D02*
X-1612389Y1170104D01*
X-1610829Y1169844D01*
X-1609464Y1170104D01*
X-1608294Y1171404D01*
X-1607514Y1173224D01*
Y1185444D01*
G01Y1183364D02*
X-1608294Y1184404D01*
X-1609464Y1185184D01*
X-1610829Y1185444D01*
X-1612389Y1184924D01*
X-1613364Y1183884D01*
X-1614144Y1182064D01*
X-1614534Y1180244D01*
X-1614339Y1178684D01*
X-1613559Y1176864D01*
X-1612389Y1175564D01*
X-1610829Y1175044D01*
X-1609659Y1175304D01*
X-1608294Y1176344D01*
X-1607514Y1177384D01*
G01X-1596049Y1176864D02*
X-1595074Y1175824D01*
X-1593709Y1175044D01*
X-1592539D01*
X-1591369Y1175564D01*
X-1590589Y1176344D01*
X-1590199Y1177384D01*
X-1590394Y1178944D01*
X-1591174Y1179724D01*
X-1594684Y1181284D01*
X-1595464Y1183104D01*
X-1595074Y1184404D01*
X-1594294Y1185184D01*
X-1593124Y1185444D01*
X-1591954Y1185184D01*
X-1590784Y1184404D01*
G01X-1563174Y1175044D02*
Y1185444D01*
G01Y1182584D02*
X-1562589Y1183884D01*
X-1561614Y1184924D01*
X-1560249Y1185444D01*
X-1558884Y1184924D01*
X-1557909Y1183884D01*
X-1557324Y1182584D01*
Y1175044D01*
G01Y1182584D02*
X-1556739Y1183884D01*
X-1555764Y1184924D01*
X-1554399Y1185444D01*
X-1553034Y1184924D01*
X-1552059Y1183884D01*
X-1551474Y1182324D01*
Y1175044D01*
G01X-1542739Y1185444D02*
Y1178164D01*
X-1541959Y1176344D01*
X-1540789Y1175304D01*
X-1539424Y1175044D01*
X-1538059Y1175304D01*
X-1536889Y1176344D01*
X-1536109Y1178164D01*
G01Y1175044D02*
Y1185444D01*
G01X-1524449Y1176864D02*
X-1523474Y1175824D01*
X-1522109Y1175044D01*
X-1520939D01*
X-1519769Y1175564D01*
X-1518989Y1176344D01*
X-1518599Y1177384D01*
X-1518794Y1178944D01*
X-1519574Y1179724D01*
X-1523084Y1181284D01*
X-1523864Y1183104D01*
X-1523474Y1184404D01*
X-1522694Y1185184D01*
X-1521524Y1185444D01*
X-1520354Y1185184D01*
X-1519184Y1184404D01*
G01X-1503624Y1190644D02*
Y1175044D01*
G01X-1506354Y1185444D02*
X-1500894D01*
G01X-1473674Y1175044D02*
Y1185444D01*
G01Y1182584D02*
X-1473089Y1183884D01*
X-1472114Y1184924D01*
X-1470749Y1185444D01*
X-1469384Y1184924D01*
X-1468409Y1183884D01*
X-1467824Y1182584D01*
Y1175044D01*
G01Y1182584D02*
X-1467239Y1183884D01*
X-1466264Y1184924D01*
X-1464899Y1185444D01*
X-1463534Y1184924D01*
X-1462559Y1183884D01*
X-1461974Y1182324D01*
Y1175044D01*
G01X-1452849Y1182064D02*
X-1446609D01*
X-1447194Y1183884D01*
X-1448169Y1184924D01*
X-1449534Y1185444D01*
X-1450899Y1185184D01*
X-1452069Y1184404D01*
X-1452849Y1182584D01*
X-1453239Y1181024D01*
Y1179464D01*
X-1452849Y1177904D01*
X-1451874Y1176344D01*
X-1450704Y1175304D01*
X-1449339Y1175044D01*
X-1447974Y1175564D01*
X-1446609Y1177124D01*
G01X-1434949Y1182064D02*
X-1428709D01*
X-1429294Y1183884D01*
X-1430269Y1184924D01*
X-1431634Y1185444D01*
X-1432999Y1185184D01*
X-1434169Y1184404D01*
X-1434949Y1182584D01*
X-1435339Y1181024D01*
Y1179464D01*
X-1434949Y1177904D01*
X-1433974Y1176344D01*
X-1432804Y1175304D01*
X-1431439Y1175044D01*
X-1430074Y1175564D01*
X-1428709Y1177124D01*
G01X-1414124Y1190644D02*
Y1175044D01*
G01X-1416854Y1185444D02*
X-1411394D01*
G01X-1378324Y1190644D02*
Y1175044D01*
G01X-1381054Y1185444D02*
X-1375594D01*
G01X-1363739Y1175044D02*
Y1190644D01*
G01Y1183104D02*
X-1362764Y1184404D01*
X-1361789Y1185184D01*
X-1360229Y1185444D01*
X-1359059Y1185184D01*
X-1357694Y1184144D01*
X-1357109Y1182584D01*
Y1175044D01*
G01X-1345449Y1182064D02*
X-1339209D01*
X-1339794Y1183884D01*
X-1340769Y1184924D01*
X-1342134Y1185444D01*
X-1343499Y1185184D01*
X-1344669Y1184404D01*
X-1345449Y1182584D01*
X-1345839Y1181024D01*
Y1179464D01*
X-1345449Y1177904D01*
X-1344474Y1176344D01*
X-1343304Y1175304D01*
X-1341939Y1175044D01*
X-1340574Y1175564D01*
X-1339209Y1177124D01*
G01X-1302434Y1189344D02*
X-1303604Y1190124D01*
X-1304969Y1190644D01*
X-1306529D01*
X-1308284Y1189864D01*
X-1309649Y1188564D01*
X-1310624Y1187004D01*
X-1311404Y1184404D01*
X-1311599Y1182064D01*
X-1311209Y1179724D01*
X-1310624Y1178164D01*
X-1309454Y1176604D01*
X-1308089Y1175564D01*
X-1306724Y1175044D01*
X-1305359D01*
X-1303994Y1175564D01*
X-1302824Y1176344D01*
X-1301849Y1177384D01*
G01X-1288824Y1175044D02*
Y1190644D01*
G01X-1267414Y1175044D02*
Y1185444D01*
G01Y1183624D02*
X-1268194Y1184664D01*
X-1269364Y1185184D01*
X-1270729Y1185444D01*
X-1272094Y1184924D01*
X-1273264Y1183884D01*
X-1274044Y1182324D01*
X-1274434Y1180244D01*
X-1274044Y1178164D01*
X-1273264Y1176604D01*
X-1272094Y1175564D01*
X-1270729Y1175044D01*
X-1269364Y1175304D01*
X-1268194Y1176084D01*
X-1267414Y1177124D01*
G01X-1255949Y1176864D02*
X-1254974Y1175824D01*
X-1253609Y1175044D01*
X-1252439D01*
X-1251269Y1175564D01*
X-1250489Y1176344D01*
X-1250099Y1177384D01*
X-1250294Y1178944D01*
X-1251074Y1179724D01*
X-1254584Y1181284D01*
X-1255364Y1183104D01*
X-1254974Y1184404D01*
X-1254194Y1185184D01*
X-1253024Y1185444D01*
X-1251854Y1185184D01*
X-1250684Y1184404D01*
G01X-1238049Y1176864D02*
X-1237074Y1175824D01*
X-1235709Y1175044D01*
X-1234539D01*
X-1233369Y1175564D01*
X-1232589Y1176344D01*
X-1232199Y1177384D01*
X-1232394Y1178944D01*
X-1233174Y1179724D01*
X-1236684Y1181284D01*
X-1237464Y1183104D01*
X-1237074Y1184404D01*
X-1236294Y1185184D01*
X-1235124Y1185444D01*
X-1233954Y1185184D01*
X-1232784Y1184404D01*
G01X-1203614Y1178164D02*
X-1202444Y1176344D01*
X-1200884Y1175304D01*
X-1199129Y1175044D01*
X-1197569Y1175304D01*
X-1196009Y1176604D01*
X-1195034Y1178164D01*
X-1194839Y1179724D01*
X-1195229Y1181544D01*
X-1196594Y1182844D01*
X-1197959Y1183364D01*
X-1199714D01*
G01X-1197959D02*
X-1196789Y1184144D01*
X-1195814Y1185444D01*
X-1195424Y1187004D01*
X-1195814Y1188564D01*
X-1196789Y1189864D01*
X-1198544Y1190644D01*
X-1200299Y1190384D01*
X-1202054Y1189344D01*
G01X-1166449Y1176864D02*
X-1165474Y1175824D01*
X-1164109Y1175044D01*
X-1162939D01*
X-1161769Y1175564D01*
X-1160989Y1176344D01*
X-1160599Y1177384D01*
X-1160794Y1178944D01*
X-1161574Y1179724D01*
X-1165084Y1181284D01*
X-1165864Y1183104D01*
X-1165474Y1184404D01*
X-1164694Y1185184D01*
X-1163524Y1185444D01*
X-1162354Y1185184D01*
X-1161184Y1184404D01*
G01X-1149134Y1169844D02*
Y1185444D01*
G01Y1183104D02*
X-1148159Y1184404D01*
X-1147184Y1185184D01*
X-1145624Y1185444D01*
X-1144259Y1185184D01*
X-1142894Y1183884D01*
X-1142309Y1182064D01*
X-1142114Y1180244D01*
X-1142309Y1178424D01*
X-1142894Y1176604D01*
X-1144064Y1175564D01*
X-1145624Y1175044D01*
X-1146989Y1175304D01*
X-1148354Y1176084D01*
X-1149134Y1177124D01*
G01X-1130649Y1182064D02*
X-1124409D01*
X-1124994Y1183884D01*
X-1125969Y1184924D01*
X-1127334Y1185444D01*
X-1128699Y1185184D01*
X-1129869Y1184404D01*
X-1130649Y1182584D01*
X-1131039Y1181024D01*
Y1179464D01*
X-1130649Y1177904D01*
X-1129674Y1176344D01*
X-1128504Y1175304D01*
X-1127139Y1175044D01*
X-1125774Y1175564D01*
X-1124409Y1177124D01*
G01X-1106704Y1184144D02*
X-1108069Y1185184D01*
X-1109239Y1185444D01*
X-1110799Y1184924D01*
X-1111969Y1183884D01*
X-1112749Y1182064D01*
X-1112944Y1180244D01*
X-1112749Y1178424D01*
X-1111969Y1176864D01*
X-1110799Y1175564D01*
X-1109239Y1175044D01*
X-1107874Y1175564D01*
X-1106704Y1176604D01*
G01X-1091924Y1185444D02*
Y1175044D01*
G01Y1189604D02*
X-1092314Y1189864D01*
Y1190384D01*
X-1091924Y1190644D01*
X-1091534Y1190384D01*
Y1189864D01*
X-1091924Y1189604D01*
G01X-1075194Y1175044D02*
Y1188304D01*
X-1074804Y1189604D01*
X-1074024Y1190384D01*
X-1072854Y1190644D01*
X-1071684Y1190124D01*
X-1071099Y1188824D01*
G01X-1073439Y1184404D02*
X-1077339D01*
G01X-1056124Y1185444D02*
Y1175044D01*
G01Y1189604D02*
X-1056514Y1189864D01*
Y1190384D01*
X-1056124Y1190644D01*
X-1055734Y1190384D01*
Y1189864D01*
X-1056124Y1189604D01*
G01X-1035104Y1184144D02*
X-1036469Y1185184D01*
X-1037639Y1185444D01*
X-1039199Y1184924D01*
X-1040369Y1183884D01*
X-1041149Y1182064D01*
X-1041344Y1180244D01*
X-1041149Y1178424D01*
X-1040369Y1176864D01*
X-1039199Y1175564D01*
X-1037639Y1175044D01*
X-1036274Y1175564D01*
X-1035104Y1176604D01*
G01X-1016814Y1175044D02*
Y1185444D01*
G01Y1183624D02*
X-1017594Y1184664D01*
X-1018764Y1185184D01*
X-1020129Y1185444D01*
X-1021494Y1184924D01*
X-1022664Y1183884D01*
X-1023444Y1182324D01*
X-1023834Y1180244D01*
X-1023444Y1178164D01*
X-1022664Y1176604D01*
X-1021494Y1175564D01*
X-1020129Y1175044D01*
X-1018764Y1175304D01*
X-1017594Y1176084D01*
X-1016814Y1177124D01*
G01X-1002424Y1190644D02*
Y1175044D01*
G01X-1005154Y1185444D02*
X-999694D01*
G01X-984524D02*
Y1175044D01*
G01Y1189604D02*
X-984914Y1189864D01*
Y1190384D01*
X-984524Y1190644D01*
X-984134Y1190384D01*
Y1189864D01*
X-984524Y1189604D01*
G01X-966624Y1175044D02*
X-967794Y1175304D01*
X-968964Y1176344D01*
X-969744Y1178164D01*
X-970134Y1180244D01*
X-969744Y1182324D01*
X-968964Y1184144D01*
X-967794Y1185184D01*
X-966624Y1185444D01*
X-965454Y1185184D01*
X-964284Y1184144D01*
X-963504Y1182324D01*
X-963309Y1180244D01*
X-963504Y1178164D01*
X-964284Y1176344D01*
X-965454Y1175304D01*
X-966624Y1175044D01*
G01X-952039D02*
Y1185444D01*
G01Y1182844D02*
X-951259Y1184144D01*
X-950089Y1185184D01*
X-948529Y1185444D01*
X-947164Y1185184D01*
X-945994Y1184144D01*
X-945409Y1182324D01*
Y1175044D01*
G01X-930824Y1174524D02*
X-931214Y1174784D01*
Y1175304D01*
X-930824Y1175564D01*
X-930434Y1175304D01*
Y1174784D01*
X-930824Y1174524D01*
G01X-1982050Y-1703000D02*
X-1984570Y-1703833D01*
X-1986460Y-1705917D01*
X-1987720Y-1708416D01*
X-1988665Y-1711750D01*
X-1988980Y-1715500D01*
X-1988665Y-1719250D01*
X-1987720Y-1722584D01*
X-1986460Y-1725084D01*
X-1984570Y-1727167D01*
X-1982050Y-1728000D01*
X-1979530Y-1727167D01*
X-1977640Y-1725084D01*
X-1976380Y-1722584D01*
X-1975435Y-1719250D01*
X-1975120Y-1715500D01*
X-1975435Y-1711750D01*
X-1976380Y-1708416D01*
X-1977640Y-1705917D01*
X-1979530Y-1703833D01*
X-1982050Y-1703000D01*
G01X-1956850Y-1728000D02*
Y-1703000D01*
X-1960630Y-1708000D01*
G01Y-1728000D02*
X-1953071D01*
G01X-149270Y11050D02*
X-149580Y11259D01*
Y11675D01*
X-149270Y11884D01*
X-148960Y11675D01*
Y11259D01*
X-149270Y11050D01*
G01X-136870Y11467D02*
Y23967D01*
X-138730Y21467D01*
G01Y11467D02*
X-135010D01*
G01X-124780D02*
X-124470Y14175D01*
X-124005Y16467D01*
X-123385Y18550D01*
X-122610Y20842D01*
X-121370Y23967D01*
X-127570D01*
G01X-112380Y11467D02*
X-112070Y14175D01*
X-111605Y16467D01*
X-110985Y18550D01*
X-110210Y20842D01*
X-108970Y23967D01*
X-115170D01*
G01X-102615Y21884D02*
X-101685Y23133D01*
X-100600Y23759D01*
X-99360Y23967D01*
X-97810Y23550D01*
X-96725Y22509D01*
X-96415Y21259D01*
X-96570Y20008D01*
X-97190Y18967D01*
X-100290Y16884D01*
X-101685Y15425D01*
X-102615Y13342D01*
X-102925Y11467D01*
X-96415D01*
G01X-149270Y43530D02*
X-149580Y43739D01*
Y44155D01*
X-149270Y44364D01*
X-148960Y44155D01*
Y43739D01*
X-149270Y43530D01*
G01X-140280Y45822D02*
X-139350Y44780D01*
X-138265Y44155D01*
X-136870Y43947D01*
X-135475Y44364D01*
X-134390Y45197D01*
X-133615Y46655D01*
X-133460Y48322D01*
X-133770Y49989D01*
X-134545Y51030D01*
X-135630Y51864D01*
X-136715Y52072D01*
X-137800Y51864D01*
X-139195Y51030D01*
X-138730Y56447D01*
X-134545D01*
G01X-124470D02*
X-125710Y56030D01*
X-126640Y54989D01*
X-127260Y53739D01*
X-127725Y52072D01*
X-127880Y50197D01*
X-127725Y48322D01*
X-127260Y46655D01*
X-126640Y45405D01*
X-125710Y44364D01*
X-124470Y43947D01*
X-123230Y44364D01*
X-122300Y45405D01*
X-121680Y46655D01*
X-121215Y48322D01*
X-121060Y50197D01*
X-121215Y52072D01*
X-121680Y53739D01*
X-122300Y54989D01*
X-123230Y56030D01*
X-124470Y56447D01*
G01X-115015Y54364D02*
X-114085Y55613D01*
X-113000Y56239D01*
X-111760Y56447D01*
X-110210Y56030D01*
X-109125Y54989D01*
X-108815Y53739D01*
X-108970Y52488D01*
X-109590Y51447D01*
X-112690Y49364D01*
X-114085Y47905D01*
X-115015Y45822D01*
X-115325Y43947D01*
X-108815D01*
G01X-99670Y56447D02*
X-100910Y56030D01*
X-101840Y54989D01*
X-102460Y53739D01*
X-102925Y52072D01*
X-103080Y50197D01*
X-102925Y48322D01*
X-102460Y46655D01*
X-101840Y45405D01*
X-100910Y44364D01*
X-99670Y43947D01*
X-98430Y44364D01*
X-97500Y45405D01*
X-96880Y46655D01*
X-96415Y48322D01*
X-96260Y50197D01*
X-96415Y52072D01*
X-96880Y53739D01*
X-97500Y54989D01*
X-98430Y56030D01*
X-99670Y56447D01*
G01X-123390Y431348D02*
Y443848D01*
X-129125Y434890D01*
X-121375D01*
G01X-112850Y430931D02*
X-113160Y431140D01*
Y431556D01*
X-112850Y431765D01*
X-112540Y431556D01*
Y431140D01*
X-112850Y430931D01*
G01X-103860Y433848D02*
X-102930Y432389D01*
X-101690Y431556D01*
X-100295Y431348D01*
X-99055Y431556D01*
X-97815Y432598D01*
X-97040Y433848D01*
X-96885Y435098D01*
X-97195Y436556D01*
X-98280Y437598D01*
X-99365Y438015D01*
X-100760D01*
G01X-99365D02*
X-98435Y438640D01*
X-97660Y439681D01*
X-97350Y440931D01*
X-97660Y442181D01*
X-98435Y443223D01*
X-99830Y443848D01*
X-101225Y443640D01*
X-102620Y442806D01*
G01X-88360Y431348D02*
X-88050Y434056D01*
X-87585Y436348D01*
X-86965Y438431D01*
X-86190Y440723D01*
X-84950Y443848D01*
X-91150D01*
G01X-78595Y436556D02*
X-77510Y438015D01*
X-76580Y438848D01*
X-75340Y439265D01*
X-74255Y438848D01*
X-73480Y438015D01*
X-72860Y436765D01*
X-72705Y435306D01*
X-72860Y434056D01*
X-73480Y432806D01*
X-74410Y431765D01*
X-75495Y431348D01*
X-76735Y431765D01*
X-77820Y433014D01*
X-78440Y434890D01*
X-78595Y436973D01*
X-78285Y439681D01*
X-77820Y441140D01*
X-77045Y442598D01*
X-75960Y443640D01*
X-74875Y443848D01*
X-73790Y443431D01*
X-73015Y442390D01*
G01X-63250Y443848D02*
X-64490Y443431D01*
X-65420Y442390D01*
X-66040Y441140D01*
X-66505Y439473D01*
X-66660Y437598D01*
X-66505Y435723D01*
X-66040Y434056D01*
X-65420Y432806D01*
X-64490Y431765D01*
X-63250Y431348D01*
X-62010Y431765D01*
X-61080Y432806D01*
X-60460Y434056D01*
X-59995Y435723D01*
X-59840Y437598D01*
X-59995Y439473D01*
X-60460Y441140D01*
X-61080Y442390D01*
X-62010Y443431D01*
X-63250Y443848D01*
G01X45118Y17717D02*
X-85645D01*
G01X52992Y50197D02*
X-85645D01*
G01X-71830Y6250D02*
X-73070Y5833D01*
X-74000Y4792D01*
X-74620Y3542D01*
X-75085Y1875D01*
X-75240Y0D01*
X-75085Y-1875D01*
X-74620Y-3542D01*
X-74000Y-4792D01*
X-73070Y-5833D01*
X-71830Y-6250D01*
X-70590Y-5833D01*
X-69660Y-4792D01*
X-69040Y-3542D01*
X-68575Y-1875D01*
X-68420Y0D01*
X-68575Y1875D01*
X-69040Y3542D01*
X-69660Y4792D01*
X-70590Y5833D01*
X-71830Y6250D01*
G01X-48307Y-229439D02*
X-48617Y-229230D01*
Y-228814D01*
X-48307Y-228605D01*
X-47997Y-228814D01*
Y-229230D01*
X-48307Y-229439D01*
G01X-35907Y-216522D02*
X-37147Y-216939D01*
X-38077Y-217980D01*
X-38697Y-219230D01*
X-39162Y-220897D01*
X-39317Y-222772D01*
X-39162Y-224647D01*
X-38697Y-226314D01*
X-38077Y-227564D01*
X-37147Y-228605D01*
X-35907Y-229022D01*
X-34667Y-228605D01*
X-33737Y-227564D01*
X-33117Y-226314D01*
X-32652Y-224647D01*
X-32497Y-222772D01*
X-32652Y-220897D01*
X-33117Y-219230D01*
X-33737Y-217980D01*
X-34667Y-216939D01*
X-35907Y-216522D01*
G01X-26452Y-218605D02*
X-25522Y-217356D01*
X-24437Y-216730D01*
X-23197Y-216522D01*
X-21647Y-216939D01*
X-20562Y-217980D01*
X-20252Y-219230D01*
X-20407Y-220481D01*
X-21027Y-221522D01*
X-24127Y-223605D01*
X-25522Y-225064D01*
X-26452Y-227147D01*
X-26762Y-229022D01*
X-20252D01*
G01X-14517Y-227147D02*
X-13587Y-228189D01*
X-12502Y-228814D01*
X-11107Y-229022D01*
X-9712Y-228605D01*
X-8627Y-227772D01*
X-7852Y-226314D01*
X-7697Y-224647D01*
X-8007Y-222980D01*
X-8782Y-221939D01*
X-9867Y-221105D01*
X-10952Y-220897D01*
X-12037Y-221105D01*
X-13432Y-221939D01*
X-12967Y-216522D01*
X-8782D01*
G01X-1652Y-223814D02*
X-567Y-222355D01*
X363Y-221522D01*
X1603Y-221105D01*
X2688Y-221522D01*
X3463Y-222355D01*
X4083Y-223605D01*
X4238Y-225064D01*
X4083Y-226314D01*
X3463Y-227564D01*
X2533Y-228605D01*
X1448Y-229022D01*
X208Y-228605D01*
X-877Y-227356D01*
X-1497Y-225480D01*
X-1652Y-223397D01*
X-1342Y-220689D01*
X-877Y-219230D01*
X-102Y-217772D01*
X983Y-216730D01*
X2068Y-216522D01*
X3153Y-216939D01*
X3928Y-217980D01*
G01X24388Y-224855D02*
X28108D01*
G01X26093Y-222147D02*
Y-227564D01*
G01X35703Y-229439D02*
X41283Y-216522D01*
G01X48878Y-224855D02*
X52908D01*
G01X63293Y-216522D02*
X62053Y-216939D01*
X61123Y-217980D01*
X60503Y-219230D01*
X60038Y-220897D01*
X59883Y-222772D01*
X60038Y-224647D01*
X60503Y-226314D01*
X61123Y-227564D01*
X62053Y-228605D01*
X63293Y-229022D01*
X64533Y-228605D01*
X65463Y-227564D01*
X66083Y-226314D01*
X66548Y-224647D01*
X66703Y-222772D01*
X66548Y-220897D01*
X66083Y-219230D01*
X65463Y-217980D01*
X64533Y-216939D01*
X63293Y-216522D01*
G01X75693Y-229439D02*
X75383Y-229230D01*
Y-228814D01*
X75693Y-228605D01*
X76003Y-228814D01*
Y-229230D01*
X75693Y-229439D01*
G01X88093Y-216522D02*
X86853Y-216939D01*
X85923Y-217980D01*
X85303Y-219230D01*
X84838Y-220897D01*
X84683Y-222772D01*
X84838Y-224647D01*
X85303Y-226314D01*
X85923Y-227564D01*
X86853Y-228605D01*
X88093Y-229022D01*
X89333Y-228605D01*
X90263Y-227564D01*
X90883Y-226314D01*
X91348Y-224647D01*
X91503Y-222772D01*
X91348Y-220897D01*
X90883Y-219230D01*
X90263Y-217980D01*
X89333Y-216939D01*
X88093Y-216522D01*
G01X100493D02*
X99253Y-216939D01*
X98323Y-217980D01*
X97703Y-219230D01*
X97238Y-220897D01*
X97083Y-222772D01*
X97238Y-224647D01*
X97703Y-226314D01*
X98323Y-227564D01*
X99253Y-228605D01*
X100493Y-229022D01*
X101733Y-228605D01*
X102663Y-227564D01*
X103283Y-226314D01*
X103748Y-224647D01*
X103903Y-222772D01*
X103748Y-220897D01*
X103283Y-219230D01*
X102663Y-217980D01*
X101733Y-216939D01*
X100493Y-216522D01*
G01X109483Y-226522D02*
X110413Y-227981D01*
X111653Y-228814D01*
X113048Y-229022D01*
X114288Y-228814D01*
X115528Y-227772D01*
X116303Y-226522D01*
X116458Y-225272D01*
X116148Y-223814D01*
X115063Y-222772D01*
X113978Y-222355D01*
X112583D01*
G01X113978D02*
X114908Y-221730D01*
X115683Y-220689D01*
X115993Y-219439D01*
X115683Y-218189D01*
X114908Y-217147D01*
X113513Y-216522D01*
X112118Y-216730D01*
X110723Y-217564D01*
G01X-10000Y0D02*
X-57805D01*
G01X-6063Y437598D02*
X-49225D01*
G01X-11633Y-271176D02*
X-11943Y-270967D01*
Y-270551D01*
X-11633Y-270342D01*
X-11323Y-270551D01*
Y-270967D01*
X-11633Y-271176D01*
G01X767Y-258259D02*
X-473Y-258676D01*
X-1403Y-259717D01*
X-2023Y-260967D01*
X-2488Y-262634D01*
X-2643Y-264509D01*
X-2488Y-266384D01*
X-2023Y-268051D01*
X-1403Y-269301D01*
X-473Y-270342D01*
X767Y-270759D01*
X2007Y-270342D01*
X2937Y-269301D01*
X3557Y-268051D01*
X4022Y-266384D01*
X4177Y-264509D01*
X4022Y-262634D01*
X3557Y-260967D01*
X2937Y-259717D01*
X2007Y-258676D01*
X767Y-258259D01*
G01X10222Y-260342D02*
X11152Y-259093D01*
X12237Y-258467D01*
X13477Y-258259D01*
X15027Y-258676D01*
X16112Y-259717D01*
X16422Y-260967D01*
X16267Y-262218D01*
X15647Y-263259D01*
X12547Y-265342D01*
X11152Y-266801D01*
X10222Y-268884D01*
X9912Y-270759D01*
X16422D01*
G01X25567D02*
Y-258259D01*
X23707Y-260759D01*
G01Y-270759D02*
X27427D01*
G01X37657D02*
X37967Y-268051D01*
X38432Y-265759D01*
X39052Y-263676D01*
X39827Y-261384D01*
X41067Y-258259D01*
X34867D01*
G01X61062Y-266592D02*
X64782D01*
G01X62767Y-263884D02*
Y-269301D01*
G01X72377Y-271176D02*
X77957Y-258259D01*
G01X85552Y-266592D02*
X89582D01*
G01X112367Y-258259D02*
X111127Y-258676D01*
X110197Y-259717D01*
X109577Y-260967D01*
X109112Y-262634D01*
X108957Y-264509D01*
X109112Y-266384D01*
X109577Y-268051D01*
X110197Y-269301D01*
X111127Y-270342D01*
X112367Y-270759D01*
X113607Y-270342D01*
X114537Y-269301D01*
X115157Y-268051D01*
X115622Y-266384D01*
X115777Y-264509D01*
X115622Y-262634D01*
X115157Y-260967D01*
X114537Y-259717D01*
X113607Y-258676D01*
X112367Y-258259D01*
G01X124767Y-271176D02*
X124457Y-270967D01*
Y-270551D01*
X124767Y-270342D01*
X125077Y-270551D01*
Y-270967D01*
X124767Y-271176D01*
G01X137167Y-258259D02*
X135927Y-258676D01*
X134997Y-259717D01*
X134377Y-260967D01*
X133912Y-262634D01*
X133757Y-264509D01*
X133912Y-266384D01*
X134377Y-268051D01*
X134997Y-269301D01*
X135927Y-270342D01*
X137167Y-270759D01*
X138407Y-270342D01*
X139337Y-269301D01*
X139957Y-268051D01*
X140422Y-266384D01*
X140577Y-264509D01*
X140422Y-262634D01*
X139957Y-260967D01*
X139337Y-259717D01*
X138407Y-258676D01*
X137167Y-258259D01*
G01X149567D02*
X148327Y-258676D01*
X147397Y-259717D01*
X146777Y-260967D01*
X146312Y-262634D01*
X146157Y-264509D01*
X146312Y-266384D01*
X146777Y-268051D01*
X147397Y-269301D01*
X148327Y-270342D01*
X149567Y-270759D01*
X150807Y-270342D01*
X151737Y-269301D01*
X152357Y-268051D01*
X152822Y-266384D01*
X152977Y-264509D01*
X152822Y-262634D01*
X152357Y-260967D01*
X151737Y-259717D01*
X150807Y-258676D01*
X149567Y-258259D01*
G01X158557Y-268259D02*
X159487Y-269718D01*
X160727Y-270551D01*
X162122Y-270759D01*
X163362Y-270551D01*
X164602Y-269509D01*
X165377Y-268259D01*
X165532Y-267009D01*
X165222Y-265551D01*
X164137Y-264509D01*
X163052Y-264092D01*
X161657D01*
G01X163052D02*
X163982Y-263467D01*
X164757Y-262426D01*
X165067Y-261176D01*
X164757Y-259926D01*
X163982Y-258884D01*
X162587Y-258259D01*
X161192Y-258467D01*
X159797Y-259301D01*
G01X10000Y0D02*
G03I-10000J0D01*
G01X-6250Y-68800D02*
X-5833Y-70040D01*
X-4792Y-70970D01*
X-3542Y-71590D01*
X-1875Y-72055D01*
X0Y-72210D01*
X1875Y-72055D01*
X3542Y-71590D01*
X4792Y-70970D01*
X5833Y-70040D01*
X6250Y-68800D01*
X5833Y-67560D01*
X4792Y-66630D01*
X3542Y-66010D01*
X1875Y-65545D01*
X0Y-65390D01*
X-1875Y-65545D01*
X-3542Y-66010D01*
X-4792Y-66630D01*
X-5833Y-67560D01*
X-6250Y-68800D01*
G01X0Y-10000D02*
Y-54775D01*
G01X658071Y284646D02*
G03X660039Y286614I0J1968D01*
G01Y433661D01*
G03X656102Y437598I-3937J0D01*
G01X3937D01*
G03X0Y433661I0J-3937D01*
G01Y21654D01*
G03X3937Y17717I3937J0D01*
G01X55118D01*
G03X59055Y21654I0J3937D01*
G01Y46260D01*
G02X62992Y50197I3937J0D01*
G01X127362D01*
G02X131299Y46260I0J-3937D01*
G01Y21654D01*
G03X135236Y17717I3937J0D01*
G01X158858D01*
G03X162795Y21654I0J3937D01*
G01Y43012D01*
G02X177165I7185J0D01*
G01Y1969D01*
X179134Y0D01*
X219291D01*
X221260Y1969D01*
Y29331D01*
G02X228740I3740J0D01*
G01Y1969D01*
X230709Y0D01*
X310236D01*
X312205Y1969D01*
Y46260D01*
G02X316142Y50197I3937J0D01*
G01X656102D01*
G03X660039Y54134I0J3937D01*
G01Y237500D01*
G03X658071Y239469I-1969J1D01*
G01X657211D01*
G02X655243Y241437I0J1968D01*
G01Y282677D01*
G02X657211Y284646I1968J0D01*
G01X658071D01*
G01X-3546Y353232D02*
X-446D01*
Y352312D01*
X-601Y352005D01*
X-963Y351775D01*
X-1376Y351698D01*
X-1789Y351775D01*
X-2099Y351967D01*
X-2254Y352312D01*
Y353232D01*
G01X-704Y348522D02*
X-549Y348752D01*
X-446Y349020D01*
Y349327D01*
X-601Y349672D01*
X-859Y349940D01*
X-1169Y350132D01*
X-1686Y350285D01*
X-2151Y350323D01*
X-2616Y350247D01*
X-2926Y350132D01*
X-3236Y349902D01*
X-3443Y349633D01*
X-3546Y349365D01*
Y349097D01*
X-3443Y348828D01*
X-3288Y348598D01*
X-3081Y348407D01*
G01X-1893Y345958D02*
X-1738Y345805D01*
X-1479Y345690D01*
X-1118Y345613D01*
X-808Y345690D01*
X-601Y345843D01*
X-446Y346112D01*
Y347147D01*
X-3546D01*
Y345882D01*
X-3339Y345613D01*
X-3029Y345460D01*
X-2668Y345383D01*
X-2306Y345460D01*
X-1996Y345690D01*
X-1893Y345958D01*
Y347147D01*
G01X-3546Y339298D02*
Y340832D01*
X-446D01*
Y339298D01*
G01X-1944Y339912D02*
Y340832D01*
G01X-3546Y337808D02*
X-446D01*
Y337042D01*
X-601Y336735D01*
X-808Y336505D01*
X-1118Y336313D01*
X-1479Y336160D01*
X-1996Y336122D01*
X-2513Y336160D01*
X-2874Y336313D01*
X-3184Y336505D01*
X-3391Y336735D01*
X-3546Y337042D01*
Y337808D01*
G01X-1996Y333635D02*
Y332868D01*
X-2926D01*
X-3236Y333098D01*
X-3443Y333367D01*
X-3546Y333750D01*
X-3443Y334133D01*
X-3236Y334402D01*
X-2926Y334632D01*
X-2564Y334785D01*
X-2151Y334862D01*
X-1789D01*
X-1479Y334785D01*
X-1118Y334632D01*
X-808Y334402D01*
X-601Y334172D01*
X-446Y333865D01*
Y333597D01*
X-549Y333290D01*
X-756Y333060D01*
G01X-3546Y329998D02*
Y331532D01*
X-446D01*
Y329998D01*
G01X-1944Y330612D02*
Y331532D01*
G01X4Y355326D02*
Y327905D01*
G01X65722Y-141290D02*
X65513Y-141600D01*
X65097D01*
X64888Y-141290D01*
X65097Y-140980D01*
X65513D01*
X65722Y-141290D01*
G01X63430Y-132300D02*
X64472Y-131370D01*
X65097Y-130285D01*
X65305Y-128890D01*
X64888Y-127495D01*
X64055Y-126410D01*
X62597Y-125635D01*
X60930Y-125480D01*
X59263Y-125790D01*
X58222Y-126565D01*
X57388Y-127650D01*
X57180Y-128735D01*
X57388Y-129820D01*
X58222Y-131215D01*
X52805Y-130750D01*
Y-126565D01*
G01X63847Y-119125D02*
X64888Y-118040D01*
X65305Y-116800D01*
X64888Y-115560D01*
X63639Y-114475D01*
X61763Y-113700D01*
X59888Y-113390D01*
X57597D01*
X55722Y-113700D01*
X54055Y-114475D01*
X53222Y-115405D01*
X52805Y-116490D01*
X53222Y-117730D01*
X54055Y-118660D01*
X55305Y-119280D01*
X56972Y-119590D01*
X58430Y-119280D01*
X59888Y-118505D01*
X60722Y-117575D01*
X60930Y-116490D01*
X60514Y-115250D01*
X59472Y-114320D01*
X57597Y-113390D01*
G01X52805Y-104090D02*
X53222Y-105330D01*
X54263Y-106260D01*
X55513Y-106880D01*
X57180Y-107345D01*
X59055Y-107500D01*
X60930Y-107345D01*
X62597Y-106880D01*
X63847Y-106260D01*
X64888Y-105330D01*
X65305Y-104090D01*
X64888Y-102850D01*
X63847Y-101920D01*
X62597Y-101300D01*
X60930Y-100835D01*
X59055Y-100680D01*
X57180Y-100835D01*
X55513Y-101300D01*
X54263Y-101920D01*
X53222Y-102850D01*
X52805Y-104090D01*
G01X60097Y-94635D02*
X58638Y-93550D01*
X57805Y-92620D01*
X57388Y-91380D01*
X57805Y-90295D01*
X58638Y-89520D01*
X59888Y-88900D01*
X61347Y-88745D01*
X62597Y-88900D01*
X63847Y-89520D01*
X64888Y-90450D01*
X65305Y-91535D01*
X64888Y-92775D01*
X63639Y-93860D01*
X61763Y-94480D01*
X59680Y-94635D01*
X56972Y-94325D01*
X55513Y-93860D01*
X54055Y-93085D01*
X53013Y-92000D01*
X52805Y-90915D01*
X53222Y-89830D01*
X54263Y-89055D01*
G01X59055Y11654D02*
Y-77665D01*
G01X126918Y-222772D02*
X177165D01*
G01X137549Y-145640D02*
X125049D01*
X127549Y-147500D01*
G01X137549D02*
Y-143780D01*
G01X137966Y-133240D02*
X137757Y-133550D01*
X137341D01*
X137132Y-133240D01*
X137341Y-132930D01*
X137757D01*
X137966Y-133240D01*
G01X135049Y-124250D02*
X136508Y-123320D01*
X137341Y-122080D01*
X137549Y-120685D01*
X137341Y-119445D01*
X136299Y-118205D01*
X135049Y-117430D01*
X133799Y-117275D01*
X132341Y-117585D01*
X131299Y-118670D01*
X130882Y-119755D01*
Y-121150D01*
G01Y-119755D02*
X130257Y-118825D01*
X129216Y-118050D01*
X127966Y-117740D01*
X126716Y-118050D01*
X125674Y-118825D01*
X125049Y-120220D01*
X125257Y-121615D01*
X126091Y-123010D01*
G01X137549Y-108440D02*
X125049D01*
X127549Y-110300D01*
G01X137549D02*
Y-106580D01*
G01X135049Y-99450D02*
X136508Y-98520D01*
X137341Y-97280D01*
X137549Y-95885D01*
X137341Y-94645D01*
X136299Y-93405D01*
X135049Y-92630D01*
X133799Y-92475D01*
X132341Y-92785D01*
X131299Y-93870D01*
X130882Y-94955D01*
Y-96350D01*
G01Y-94955D02*
X130257Y-94025D01*
X129216Y-93250D01*
X127966Y-92940D01*
X126716Y-93250D01*
X125674Y-94025D01*
X125049Y-95420D01*
X125257Y-96815D01*
X126091Y-98210D01*
G01X125049Y-83640D02*
X125466Y-84880D01*
X126507Y-85810D01*
X127757Y-86430D01*
X129424Y-86895D01*
X131299Y-87050D01*
X133174Y-86895D01*
X134841Y-86430D01*
X136091Y-85810D01*
X137132Y-84880D01*
X137549Y-83640D01*
X137132Y-82400D01*
X136091Y-81470D01*
X134841Y-80850D01*
X133174Y-80385D01*
X131299Y-80230D01*
X129424Y-80385D01*
X127757Y-80850D01*
X126507Y-81470D01*
X125466Y-82400D01*
X125049Y-83640D01*
G01X131299Y36260D02*
Y-69615D01*
G01X153982Y-146306D02*
X141482D01*
X143982Y-148166D01*
G01X153982D02*
Y-144446D01*
G01X154399Y-133906D02*
X154190Y-134216D01*
X153774D01*
X153565Y-133906D01*
X153774Y-133596D01*
X154190D01*
X154399Y-133906D01*
G01X148774Y-124451D02*
X147315Y-123366D01*
X146482Y-122436D01*
X146065Y-121196D01*
X146482Y-120111D01*
X147315Y-119336D01*
X148565Y-118716D01*
X150024Y-118561D01*
X151274Y-118716D01*
X152524Y-119336D01*
X153565Y-120266D01*
X153982Y-121351D01*
X153565Y-122591D01*
X152316Y-123676D01*
X150440Y-124296D01*
X148357Y-124451D01*
X145649Y-124141D01*
X144190Y-123676D01*
X142732Y-122901D01*
X141690Y-121816D01*
X141482Y-120731D01*
X141899Y-119646D01*
X142940Y-118871D01*
G01X143565Y-112051D02*
X142316Y-111121D01*
X141690Y-110036D01*
X141482Y-108796D01*
X141899Y-107246D01*
X142940Y-106161D01*
X144190Y-105851D01*
X145441Y-106006D01*
X146482Y-106626D01*
X148565Y-109726D01*
X150024Y-111121D01*
X152107Y-112051D01*
X153982Y-112361D01*
Y-105851D01*
G01Y-96706D02*
X153774Y-95621D01*
X153149Y-94381D01*
X152107Y-93606D01*
X150649Y-93296D01*
X149191Y-93606D01*
X147940Y-94536D01*
X147315Y-95931D01*
Y-97481D01*
X146899Y-98411D01*
X145857Y-99186D01*
X144399Y-99496D01*
X142940Y-99031D01*
X141899Y-97946D01*
X141482Y-96706D01*
X141899Y-95466D01*
X142940Y-94381D01*
X144399Y-93916D01*
X145857Y-94226D01*
X146899Y-95001D01*
X147315Y-95931D01*
Y-97481D01*
X147940Y-98876D01*
X149191Y-99806D01*
X150649Y-100116D01*
X152107Y-99806D01*
X153149Y-99031D01*
X153774Y-97791D01*
X153982Y-96706D01*
G01X141482Y-84306D02*
X141899Y-85546D01*
X142940Y-86476D01*
X144190Y-87096D01*
X145857Y-87561D01*
X147732Y-87716D01*
X149607Y-87561D01*
X151274Y-87096D01*
X152524Y-86476D01*
X153565Y-85546D01*
X153982Y-84306D01*
X153565Y-83066D01*
X152524Y-82136D01*
X151274Y-81516D01*
X149607Y-81051D01*
X147732Y-80896D01*
X145857Y-81051D01*
X144190Y-81516D01*
X142940Y-82136D01*
X141899Y-83066D01*
X141482Y-84306D01*
G01X155123Y-660800D02*
X185123D01*
G01X162165Y-225272D02*
X177165Y-222772D01*
X162165Y-220272D01*
Y-225272D01*
G01X172432Y-146140D02*
X159932D01*
X162432Y-148000D01*
G01X172432D02*
Y-144280D01*
G01X172849Y-133740D02*
X172640Y-134050D01*
X172224D01*
X172015Y-133740D01*
X172224Y-133430D01*
X172640D01*
X172849Y-133740D01*
G01X172432Y-121650D02*
X169724Y-121340D01*
X167432Y-120875D01*
X165349Y-120255D01*
X163057Y-119480D01*
X159932Y-118240D01*
Y-124440D01*
G01X172432Y-109250D02*
X169724Y-108940D01*
X167432Y-108475D01*
X165349Y-107855D01*
X163057Y-107080D01*
X159932Y-105840D01*
Y-112040D01*
G01X172432Y-96540D02*
X159932D01*
X162432Y-98400D01*
G01X172432D02*
Y-94680D01*
G01Y-84450D02*
X169724Y-84140D01*
X167432Y-83675D01*
X165349Y-83055D01*
X163057Y-82280D01*
X159932Y-81040D01*
Y-87240D01*
G01X162795Y11654D02*
Y-33362D01*
X156009Y-70281D01*
G01X174600Y-699900D02*
Y-705633D01*
X175000Y-706834D01*
X175800Y-707633D01*
X176800Y-707900D01*
X177800Y-707633D01*
X178600Y-706834D01*
X179000Y-705633D01*
Y-699900D01*
G01X182500Y-707900D02*
Y-699900D01*
X187100Y-707900D01*
Y-699900D01*
G01X191600D02*
X194000D01*
G01X192800D02*
Y-707900D01*
G01X191600D02*
X194000D01*
G01X200800Y-699900D02*
Y-707900D01*
G01X198500Y-699900D02*
X203100D01*
G01X208800Y-708167D02*
X208600Y-708033D01*
Y-707767D01*
X208800Y-707633D01*
X209000Y-707767D01*
Y-708033D01*
X208800Y-708167D01*
G01Y-704567D02*
X208600Y-704433D01*
Y-704167D01*
X208800Y-704033D01*
X209000Y-704167D01*
Y-704433D01*
X208800Y-704567D01*
G01X222200Y-707900D02*
Y-699900D01*
X224800Y-706567D01*
X227400Y-699900D01*
Y-707900D01*
G01X230200D02*
Y-699900D01*
X232800Y-706567D01*
X235400Y-699900D01*
Y-707900D01*
G01X170123Y-663300D02*
X185123Y-660800D01*
X170123Y-658300D01*
Y-663300D01*
G01X172100Y-520400D02*
Y-512400D01*
X174100D01*
X174900Y-512800D01*
X175500Y-513333D01*
X176000Y-514133D01*
X176400Y-515067D01*
X176500Y-516400D01*
X176400Y-517733D01*
X176000Y-518667D01*
X175500Y-519467D01*
X174900Y-520000D01*
X174100Y-520400D01*
X172100D01*
G01X184300D02*
X180300D01*
Y-512400D01*
X184300D01*
G01X182700Y-516267D02*
X180300D01*
G01X190300Y-512400D02*
Y-520400D01*
G01X188000Y-512400D02*
X192600D01*
G01X195800Y-520400D02*
X198300Y-512400D01*
X200800Y-520400D01*
G01X199900Y-517600D02*
X196700D01*
G01X205100Y-512400D02*
X207500D01*
G01X206300D02*
Y-520400D01*
G01X205100D02*
X207500D01*
G01X212300Y-512400D02*
Y-520400D01*
X216300D01*
G01X231100Y-516133D02*
X231500Y-515733D01*
X231800Y-515067D01*
X232000Y-514133D01*
X231800Y-513333D01*
X231400Y-512800D01*
X230700Y-512400D01*
X228000D01*
Y-520400D01*
X231300D01*
X232000Y-519867D01*
X232400Y-519067D01*
X232600Y-518133D01*
X232400Y-517200D01*
X231800Y-516400D01*
X231100Y-516133D01*
X228000D01*
G01X175992Y-264509D02*
X219094D01*
G01X177165Y3725D02*
Y-232772D01*
G01X179724Y3781D02*
Y-232772D01*
G01X209724Y-222772D02*
X179724D01*
G01X194724Y-220272D02*
X179724Y-222772D01*
X194724Y-225272D01*
Y-220272D01*
G01X177165Y33012D02*
Y-36187D01*
X172445Y-70115D01*
G01X185123Y-617400D02*
Y-670800D01*
G01Y-607400D02*
X191123Y-623900D01*
X197723D01*
X203723Y-607400D01*
Y-547400D01*
X201323D01*
G01X197723Y-623900D02*
X224123Y-551300D01*
G01X185123Y-543500D02*
Y-607400D01*
G01Y-562400D02*
X203723D01*
G01X189023Y-539600D02*
G03X185123Y-543500I0J-3900D01*
G01X193823Y-539600D02*
X189023D01*
G01X198323Y-544400D02*
Y-544100D01*
G01D02*
G03X193823Y-539600I-4500J0D01*
G01X198323Y-544400D02*
G03X201323Y-547400I3000J0D01*
G01X198740Y-248203D02*
X228740D01*
G01X201408Y-148586D02*
X200159Y-147656D01*
X199533Y-146571D01*
X199325Y-145331D01*
X199742Y-143781D01*
X200783Y-142696D01*
X202033Y-142386D01*
X203284Y-142541D01*
X204325Y-143161D01*
X206408Y-146261D01*
X207867Y-147656D01*
X209950Y-148586D01*
X211825Y-148896D01*
Y-142386D01*
G01X212242Y-133241D02*
X212033Y-133551D01*
X211617D01*
X211408Y-133241D01*
X211617Y-132931D01*
X212033D01*
X212242Y-133241D01*
G01X201408Y-123786D02*
X200159Y-122856D01*
X199533Y-121771D01*
X199325Y-120531D01*
X199742Y-118981D01*
X200783Y-117896D01*
X202033Y-117586D01*
X203284Y-117741D01*
X204325Y-118361D01*
X206408Y-121461D01*
X207867Y-122856D01*
X209950Y-123786D01*
X211825Y-124096D01*
Y-117586D01*
G01Y-108441D02*
X199325D01*
X201825Y-110301D01*
G01X211825D02*
Y-106581D01*
G01X201408Y-98986D02*
X200159Y-98056D01*
X199533Y-96971D01*
X199325Y-95731D01*
X199742Y-94181D01*
X200783Y-93096D01*
X202033Y-92786D01*
X203284Y-92941D01*
X204325Y-93561D01*
X206408Y-96661D01*
X207867Y-98056D01*
X209950Y-98986D01*
X211825Y-99296D01*
Y-92786D01*
G01X206617Y-86586D02*
X205158Y-85501D01*
X204325Y-84571D01*
X203908Y-83331D01*
X204325Y-82246D01*
X205158Y-81471D01*
X206408Y-80851D01*
X207867Y-80696D01*
X209117Y-80851D01*
X210367Y-81471D01*
X211408Y-82401D01*
X211825Y-83486D01*
X211408Y-84726D01*
X210159Y-85811D01*
X208283Y-86431D01*
X206200Y-86586D01*
X203492Y-86276D01*
X202033Y-85811D01*
X200575Y-85036D01*
X199533Y-83951D01*
X199325Y-82866D01*
X199742Y-81781D01*
X200783Y-81006D01*
G01X203723Y-617400D02*
Y-670800D01*
G01X218723Y-658300D02*
X203723Y-660800D01*
X218723Y-663300D01*
Y-658300D01*
G01X224473Y-660800D02*
X203723D01*
G01X207723Y-623900D02*
X260523D01*
G01X213723Y-607400D02*
X260523D01*
G01X218926Y-554474D02*
X203723Y-554810D01*
X218213Y-559423D01*
X218926Y-554474D01*
G01X206501Y-557360D02*
X221695Y-557976D01*
X207522Y-552466D01*
X206501Y-557360D01*
G01X234869Y-565025D02*
G03X203723Y-554810I-31146J-42375D01*
G01Y-537400D02*
Y-544810D01*
G01X204094Y-267009D02*
X219094Y-264509D01*
X204094Y-262009D01*
Y-267009D01*
G01X213740Y-250703D02*
X228740Y-248203D01*
X213740Y-245703D01*
Y-250703D01*
G01X221260Y19331D02*
Y-18901D01*
X212951Y-69616D01*
G01X226740Y-674400D02*
X228323Y-669400D01*
X229906Y-674400D01*
G01X229336Y-672650D02*
X227310D01*
G01X234816Y-669817D02*
X234436Y-669567D01*
X233993Y-669400D01*
X233486D01*
X232916Y-669650D01*
X232473Y-670067D01*
X232156Y-670567D01*
X231903Y-671400D01*
X231840Y-672150D01*
X231966Y-672900D01*
X232156Y-673400D01*
X232536Y-673900D01*
X232980Y-674233D01*
X233423Y-674400D01*
X233866D01*
X234310Y-674233D01*
X234690Y-673983D01*
X235006Y-673650D01*
G01X237256Y-674400D02*
Y-669400D01*
X238840D01*
X239346Y-669650D01*
X239663Y-669983D01*
X239790Y-670650D01*
X239663Y-671317D01*
X239283Y-671733D01*
X238840Y-671983D01*
X237256D01*
G01X238840D02*
X239790Y-674400D01*
G01X243623D02*
X243116Y-674317D01*
X242673Y-673983D01*
X242293Y-673483D01*
X242040Y-672900D01*
X241913Y-672233D01*
Y-671567D01*
X242040Y-670900D01*
X242293Y-670317D01*
X242673Y-669817D01*
X243116Y-669483D01*
X243623Y-669400D01*
X244130Y-669483D01*
X244573Y-669817D01*
X244953Y-670317D01*
X245206Y-670900D01*
X245333Y-671567D01*
Y-672233D01*
X245206Y-672900D01*
X244953Y-673483D01*
X244573Y-673983D01*
X244130Y-674317D01*
X243623Y-674400D01*
G01X247393Y-673733D02*
X247900Y-674150D01*
X248470Y-674400D01*
X248976D01*
X249483Y-674150D01*
X249863Y-673733D01*
X250053Y-673150D01*
X249926Y-672567D01*
X249610Y-672067D01*
X249040Y-671733D01*
X248280Y-671567D01*
X247836Y-671233D01*
X247646Y-670650D01*
X247773Y-670067D01*
X248090Y-669650D01*
X248533Y-669400D01*
X248976D01*
X249420Y-669567D01*
X249800Y-669983D01*
G01X252493Y-673733D02*
X253000Y-674150D01*
X253570Y-674400D01*
X254076D01*
X254583Y-674150D01*
X254963Y-673733D01*
X255153Y-673150D01*
X255026Y-672567D01*
X254710Y-672067D01*
X254140Y-671733D01*
X253380Y-671567D01*
X252936Y-671233D01*
X252746Y-670650D01*
X252873Y-670067D01*
X253190Y-669650D01*
X253633Y-669400D01*
X254076D01*
X254520Y-669567D01*
X254900Y-669983D01*
G01X262756Y-674400D02*
Y-669400D01*
X264276D01*
X264783Y-669650D01*
X265163Y-670233D01*
X265290Y-670900D01*
X265163Y-671567D01*
X264846Y-672067D01*
X264276Y-672317D01*
X262756D01*
G01X267540Y-674400D02*
X269123Y-669400D01*
X270706Y-674400D01*
G01X270136Y-672650D02*
X268110D01*
G01X272830Y-674400D02*
Y-669400D01*
X274096D01*
X274603Y-669650D01*
X274983Y-669983D01*
X275300Y-670483D01*
X275553Y-671067D01*
X275616Y-671900D01*
X275553Y-672733D01*
X275300Y-673317D01*
X274983Y-673817D01*
X274603Y-674150D01*
X274096Y-674400D01*
X272830D01*
G01X277993Y-673733D02*
X278500Y-674150D01*
X279070Y-674400D01*
X279576D01*
X280083Y-674150D01*
X280463Y-673733D01*
X280653Y-673150D01*
X280526Y-672567D01*
X280210Y-672067D01*
X279640Y-671733D01*
X278880Y-671567D01*
X278436Y-671233D01*
X278246Y-670650D01*
X278373Y-670067D01*
X278690Y-669650D01*
X279133Y-669400D01*
X279576D01*
X280020Y-669567D01*
X280400Y-669983D01*
G01X230123Y-663300D02*
Y-658300D01*
X229363Y-659300D01*
G01Y-663300D02*
X230883D01*
G01X235223Y-663467D02*
X235096Y-663383D01*
Y-663217D01*
X235223Y-663133D01*
X235350Y-663217D01*
Y-663383D01*
X235223Y-663467D01*
G01X238930Y-662550D02*
X239310Y-662967D01*
X239753Y-663217D01*
X240323Y-663300D01*
X240893Y-663133D01*
X241336Y-662800D01*
X241653Y-662217D01*
X241716Y-661550D01*
X241590Y-660883D01*
X241273Y-660467D01*
X240830Y-660133D01*
X240386Y-660050D01*
X239943Y-660133D01*
X239373Y-660467D01*
X239563Y-658300D01*
X241273D01*
G01X245296Y-663300D02*
X245423Y-662217D01*
X245613Y-661300D01*
X245866Y-660467D01*
X246183Y-659550D01*
X246690Y-658300D01*
X244156D01*
G01X226423Y-585800D02*
Y-580800D01*
X225663Y-581800D01*
G01Y-585800D02*
X227183D01*
G01X231523Y-585967D02*
X231396Y-585883D01*
Y-585717D01*
X231523Y-585633D01*
X231650Y-585717D01*
Y-585883D01*
X231523Y-585967D01*
G01X235230Y-584800D02*
X235610Y-585383D01*
X236116Y-585717D01*
X236686Y-585800D01*
X237193Y-585717D01*
X237700Y-585300D01*
X238016Y-584800D01*
X238080Y-584300D01*
X237953Y-583717D01*
X237510Y-583300D01*
X237066Y-583133D01*
X236496D01*
G01X237066D02*
X237446Y-582883D01*
X237763Y-582467D01*
X237890Y-581967D01*
X237763Y-581467D01*
X237446Y-581050D01*
X236876Y-580800D01*
X236306Y-580883D01*
X235736Y-581217D01*
G01X241723Y-580800D02*
X241216Y-580967D01*
X240836Y-581383D01*
X240583Y-581883D01*
X240393Y-582550D01*
X240330Y-583300D01*
X240393Y-584050D01*
X240583Y-584717D01*
X240836Y-585217D01*
X241216Y-585633D01*
X241723Y-585800D01*
X242230Y-585633D01*
X242610Y-585217D01*
X242863Y-584717D01*
X243053Y-584050D01*
X243116Y-583300D01*
X243053Y-582550D01*
X242863Y-581883D01*
X242610Y-581383D01*
X242230Y-580967D01*
X241723Y-580800D01*
G01X225520Y-570858D02*
X225900Y-570358D01*
X226343Y-570108D01*
X226850Y-570025D01*
X227483Y-570192D01*
X227926Y-570608D01*
X228053Y-571108D01*
X227990Y-571608D01*
X227736Y-572025D01*
X226470Y-572858D01*
X225900Y-573442D01*
X225520Y-574275D01*
X225393Y-575025D01*
X228053D01*
G01X231823Y-570025D02*
X231316Y-570192D01*
X230936Y-570608D01*
X230683Y-571108D01*
X230493Y-571775D01*
X230430Y-572525D01*
X230493Y-573275D01*
X230683Y-573942D01*
X230936Y-574442D01*
X231316Y-574858D01*
X231823Y-575025D01*
X232330Y-574858D01*
X232710Y-574442D01*
X232963Y-573942D01*
X233153Y-573275D01*
X233216Y-572525D01*
X233153Y-571775D01*
X232963Y-571108D01*
X232710Y-570608D01*
X232330Y-570192D01*
X231823Y-570025D01*
G01X237523D02*
G03I-1250J0D01*
G01X227540Y-541902D02*
X225113Y-548578D01*
G01X219094Y3781D02*
Y-274509D01*
G01X221260Y3655D02*
Y-274509D01*
G01X251260Y-264509D02*
X221260D01*
G01X236260Y-262009D02*
X221260Y-264509D01*
X236260Y-267009D01*
Y-262009D01*
G01X228740Y19331D02*
Y-258203D01*
G01X230905Y3781D02*
Y-258203D01*
G01X281685Y-248203D02*
X230905D01*
G01X245905Y-245703D02*
X230905Y-248203D01*
X245905Y-250703D01*
Y-245703D01*
G01X228740Y-8031D02*
Y-58900D01*
X245390Y-82570D01*
G01X255423Y-663300D02*
X253523D01*
Y-658300D01*
X255423D01*
G01X253023Y-638900D02*
X250523Y-623900D01*
X248023Y-638900D01*
X253023D01*
G01X250523Y-653900D02*
Y-623900D01*
G01X248023Y-592400D02*
X250523Y-607400D01*
X253023Y-592400D01*
X248023D01*
G01X250523Y-589550D02*
Y-607400D01*
G01X255523Y-580800D02*
X255016Y-580967D01*
X254636Y-581383D01*
X254383Y-581883D01*
X254193Y-582550D01*
X254130Y-583300D01*
X254193Y-584050D01*
X254383Y-584717D01*
X254636Y-585217D01*
X255016Y-585633D01*
X255523Y-585800D01*
X256030Y-585633D01*
X256410Y-585217D01*
X256663Y-584717D01*
X256853Y-584050D01*
X256916Y-583300D01*
X256853Y-582550D01*
X256663Y-581883D01*
X256410Y-581383D01*
X256030Y-580967D01*
X255523Y-580800D01*
G01X260623Y-585967D02*
X260496Y-585883D01*
Y-585717D01*
X260623Y-585633D01*
X260750Y-585717D01*
Y-585883D01*
X260623Y-585967D01*
G01X264520Y-581633D02*
X264900Y-581133D01*
X265343Y-580883D01*
X265850Y-580800D01*
X266483Y-580967D01*
X266926Y-581383D01*
X267053Y-581883D01*
X266990Y-582383D01*
X266736Y-582800D01*
X265470Y-583633D01*
X264900Y-584217D01*
X264520Y-585050D01*
X264393Y-585800D01*
X267053D01*
G01X269430Y-585050D02*
X269810Y-585467D01*
X270253Y-585717D01*
X270823Y-585800D01*
X271393Y-585633D01*
X271836Y-585300D01*
X272153Y-584717D01*
X272216Y-584050D01*
X272090Y-583383D01*
X271773Y-582967D01*
X271330Y-582633D01*
X270886Y-582550D01*
X270443Y-582633D01*
X269873Y-582967D01*
X270063Y-580800D01*
X271773D01*
G01X240626Y-572733D02*
X242146D01*
G01X241323Y-571650D02*
Y-573817D01*
G01X245600Y-572733D02*
X247246D01*
G01X248930Y-574650D02*
X249310Y-575067D01*
X249753Y-575317D01*
X250323Y-575400D01*
X250893Y-575233D01*
X251336Y-574900D01*
X251653Y-574317D01*
X251716Y-573650D01*
X251590Y-572983D01*
X251273Y-572567D01*
X250830Y-572233D01*
X250386Y-572150D01*
X249943Y-572233D01*
X249373Y-572567D01*
X249563Y-570400D01*
X251273D01*
G01X251723Y-585800D02*
X249823D01*
Y-580800D01*
X251723D01*
G01X241393Y-154965D02*
X240144Y-154035D01*
X239518Y-152950D01*
X239310Y-151710D01*
X239727Y-150160D01*
X240768Y-149075D01*
X242018Y-148765D01*
X243269Y-148920D01*
X244310Y-149540D01*
X246393Y-152640D01*
X247852Y-154035D01*
X249935Y-154965D01*
X251810Y-155275D01*
Y-148765D01*
G01X252227Y-139620D02*
X252018Y-139930D01*
X251602D01*
X251393Y-139620D01*
X251602Y-139310D01*
X252018D01*
X252227Y-139620D01*
G01X241393Y-130165D02*
X240144Y-129235D01*
X239518Y-128150D01*
X239310Y-126910D01*
X239727Y-125360D01*
X240768Y-124275D01*
X242018Y-123965D01*
X243269Y-124120D01*
X244310Y-124740D01*
X246393Y-127840D01*
X247852Y-129235D01*
X249935Y-130165D01*
X251810Y-130475D01*
Y-123965D01*
G01Y-114820D02*
X251602Y-113735D01*
X250977Y-112495D01*
X249935Y-111720D01*
X248477Y-111410D01*
X247019Y-111720D01*
X245768Y-112650D01*
X245143Y-114045D01*
Y-115595D01*
X244727Y-116525D01*
X243685Y-117300D01*
X242227Y-117610D01*
X240768Y-117145D01*
X239727Y-116060D01*
X239310Y-114820D01*
X239727Y-113580D01*
X240768Y-112495D01*
X242227Y-112030D01*
X243685Y-112340D01*
X244727Y-113115D01*
X245143Y-114045D01*
Y-115595D01*
X245768Y-116990D01*
X247019Y-117920D01*
X248477Y-118230D01*
X249935Y-117920D01*
X250977Y-117145D01*
X251602Y-115905D01*
X251810Y-114820D01*
G01Y-102730D02*
X249102Y-102420D01*
X246810Y-101955D01*
X244727Y-101335D01*
X242435Y-100560D01*
X239310Y-99320D01*
Y-105520D01*
G01X251810Y-88160D02*
X239310D01*
X248268Y-93895D01*
Y-86145D01*
G01X259223Y-663467D02*
X259096Y-663383D01*
Y-663217D01*
X259223Y-663133D01*
X259350Y-663217D01*
Y-663383D01*
X259223Y-663467D01*
G01X264323Y-658300D02*
X263816Y-658467D01*
X263436Y-658883D01*
X263183Y-659383D01*
X262993Y-660050D01*
X262930Y-660800D01*
X262993Y-661550D01*
X263183Y-662217D01*
X263436Y-662717D01*
X263816Y-663133D01*
X264323Y-663300D01*
X264830Y-663133D01*
X265210Y-662717D01*
X265463Y-662217D01*
X265653Y-661550D01*
X265716Y-660800D01*
X265653Y-660050D01*
X265463Y-659383D01*
X265210Y-658883D01*
X264830Y-658467D01*
X264323Y-658300D01*
G01X268220Y-661217D02*
X268663Y-660633D01*
X269043Y-660300D01*
X269550Y-660133D01*
X269993Y-660300D01*
X270310Y-660633D01*
X270563Y-661133D01*
X270626Y-661717D01*
X270563Y-662217D01*
X270310Y-662717D01*
X269930Y-663133D01*
X269486Y-663300D01*
X268980Y-663133D01*
X268536Y-662633D01*
X268283Y-661883D01*
X268220Y-661050D01*
X268346Y-659967D01*
X268536Y-659383D01*
X268853Y-658800D01*
X269296Y-658383D01*
X269740Y-658300D01*
X270183Y-658467D01*
X270500Y-658883D01*
G01X273320Y-659133D02*
X273700Y-658633D01*
X274143Y-658383D01*
X274650Y-658300D01*
X275283Y-658467D01*
X275726Y-658883D01*
X275853Y-659383D01*
X275790Y-659883D01*
X275536Y-660300D01*
X274270Y-661133D01*
X273700Y-661717D01*
X273320Y-662550D01*
X273193Y-663300D01*
X275853D01*
G01X256523Y-571025D02*
G03I-1250J0D01*
G01X278323Y-663300D02*
X280223D01*
Y-658300D01*
X278323D01*
G01X274623Y-585800D02*
X276523D01*
Y-580800D01*
X274623D01*
G01X279645Y-216954D02*
X309645D01*
G01X295710Y-254870D02*
X295400Y-254661D01*
Y-254245D01*
X295710Y-254036D01*
X296020Y-254245D01*
Y-254661D01*
X295710Y-254870D01*
G01X308110Y-241953D02*
X306870Y-242370D01*
X305940Y-243411D01*
X305320Y-244661D01*
X304855Y-246328D01*
X304700Y-248203D01*
X304855Y-250078D01*
X305320Y-251745D01*
X305940Y-252995D01*
X306870Y-254036D01*
X308110Y-254453D01*
X309350Y-254036D01*
X310280Y-252995D01*
X310900Y-251745D01*
X311365Y-250078D01*
X311520Y-248203D01*
X311365Y-246328D01*
X310900Y-244661D01*
X310280Y-243411D01*
X309350Y-242370D01*
X308110Y-241953D01*
G01X317565Y-244036D02*
X318495Y-242787D01*
X319580Y-242161D01*
X320820Y-241953D01*
X322370Y-242370D01*
X323455Y-243411D01*
X323765Y-244661D01*
X323610Y-245912D01*
X322990Y-246953D01*
X319890Y-249036D01*
X318495Y-250495D01*
X317565Y-252578D01*
X317255Y-254453D01*
X323765D01*
G01X332910D02*
Y-241953D01*
X331050Y-244453D01*
G01Y-254453D02*
X334770D01*
G01X342365Y-249245D02*
X343450Y-247786D01*
X344380Y-246953D01*
X345620Y-246536D01*
X346705Y-246953D01*
X347480Y-247786D01*
X348100Y-249036D01*
X348255Y-250495D01*
X348100Y-251745D01*
X347480Y-252995D01*
X346550Y-254036D01*
X345465Y-254453D01*
X344225Y-254036D01*
X343140Y-252787D01*
X342520Y-250911D01*
X342365Y-248828D01*
X342675Y-246120D01*
X343140Y-244661D01*
X343915Y-243203D01*
X345000Y-242161D01*
X346085Y-241953D01*
X347170Y-242370D01*
X347945Y-243411D01*
G01X368405Y-250286D02*
X372125D01*
G01X370110Y-247578D02*
Y-252995D01*
G01X379720Y-254870D02*
X385300Y-241953D01*
G01X392895Y-250286D02*
X396925D01*
G01X419710Y-241953D02*
X418470Y-242370D01*
X417540Y-243411D01*
X416920Y-244661D01*
X416455Y-246328D01*
X416300Y-248203D01*
X416455Y-250078D01*
X416920Y-251745D01*
X417540Y-252995D01*
X418470Y-254036D01*
X419710Y-254453D01*
X420950Y-254036D01*
X421880Y-252995D01*
X422500Y-251745D01*
X422965Y-250078D01*
X423120Y-248203D01*
X422965Y-246328D01*
X422500Y-244661D01*
X421880Y-243411D01*
X420950Y-242370D01*
X419710Y-241953D01*
G01X432110Y-254870D02*
X431800Y-254661D01*
Y-254245D01*
X432110Y-254036D01*
X432420Y-254245D01*
Y-254661D01*
X432110Y-254870D01*
G01X444510Y-241953D02*
X443270Y-242370D01*
X442340Y-243411D01*
X441720Y-244661D01*
X441255Y-246328D01*
X441100Y-248203D01*
X441255Y-250078D01*
X441720Y-251745D01*
X442340Y-252995D01*
X443270Y-254036D01*
X444510Y-254453D01*
X445750Y-254036D01*
X446680Y-252995D01*
X447300Y-251745D01*
X447765Y-250078D01*
X447920Y-248203D01*
X447765Y-246328D01*
X447300Y-244661D01*
X446680Y-243411D01*
X445750Y-242370D01*
X444510Y-241953D01*
G01X456910D02*
X455670Y-242370D01*
X454740Y-243411D01*
X454120Y-244661D01*
X453655Y-246328D01*
X453500Y-248203D01*
X453655Y-250078D01*
X454120Y-251745D01*
X454740Y-252995D01*
X455670Y-254036D01*
X456910Y-254453D01*
X458150Y-254036D01*
X459080Y-252995D01*
X459700Y-251745D01*
X460165Y-250078D01*
X460320Y-248203D01*
X460165Y-246328D01*
X459700Y-244661D01*
X459080Y-243411D01*
X458150Y-242370D01*
X456910Y-241953D01*
G01X465900Y-251953D02*
X466830Y-253412D01*
X468070Y-254245D01*
X469465Y-254453D01*
X470705Y-254245D01*
X471945Y-253203D01*
X472720Y-251953D01*
X472875Y-250703D01*
X472565Y-249245D01*
X471480Y-248203D01*
X470395Y-247786D01*
X469000D01*
G01X470395D02*
X471325Y-247161D01*
X472100Y-246120D01*
X472410Y-244870D01*
X472100Y-243620D01*
X471325Y-242578D01*
X469930Y-241953D01*
X468535Y-242161D01*
X467140Y-242995D01*
G01X294645Y-219454D02*
X309645Y-216954D01*
X294645Y-214454D01*
Y-219454D01*
G01X309645Y3781D02*
Y-226954D01*
G01X312205Y-8031D02*
Y-226954D01*
G01X350499Y-216954D02*
X312205D01*
G01X327205Y-214454D02*
X312205Y-216954D01*
X327205Y-219454D01*
Y-214454D01*
G01X364524Y-223621D02*
X364214Y-223412D01*
Y-222996D01*
X364524Y-222787D01*
X364834Y-222996D01*
Y-223412D01*
X364524Y-223621D01*
G01X376924Y-210704D02*
X375684Y-211121D01*
X374754Y-212162D01*
X374134Y-213412D01*
X373669Y-215079D01*
X373514Y-216954D01*
X373669Y-218829D01*
X374134Y-220496D01*
X374754Y-221746D01*
X375684Y-222787D01*
X376924Y-223204D01*
X378164Y-222787D01*
X379094Y-221746D01*
X379714Y-220496D01*
X380179Y-218829D01*
X380334Y-216954D01*
X380179Y-215079D01*
X379714Y-213412D01*
X379094Y-212162D01*
X378164Y-211121D01*
X376924Y-210704D01*
G01X386379Y-212787D02*
X387309Y-211538D01*
X388394Y-210912D01*
X389634Y-210704D01*
X391184Y-211121D01*
X392269Y-212162D01*
X392579Y-213412D01*
X392424Y-214663D01*
X391804Y-215704D01*
X388704Y-217787D01*
X387309Y-219246D01*
X386379Y-221329D01*
X386069Y-223204D01*
X392579D01*
G01X398314Y-221329D02*
X399244Y-222371D01*
X400329Y-222996D01*
X401724Y-223204D01*
X403119Y-222787D01*
X404204Y-221954D01*
X404979Y-220496D01*
X405134Y-218829D01*
X404824Y-217162D01*
X404049Y-216121D01*
X402964Y-215287D01*
X401879Y-215079D01*
X400794Y-215287D01*
X399399Y-216121D01*
X399864Y-210704D01*
X404049D01*
G01X411179Y-217996D02*
X412264Y-216537D01*
X413194Y-215704D01*
X414434Y-215287D01*
X415519Y-215704D01*
X416294Y-216537D01*
X416914Y-217787D01*
X417069Y-219246D01*
X416914Y-220496D01*
X416294Y-221746D01*
X415364Y-222787D01*
X414279Y-223204D01*
X413039Y-222787D01*
X411954Y-221538D01*
X411334Y-219662D01*
X411179Y-217579D01*
X411489Y-214871D01*
X411954Y-213412D01*
X412729Y-211954D01*
X413814Y-210912D01*
X414899Y-210704D01*
X415984Y-211121D01*
X416759Y-212162D01*
G01X437219Y-219037D02*
X440939D01*
G01X438924Y-216329D02*
Y-221746D01*
G01X448534Y-223621D02*
X454114Y-210704D01*
G01X461709Y-219037D02*
X465739D01*
G01X488524Y-210704D02*
X487284Y-211121D01*
X486354Y-212162D01*
X485734Y-213412D01*
X485269Y-215079D01*
X485114Y-216954D01*
X485269Y-218829D01*
X485734Y-220496D01*
X486354Y-221746D01*
X487284Y-222787D01*
X488524Y-223204D01*
X489764Y-222787D01*
X490694Y-221746D01*
X491314Y-220496D01*
X491779Y-218829D01*
X491934Y-216954D01*
X491779Y-215079D01*
X491314Y-213412D01*
X490694Y-212162D01*
X489764Y-211121D01*
X488524Y-210704D01*
G01X500924Y-223621D02*
X500614Y-223412D01*
Y-222996D01*
X500924Y-222787D01*
X501234Y-222996D01*
Y-223412D01*
X500924Y-223621D01*
G01X513324Y-210704D02*
X512084Y-211121D01*
X511154Y-212162D01*
X510534Y-213412D01*
X510069Y-215079D01*
X509914Y-216954D01*
X510069Y-218829D01*
X510534Y-220496D01*
X511154Y-221746D01*
X512084Y-222787D01*
X513324Y-223204D01*
X514564Y-222787D01*
X515494Y-221746D01*
X516114Y-220496D01*
X516579Y-218829D01*
X516734Y-216954D01*
X516579Y-215079D01*
X516114Y-213412D01*
X515494Y-212162D01*
X514564Y-211121D01*
X513324Y-210704D01*
G01X525724D02*
X524484Y-211121D01*
X523554Y-212162D01*
X522934Y-213412D01*
X522469Y-215079D01*
X522314Y-216954D01*
X522469Y-218829D01*
X522934Y-220496D01*
X523554Y-221746D01*
X524484Y-222787D01*
X525724Y-223204D01*
X526964Y-222787D01*
X527894Y-221746D01*
X528514Y-220496D01*
X528979Y-218829D01*
X529134Y-216954D01*
X528979Y-215079D01*
X528514Y-213412D01*
X527894Y-212162D01*
X526964Y-211121D01*
X525724Y-210704D01*
G01X534714Y-220704D02*
X535644Y-222163D01*
X536884Y-222996D01*
X538279Y-223204D01*
X539519Y-222996D01*
X540759Y-221954D01*
X541534Y-220704D01*
X541689Y-219454D01*
X541379Y-217996D01*
X540294Y-216954D01*
X539209Y-216537D01*
X537814D01*
G01X539209D02*
X540139Y-215912D01*
X540914Y-214871D01*
X541224Y-213621D01*
X540914Y-212371D01*
X540139Y-211329D01*
X538744Y-210704D01*
X537349Y-210912D01*
X535954Y-211746D01*
G01X661081Y-139355D02*
X659622Y-138270D01*
X658789Y-137340D01*
X658372Y-136100D01*
X658789Y-135015D01*
X659622Y-134240D01*
X660872Y-133620D01*
X662331Y-133465D01*
X663581Y-133620D01*
X664831Y-134240D01*
X665872Y-135170D01*
X666289Y-136255D01*
X665872Y-137495D01*
X664623Y-138580D01*
X662747Y-139200D01*
X660664Y-139355D01*
X657956Y-139045D01*
X656497Y-138580D01*
X655039Y-137805D01*
X653997Y-136720D01*
X653789Y-135635D01*
X654206Y-134550D01*
X655247Y-133775D01*
G01X666706Y-124010D02*
X666497Y-124320D01*
X666081D01*
X665872Y-124010D01*
X666081Y-123700D01*
X666497D01*
X666706Y-124010D01*
G01X661081Y-114555D02*
X659622Y-113470D01*
X658789Y-112540D01*
X658372Y-111300D01*
X658789Y-110215D01*
X659622Y-109440D01*
X660872Y-108820D01*
X662331Y-108665D01*
X663581Y-108820D01*
X664831Y-109440D01*
X665872Y-110370D01*
X666289Y-111455D01*
X665872Y-112695D01*
X664623Y-113780D01*
X662747Y-114400D01*
X660664Y-114555D01*
X657956Y-114245D01*
X656497Y-113780D01*
X655039Y-113005D01*
X653997Y-111920D01*
X653789Y-110835D01*
X654206Y-109750D01*
X655247Y-108975D01*
G01X653789Y-99210D02*
X654206Y-100450D01*
X655247Y-101380D01*
X656497Y-102000D01*
X658164Y-102465D01*
X660039Y-102620D01*
X661914Y-102465D01*
X663581Y-102000D01*
X664831Y-101380D01*
X665872Y-100450D01*
X666289Y-99210D01*
X665872Y-97970D01*
X664831Y-97040D01*
X663581Y-96420D01*
X661914Y-95955D01*
X660039Y-95800D01*
X658164Y-95955D01*
X656497Y-96420D01*
X655247Y-97040D01*
X654206Y-97970D01*
X653789Y-99210D01*
G01Y-86810D02*
X654206Y-88050D01*
X655247Y-88980D01*
X656497Y-89600D01*
X658164Y-90065D01*
X660039Y-90220D01*
X661914Y-90065D01*
X663581Y-89600D01*
X664831Y-88980D01*
X665872Y-88050D01*
X666289Y-86810D01*
X665872Y-85570D01*
X664831Y-84640D01*
X663581Y-84020D01*
X661914Y-83555D01*
X660039Y-83400D01*
X658164Y-83555D01*
X656497Y-84020D01*
X655247Y-84640D01*
X654206Y-85570D01*
X653789Y-86810D01*
G01X666289Y-72550D02*
X653789D01*
X662747Y-78285D01*
Y-70535D01*
G01X656285Y476795D02*
X654826Y477880D01*
X653993Y478810D01*
X653576Y480050D01*
X653993Y481135D01*
X654826Y481910D01*
X656076Y482530D01*
X657535Y482685D01*
X658785Y482530D01*
X660035Y481910D01*
X661076Y480980D01*
X661493Y479895D01*
X661076Y478655D01*
X659827Y477570D01*
X657951Y476950D01*
X655868Y476795D01*
X653160Y477105D01*
X651701Y477570D01*
X650243Y478345D01*
X649201Y479430D01*
X648993Y480515D01*
X649410Y481600D01*
X650451Y482375D01*
G01X661910Y492140D02*
X661701Y491830D01*
X661285D01*
X661076Y492140D01*
X661285Y492450D01*
X661701D01*
X661910Y492140D01*
G01X659618Y501130D02*
X660660Y502060D01*
X661285Y503145D01*
X661493Y504540D01*
X661076Y505935D01*
X660243Y507020D01*
X658785Y507795D01*
X657118Y507950D01*
X655451Y507640D01*
X654410Y506865D01*
X653576Y505780D01*
X653368Y504695D01*
X653576Y503610D01*
X654410Y502215D01*
X648993Y502680D01*
Y506865D01*
G01X659618Y513530D02*
X660660Y514460D01*
X661285Y515545D01*
X661493Y516940D01*
X661076Y518335D01*
X660243Y519420D01*
X658785Y520195D01*
X657118Y520350D01*
X655451Y520040D01*
X654410Y519265D01*
X653576Y518180D01*
X653368Y517095D01*
X653576Y516010D01*
X654410Y514615D01*
X648993Y515080D01*
Y519265D01*
G01X651076Y526395D02*
X649827Y527325D01*
X649201Y528410D01*
X648993Y529650D01*
X649410Y531200D01*
X650451Y532285D01*
X651701Y532595D01*
X652952Y532440D01*
X653993Y531820D01*
X656076Y528720D01*
X657535Y527325D01*
X659618Y526395D01*
X661493Y526085D01*
Y532595D01*
G01Y543600D02*
X648993D01*
X657951Y537865D01*
Y545615D01*
G01X660039Y44134D02*
Y-60385D01*
G01X657291Y191024D02*
Y230573D01*
G01X667211Y239469D02*
X679695D01*
G01X655243Y251437D02*
Y465715D01*
G01X668071Y284646D02*
X681365D01*
G01X671232Y445390D02*
X659190Y436103D01*
X673593Y440983D01*
X671232Y445390D01*
G01X659190Y436103D02*
X755260Y487570D01*
X779636Y487489D01*
G01X690775Y243636D02*
X691705Y244885D01*
X692790Y245511D01*
X694030Y245719D01*
X695580Y245302D01*
X696665Y244261D01*
X696975Y243011D01*
X696820Y241760D01*
X696200Y240719D01*
X693100Y238636D01*
X691705Y237177D01*
X690775Y235094D01*
X690465Y233219D01*
X696975D01*
G01X706120Y232802D02*
X705810Y233011D01*
Y233427D01*
X706120Y233636D01*
X706430Y233427D01*
Y233011D01*
X706120Y232802D01*
G01X715110Y235719D02*
X716040Y234260D01*
X717280Y233427D01*
X718675Y233219D01*
X719915Y233427D01*
X721155Y234469D01*
X721930Y235719D01*
X722085Y236969D01*
X721775Y238427D01*
X720690Y239469D01*
X719605Y239886D01*
X718210D01*
G01X719605D02*
X720535Y240511D01*
X721310Y241552D01*
X721620Y242802D01*
X721310Y244052D01*
X720535Y245094D01*
X719140Y245719D01*
X717745Y245511D01*
X716350Y244677D01*
G01X728285Y234677D02*
X729370Y233636D01*
X730610Y233219D01*
X731850Y233636D01*
X732935Y234885D01*
X733710Y236761D01*
X734020Y238636D01*
Y240927D01*
X733710Y242802D01*
X732935Y244469D01*
X732005Y245302D01*
X730920Y245719D01*
X729680Y245302D01*
X728750Y244469D01*
X728130Y243219D01*
X727820Y241552D01*
X728130Y240094D01*
X728905Y238636D01*
X729835Y237802D01*
X730920Y237594D01*
X732160Y238010D01*
X733090Y239052D01*
X734020Y240927D01*
G01X745180Y233219D02*
Y245719D01*
X739445Y236761D01*
X747195D01*
G01X755410Y233219D02*
X755720Y235927D01*
X756185Y238219D01*
X756805Y240302D01*
X757580Y242594D01*
X758820Y245719D01*
X752620D01*
G01X692445Y288813D02*
X693375Y290062D01*
X694460Y290688D01*
X695700Y290896D01*
X697250Y290479D01*
X698335Y289438D01*
X698645Y288188D01*
X698490Y286937D01*
X697870Y285896D01*
X694770Y283813D01*
X693375Y282354D01*
X692445Y280271D01*
X692135Y278396D01*
X698645D01*
G01X707790Y277979D02*
X707480Y278188D01*
Y278604D01*
X707790Y278813D01*
X708100Y278604D01*
Y278188D01*
X707790Y277979D01*
G01X720190Y278396D02*
X721275Y278604D01*
X722515Y279229D01*
X723290Y280271D01*
X723600Y281729D01*
X723290Y283187D01*
X722360Y284438D01*
X720965Y285063D01*
X719415D01*
X718485Y285479D01*
X717710Y286521D01*
X717400Y287979D01*
X717865Y289438D01*
X718950Y290479D01*
X720190Y290896D01*
X721430Y290479D01*
X722515Y289438D01*
X722980Y287979D01*
X722670Y286521D01*
X721895Y285479D01*
X720965Y285063D01*
X719415D01*
X718020Y284438D01*
X717090Y283187D01*
X716780Y281729D01*
X717090Y280271D01*
X717865Y279229D01*
X719105Y278604D01*
X720190Y278396D01*
G01X734450D02*
Y290896D01*
X728715Y281938D01*
X736465D01*
G01X742045Y283604D02*
X743130Y285063D01*
X744060Y285896D01*
X745300Y286313D01*
X746385Y285896D01*
X747160Y285063D01*
X747780Y283813D01*
X747935Y282354D01*
X747780Y281104D01*
X747160Y279854D01*
X746230Y278813D01*
X745145Y278396D01*
X743905Y278813D01*
X742820Y280062D01*
X742200Y281938D01*
X742045Y284021D01*
X742355Y286729D01*
X742820Y288188D01*
X743595Y289646D01*
X744680Y290688D01*
X745765Y290896D01*
X746850Y290479D01*
X747625Y289438D01*
G01X753980Y280271D02*
X754910Y279229D01*
X755995Y278604D01*
X757390Y278396D01*
X758785Y278813D01*
X759870Y279646D01*
X760645Y281104D01*
X760800Y282771D01*
X760490Y284438D01*
X759715Y285479D01*
X758630Y286313D01*
X757545Y286521D01*
X756460Y286313D01*
X755065Y285479D01*
X755530Y290896D01*
X759715D01*
G01X758000Y-1608501D02*
X759500Y-1610167D01*
X761250Y-1611167D01*
X763500Y-1611500D01*
X765750Y-1610833D01*
X767500Y-1609500D01*
X768750Y-1607167D01*
X769000Y-1604500D01*
X768500Y-1601834D01*
X767250Y-1600167D01*
X765500Y-1598834D01*
X763750Y-1598500D01*
X762000Y-1598834D01*
X759750Y-1600167D01*
X760500Y-1591500D01*
X767250D01*
G01X798000Y-1611500D02*
Y-1591500D01*
X803000D01*
X805000Y-1592500D01*
X806500Y-1593833D01*
X807750Y-1595833D01*
X808750Y-1598167D01*
X809000Y-1601500D01*
X808750Y-1604834D01*
X807750Y-1607167D01*
X806500Y-1609167D01*
X805000Y-1610500D01*
X803000Y-1611500D01*
X798000D01*
G01X828500D02*
X818500D01*
Y-1591500D01*
X828500D01*
G01X824500Y-1601166D02*
X818500D01*
G01X845000Y-1601500D02*
X850000D01*
Y-1607500D01*
X848500Y-1609500D01*
X846750Y-1610833D01*
X844250Y-1611500D01*
X841750Y-1610833D01*
X840000Y-1609500D01*
X838500Y-1607500D01*
X837500Y-1605167D01*
X837000Y-1602500D01*
Y-1600167D01*
X837500Y-1598167D01*
X838500Y-1595833D01*
X840000Y-1593833D01*
X841500Y-1592500D01*
X843500Y-1591500D01*
X845250D01*
X847250Y-1592167D01*
X848750Y-1593500D01*
G01X858500Y-1611500D02*
Y-1591500D01*
X864750D01*
X866750Y-1592500D01*
X868000Y-1593833D01*
X868500Y-1596500D01*
X868000Y-1599167D01*
X866500Y-1600833D01*
X864750Y-1601834D01*
X858500D01*
G01X864750D02*
X868500Y-1611500D01*
G01X888500D02*
X878500D01*
Y-1591500D01*
X888500D01*
G01X884500Y-1601166D02*
X878500D01*
G01X908500Y-1611500D02*
X898500D01*
Y-1591500D01*
X908500D01*
G01X904500Y-1601166D02*
X898500D01*
G01X775500Y-1546000D02*
X773500Y-1546667D01*
X772000Y-1548333D01*
X771000Y-1550333D01*
X770250Y-1553000D01*
X770000Y-1556000D01*
X770250Y-1559000D01*
X771000Y-1561667D01*
X772000Y-1563667D01*
X773500Y-1565333D01*
X775500Y-1566000D01*
X777500Y-1565333D01*
X779000Y-1563667D01*
X780000Y-1561667D01*
X780750Y-1559000D01*
X781000Y-1556000D01*
X780750Y-1553000D01*
X780000Y-1550333D01*
X779000Y-1548333D01*
X777500Y-1546667D01*
X775500Y-1546000D01*
G01X795500Y-1566667D02*
X795000Y-1566333D01*
Y-1565667D01*
X795500Y-1565333D01*
X796000Y-1565667D01*
Y-1566333D01*
X795500Y-1566667D01*
G01X815500Y-1546000D02*
X813500Y-1546667D01*
X812000Y-1548333D01*
X811000Y-1550333D01*
X810250Y-1553000D01*
X810000Y-1556000D01*
X810250Y-1559000D01*
X811000Y-1561667D01*
X812000Y-1563667D01*
X813500Y-1565333D01*
X815500Y-1566000D01*
X817500Y-1565333D01*
X819000Y-1563667D01*
X820000Y-1561667D01*
X820750Y-1559000D01*
X821000Y-1556000D01*
X820750Y-1553000D01*
X820000Y-1550333D01*
X819000Y-1548333D01*
X817500Y-1546667D01*
X815500Y-1546000D01*
G01X835500D02*
X833500Y-1546667D01*
X832000Y-1548333D01*
X831000Y-1550333D01*
X830250Y-1553000D01*
X830000Y-1556000D01*
X830250Y-1559000D01*
X831000Y-1561667D01*
X832000Y-1563667D01*
X833500Y-1565333D01*
X835500Y-1566000D01*
X837500Y-1565333D01*
X839000Y-1563667D01*
X840000Y-1561667D01*
X840750Y-1559000D01*
X841000Y-1556000D01*
X840750Y-1553000D01*
X840000Y-1550333D01*
X839000Y-1548333D01*
X837500Y-1546667D01*
X835500Y-1546000D01*
G01X850000Y-1563001D02*
X851500Y-1564667D01*
X853250Y-1565667D01*
X855500Y-1566000D01*
X857750Y-1565333D01*
X859500Y-1564000D01*
X860750Y-1561667D01*
X861000Y-1559000D01*
X860500Y-1556334D01*
X859250Y-1554667D01*
X857500Y-1553334D01*
X855750Y-1553000D01*
X854000Y-1553334D01*
X851750Y-1554667D01*
X852500Y-1546000D01*
X859250D01*
G01X873250Y-1550333D02*
X874500Y-1546000D01*
G01X877750D02*
X876500Y-1550333D01*
G01X790540Y481204D02*
X790581Y493704D01*
X794456Y493691D01*
X795694Y493062D01*
X796466Y492226D01*
X796771Y490558D01*
X796455Y488893D01*
X795522Y487854D01*
X794435Y487233D01*
X790560Y487245D01*
G01X794435Y487233D02*
X796740Y481184D01*
G01X806038Y480736D02*
X805729Y480945D01*
X805731Y481362D01*
X806041Y481569D01*
X806351Y481360D01*
X806349Y480943D01*
X806038Y480736D01*
G01X818481Y493612D02*
X817239Y493199D01*
X816306Y492160D01*
X815682Y490913D01*
X815212Y489247D01*
X815051Y487373D01*
X815199Y485497D01*
X815659Y483829D01*
X816275Y482577D01*
X817201Y481532D01*
X818440Y481112D01*
X819681Y481524D01*
X820615Y482563D01*
X821239Y483811D01*
X821709Y485476D01*
X821870Y487350D01*
X821722Y489226D01*
X821262Y490894D01*
X820646Y492146D01*
X819719Y493191D01*
X818481Y493612D01*
G01X827438Y483582D02*
X828363Y482120D01*
X829601Y481283D01*
X830995Y481070D01*
X832236Y481274D01*
X833479Y482312D01*
X834258Y483559D01*
X834417Y484809D01*
X834112Y486268D01*
X833030Y487313D01*
X831947Y487734D01*
X830552Y487738D01*
G01X831947Y487734D02*
X832879Y488356D01*
X833657Y489395D01*
X833971Y490644D01*
X833666Y491895D01*
X832894Y492939D01*
X831501Y493569D01*
X830105Y493365D01*
X828708Y492536D01*
G01X840610Y482496D02*
X841691Y481451D01*
X842930Y481031D01*
X844171Y481443D01*
X845260Y482689D01*
X846042Y484562D01*
X846358Y486436D01*
X846365Y488728D01*
X846062Y490604D01*
X845292Y492273D01*
X844365Y493110D01*
X843281Y493530D01*
X842039Y493117D01*
X841107Y492287D01*
X840483Y491039D01*
X840167Y489373D01*
X840472Y487914D01*
X841243Y486453D01*
X842170Y485616D01*
X843254Y485405D01*
X844496Y485817D01*
X845429Y486856D01*
X846365Y488728D01*
G01X857500Y480983D02*
X857541Y493483D01*
X851776Y484543D01*
X859527Y484518D01*
G01X889585Y480876D02*
X896136Y493355D01*
G01X889626Y493376D02*
X896095Y480855D01*
G01X905240Y480825D02*
X905281Y493325D01*
X903413Y490831D01*
G01X903380Y480831D02*
X907100Y480819D01*
G01X917681Y493284D02*
X916439Y492871D01*
X915506Y491832D01*
X914882Y490585D01*
X914412Y488919D01*
X914251Y487045D01*
X914399Y485169D01*
X914859Y483501D01*
X915475Y482249D01*
X916401Y481204D01*
X917640Y480784D01*
X918881Y481196D01*
X919815Y482235D01*
X920439Y483483D01*
X920909Y485148D01*
X921070Y487022D01*
X920922Y488898D01*
X920462Y490566D01*
X919846Y491818D01*
X918919Y492863D01*
X917681Y493284D01*
G01X829000Y11000D02*
Y461000D01*
X1526500D01*
Y11000D01*
X829000D01*
G01Y36000D02*
X1526500D01*
G01X829000Y61000D02*
X1526500D01*
G01X829000Y86000D02*
X1526500D01*
G01X829000Y111000D02*
X1526500D01*
G01X829000Y136000D02*
X1526500D01*
G01X829000Y161000D02*
X1526500D01*
G01X829000Y186000D02*
X1526500D01*
G01X829000Y211000D02*
X1526500D01*
G01X829000Y236000D02*
X1526500D01*
G01X829000Y261000D02*
X1526500D01*
G01X829000Y286000D02*
X1526500D01*
G01X829000Y311000D02*
X1526500D01*
G01X829000Y336000D02*
X1526500D01*
G01X829000Y361000D02*
X1526500D01*
G01X829000Y386000D02*
X1526500D01*
G01X829000Y411000D02*
X1526500D01*
G01X829000Y436000D02*
X1526500D01*
G01X840005Y392250D02*
Y404750D01*
X845895D01*
G01X843725Y398708D02*
X840005D01*
G01X853490Y404750D02*
X857210D01*
G01X855350D02*
Y392250D01*
G01X853490D02*
X857210D01*
G01X868680Y398500D02*
X871780D01*
Y394750D01*
X870850Y393500D01*
X869765Y392667D01*
X868215Y392250D01*
X866665Y392667D01*
X865580Y393500D01*
X864650Y394750D01*
X864030Y396208D01*
X863720Y397875D01*
Y399333D01*
X864030Y400583D01*
X864650Y402042D01*
X865580Y403292D01*
X866510Y404125D01*
X867750Y404750D01*
X868835D01*
X870075Y404333D01*
X871005Y403500D01*
G01X876740Y404750D02*
Y395792D01*
X877360Y393916D01*
X878600Y392667D01*
X880150Y392250D01*
X881700Y392667D01*
X882940Y393916D01*
X883560Y395792D01*
Y404750D01*
G01X889450Y392250D02*
Y404750D01*
X893325D01*
X894565Y404125D01*
X895340Y403292D01*
X895650Y401625D01*
X895340Y399958D01*
X894410Y398917D01*
X893325Y398292D01*
X889450D01*
G01X893325D02*
X895650Y392250D01*
G01X908050D02*
X901850D01*
Y404750D01*
X908050D01*
G01X905570Y398708D02*
X901850D01*
G01X918900Y411000D02*
Y11000D01*
G01X942305Y392250D02*
Y404750D01*
X948195D01*
G01X946025Y398708D02*
X942305D01*
G01X955790Y404750D02*
X959510D01*
G01X957650D02*
Y392250D01*
G01X955790D02*
X959510D01*
G01X966485D02*
Y404750D01*
X973615Y392250D01*
Y404750D01*
G01X980590D02*
X984310D01*
G01X982450D02*
Y392250D01*
G01X980590D02*
X984310D01*
G01X991595Y393916D02*
X992835Y392875D01*
X994230Y392250D01*
X995470D01*
X996710Y392875D01*
X997640Y393916D01*
X998105Y395375D01*
X997795Y396833D01*
X997020Y398083D01*
X995625Y398917D01*
X993765Y399333D01*
X992680Y400167D01*
X992215Y401625D01*
X992525Y403083D01*
X993300Y404125D01*
X994385Y404750D01*
X995470D01*
X996555Y404333D01*
X997485Y403292D01*
G01X1003995Y392250D02*
Y404750D01*
G01X1010505D02*
Y392250D01*
G01Y398500D02*
X1003995D01*
G01X1022750Y392250D02*
X1016550D01*
Y404750D01*
X1022750D01*
G01X1020270Y398708D02*
X1016550D01*
G01X1028640Y392250D02*
Y404750D01*
X1031740D01*
X1032980Y404125D01*
X1033910Y403292D01*
X1034685Y402042D01*
X1035305Y400583D01*
X1035460Y398500D01*
X1035305Y396417D01*
X1034685Y394958D01*
X1033910Y393708D01*
X1032980Y392875D01*
X1031740Y392250D01*
X1028640D01*
G01X1039800Y388083D02*
X1049100D01*
G01X1053595Y393916D02*
X1054835Y392875D01*
X1056230Y392250D01*
X1057470D01*
X1058710Y392875D01*
X1059640Y393916D01*
X1060105Y395375D01*
X1059795Y396833D01*
X1059020Y398083D01*
X1057625Y398917D01*
X1055765Y399333D01*
X1054680Y400167D01*
X1054215Y401625D01*
X1054525Y403083D01*
X1055300Y404125D01*
X1056385Y404750D01*
X1057470D01*
X1058555Y404333D01*
X1059485Y403292D01*
G01X1067390Y404750D02*
X1071110D01*
G01X1069250D02*
Y392250D01*
G01X1067390D02*
X1071110D01*
G01X1078705Y404750D02*
X1084595D01*
X1078705Y392250D01*
X1084595D01*
G01X1097150D02*
X1090950D01*
Y404750D01*
X1097150D01*
G01X1094670Y398708D02*
X1090950D01*
G01X967105Y22458D02*
X968190Y23917D01*
X969120Y24750D01*
X970360Y25167D01*
X971445Y24750D01*
X972220Y23917D01*
X972840Y22667D01*
X972995Y21208D01*
X972840Y19958D01*
X972220Y18708D01*
X971290Y17667D01*
X970205Y17250D01*
X968965Y17667D01*
X967880Y18916D01*
X967260Y20792D01*
X967105Y22875D01*
X967415Y25583D01*
X967880Y27042D01*
X968655Y28500D01*
X969740Y29542D01*
X970825Y29750D01*
X971910Y29333D01*
X972685Y28292D01*
G01X979040Y19750D02*
X979970Y18291D01*
X981210Y17458D01*
X982605Y17250D01*
X983845Y17458D01*
X985085Y18500D01*
X985860Y19750D01*
X986015Y21000D01*
X985705Y22458D01*
X984620Y23500D01*
X983535Y23917D01*
X982140D01*
G01X983535D02*
X984465Y24542D01*
X985240Y25583D01*
X985550Y26833D01*
X985240Y28083D01*
X984465Y29125D01*
X983070Y29750D01*
X981675Y29542D01*
X980280Y28708D01*
G01X994850Y16833D02*
X994540Y17042D01*
Y17458D01*
X994850Y17667D01*
X995160Y17458D01*
Y17042D01*
X994850Y16833D01*
G01X1007250Y29750D02*
X1006010Y29333D01*
X1005080Y28292D01*
X1004460Y27042D01*
X1003995Y25375D01*
X1003840Y23500D01*
X1003995Y21625D01*
X1004460Y19958D01*
X1005080Y18708D01*
X1006010Y17667D01*
X1007250Y17250D01*
X1008490Y17667D01*
X1009420Y18708D01*
X1010040Y19958D01*
X1010505Y21625D01*
X1010660Y23500D01*
X1010505Y25375D01*
X1010040Y27042D01*
X1009420Y28292D01*
X1008490Y29333D01*
X1007250Y29750D01*
G01X1017325Y25583D02*
X1021975Y17250D01*
G01Y25583D02*
X1017325Y17250D01*
G01X1029105Y27667D02*
X1030035Y28916D01*
X1031120Y29542D01*
X1032360Y29750D01*
X1033910Y29333D01*
X1034995Y28292D01*
X1035305Y27042D01*
X1035150Y25791D01*
X1034530Y24750D01*
X1031430Y22667D01*
X1030035Y21208D01*
X1029105Y19125D01*
X1028795Y17250D01*
X1035305D01*
G01X1046310D02*
Y29750D01*
X1040575Y20792D01*
X1048325D01*
G01X1056850Y16833D02*
X1056540Y17042D01*
Y17458D01*
X1056850Y17667D01*
X1057160Y17458D01*
Y17042D01*
X1056850Y16833D01*
G01X1069250Y29750D02*
X1068010Y29333D01*
X1067080Y28292D01*
X1066460Y27042D01*
X1065995Y25375D01*
X1065840Y23500D01*
X1065995Y21625D01*
X1066460Y19958D01*
X1067080Y18708D01*
X1068010Y17667D01*
X1069250Y17250D01*
X1070490Y17667D01*
X1071420Y18708D01*
X1072040Y19958D01*
X1072505Y21625D01*
X1072660Y23500D01*
X1072505Y25375D01*
X1072040Y27042D01*
X1071420Y28292D01*
X1070490Y29333D01*
X1069250Y29750D01*
G01X966640Y44125D02*
X967570Y43083D01*
X968655Y42458D01*
X970050Y42250D01*
X971445Y42667D01*
X972530Y43500D01*
X973305Y44958D01*
X973460Y46625D01*
X973150Y48292D01*
X972375Y49333D01*
X971290Y50167D01*
X970205Y50375D01*
X969120Y50167D01*
X967725Y49333D01*
X968190Y54750D01*
X972375D01*
G01X982450Y42250D02*
Y54750D01*
X980590Y52250D01*
G01Y42250D02*
X984310D01*
G01X994850Y41833D02*
X994540Y42042D01*
Y42458D01*
X994850Y42667D01*
X995160Y42458D01*
Y42042D01*
X994850Y41833D01*
G01X1007250Y54750D02*
X1006010Y54333D01*
X1005080Y53292D01*
X1004460Y52042D01*
X1003995Y50375D01*
X1003840Y48500D01*
X1003995Y46625D01*
X1004460Y44958D01*
X1005080Y43708D01*
X1006010Y42667D01*
X1007250Y42250D01*
X1008490Y42667D01*
X1009420Y43708D01*
X1010040Y44958D01*
X1010505Y46625D01*
X1010660Y48500D01*
X1010505Y50375D01*
X1010040Y52042D01*
X1009420Y53292D01*
X1008490Y54333D01*
X1007250Y54750D01*
G01X1017325Y50583D02*
X1021975Y42250D01*
G01Y50583D02*
X1017325Y42250D01*
G01X1029105Y52667D02*
X1030035Y53916D01*
X1031120Y54542D01*
X1032360Y54750D01*
X1033910Y54333D01*
X1034995Y53292D01*
X1035305Y52042D01*
X1035150Y50791D01*
X1034530Y49750D01*
X1031430Y47667D01*
X1030035Y46208D01*
X1029105Y44125D01*
X1028795Y42250D01*
X1035305D01*
G01X1046310D02*
Y54750D01*
X1040575Y45792D01*
X1048325D01*
G01X1056850Y41833D02*
X1056540Y42042D01*
Y42458D01*
X1056850Y42667D01*
X1057160Y42458D01*
Y42042D01*
X1056850Y41833D01*
G01X1069250Y54750D02*
X1068010Y54333D01*
X1067080Y53292D01*
X1066460Y52042D01*
X1065995Y50375D01*
X1065840Y48500D01*
X1065995Y46625D01*
X1066460Y44958D01*
X1067080Y43708D01*
X1068010Y42667D01*
X1069250Y42250D01*
X1070490Y42667D01*
X1071420Y43708D01*
X1072040Y44958D01*
X1072505Y46625D01*
X1072660Y48500D01*
X1072505Y50375D01*
X1072040Y52042D01*
X1071420Y53292D01*
X1070490Y54333D01*
X1069250Y54750D01*
G01X994850Y67250D02*
Y79750D01*
X992990Y77250D01*
G01Y67250D02*
X996710D01*
G01X1004305Y77667D02*
X1005235Y78916D01*
X1006320Y79542D01*
X1007560Y79750D01*
X1009110Y79333D01*
X1010195Y78292D01*
X1010505Y77042D01*
X1010350Y75791D01*
X1009730Y74750D01*
X1006630Y72667D01*
X1005235Y71208D01*
X1004305Y69125D01*
X1003995Y67250D01*
X1010505D01*
G01X1016240Y69125D02*
X1017170Y68083D01*
X1018255Y67458D01*
X1019650Y67250D01*
X1021045Y67667D01*
X1022130Y68500D01*
X1022905Y69958D01*
X1023060Y71625D01*
X1022750Y73292D01*
X1021975Y74333D01*
X1020890Y75167D01*
X1019805Y75375D01*
X1018720Y75167D01*
X1017325Y74333D01*
X1017790Y79750D01*
X1021975D01*
G01X1032050Y66833D02*
X1031740Y67042D01*
Y67458D01*
X1032050Y67667D01*
X1032360Y67458D01*
Y67042D01*
X1032050Y66833D01*
G01X1044450Y79750D02*
X1043210Y79333D01*
X1042280Y78292D01*
X1041660Y77042D01*
X1041195Y75375D01*
X1041040Y73500D01*
X1041195Y71625D01*
X1041660Y69958D01*
X1042280Y68708D01*
X1043210Y67667D01*
X1044450Y67250D01*
X1045690Y67667D01*
X1046620Y68708D01*
X1047240Y69958D01*
X1047705Y71625D01*
X1047860Y73500D01*
X1047705Y75375D01*
X1047240Y77042D01*
X1046620Y78292D01*
X1045690Y79333D01*
X1044450Y79750D01*
G01X994850Y92250D02*
Y104750D01*
X992990Y102250D01*
G01Y92250D02*
X996710D01*
G01X1007250D02*
Y104750D01*
X1005390Y102250D01*
G01Y92250D02*
X1009110D01*
G01X1019650D02*
X1020735Y92458D01*
X1021975Y93083D01*
X1022750Y94125D01*
X1023060Y95583D01*
X1022750Y97041D01*
X1021820Y98292D01*
X1020425Y98917D01*
X1018875D01*
X1017945Y99333D01*
X1017170Y100375D01*
X1016860Y101833D01*
X1017325Y103292D01*
X1018410Y104333D01*
X1019650Y104750D01*
X1020890Y104333D01*
X1021975Y103292D01*
X1022440Y101833D01*
X1022130Y100375D01*
X1021355Y99333D01*
X1020425Y98917D01*
X1018875D01*
X1017480Y98292D01*
X1016550Y97041D01*
X1016240Y95583D01*
X1016550Y94125D01*
X1017325Y93083D01*
X1018565Y92458D01*
X1019650Y92250D01*
G01X1032050Y91833D02*
X1031740Y92042D01*
Y92458D01*
X1032050Y92667D01*
X1032360Y92458D01*
Y92042D01*
X1032050Y91833D01*
G01X1044450Y104750D02*
X1043210Y104333D01*
X1042280Y103292D01*
X1041660Y102042D01*
X1041195Y100375D01*
X1041040Y98500D01*
X1041195Y96625D01*
X1041660Y94958D01*
X1042280Y93708D01*
X1043210Y92667D01*
X1044450Y92250D01*
X1045690Y92667D01*
X1046620Y93708D01*
X1047240Y94958D01*
X1047705Y96625D01*
X1047860Y98500D01*
X1047705Y100375D01*
X1047240Y102042D01*
X1046620Y103292D01*
X1045690Y104333D01*
X1044450Y104750D01*
G01X994850Y117250D02*
Y129750D01*
X992990Y127250D01*
G01Y117250D02*
X996710D01*
G01X1007250Y129750D02*
X1006010Y129333D01*
X1005080Y128292D01*
X1004460Y127042D01*
X1003995Y125375D01*
X1003840Y123500D01*
X1003995Y121625D01*
X1004460Y119958D01*
X1005080Y118708D01*
X1006010Y117667D01*
X1007250Y117250D01*
X1008490Y117667D01*
X1009420Y118708D01*
X1010040Y119958D01*
X1010505Y121625D01*
X1010660Y123500D01*
X1010505Y125375D01*
X1010040Y127042D01*
X1009420Y128292D01*
X1008490Y129333D01*
X1007250Y129750D01*
G01X1019650D02*
X1018410Y129333D01*
X1017480Y128292D01*
X1016860Y127042D01*
X1016395Y125375D01*
X1016240Y123500D01*
X1016395Y121625D01*
X1016860Y119958D01*
X1017480Y118708D01*
X1018410Y117667D01*
X1019650Y117250D01*
X1020890Y117667D01*
X1021820Y118708D01*
X1022440Y119958D01*
X1022905Y121625D01*
X1023060Y123500D01*
X1022905Y125375D01*
X1022440Y127042D01*
X1021820Y128292D01*
X1020890Y129333D01*
X1019650Y129750D01*
G01X1032050Y116833D02*
X1031740Y117042D01*
Y117458D01*
X1032050Y117667D01*
X1032360Y117458D01*
Y117042D01*
X1032050Y116833D01*
G01X1044450Y129750D02*
X1043210Y129333D01*
X1042280Y128292D01*
X1041660Y127042D01*
X1041195Y125375D01*
X1041040Y123500D01*
X1041195Y121625D01*
X1041660Y119958D01*
X1042280Y118708D01*
X1043210Y117667D01*
X1044450Y117250D01*
X1045690Y117667D01*
X1046620Y118708D01*
X1047240Y119958D01*
X1047705Y121625D01*
X1047860Y123500D01*
X1047705Y125375D01*
X1047240Y127042D01*
X1046620Y128292D01*
X1045690Y129333D01*
X1044450Y129750D01*
G01X994850Y142250D02*
Y154750D01*
X992990Y152250D01*
G01Y142250D02*
X996710D01*
G01X1004305Y147458D02*
X1005390Y148917D01*
X1006320Y149750D01*
X1007560Y150167D01*
X1008645Y149750D01*
X1009420Y148917D01*
X1010040Y147667D01*
X1010195Y146208D01*
X1010040Y144958D01*
X1009420Y143708D01*
X1008490Y142667D01*
X1007405Y142250D01*
X1006165Y142667D01*
X1005080Y143916D01*
X1004460Y145792D01*
X1004305Y147875D01*
X1004615Y150583D01*
X1005080Y152042D01*
X1005855Y153500D01*
X1006940Y154542D01*
X1008025Y154750D01*
X1009110Y154333D01*
X1009885Y153292D01*
G01X1016705Y147458D02*
X1017790Y148917D01*
X1018720Y149750D01*
X1019960Y150167D01*
X1021045Y149750D01*
X1021820Y148917D01*
X1022440Y147667D01*
X1022595Y146208D01*
X1022440Y144958D01*
X1021820Y143708D01*
X1020890Y142667D01*
X1019805Y142250D01*
X1018565Y142667D01*
X1017480Y143916D01*
X1016860Y145792D01*
X1016705Y147875D01*
X1017015Y150583D01*
X1017480Y152042D01*
X1018255Y153500D01*
X1019340Y154542D01*
X1020425Y154750D01*
X1021510Y154333D01*
X1022285Y153292D01*
G01X1032050Y141833D02*
X1031740Y142042D01*
Y142458D01*
X1032050Y142667D01*
X1032360Y142458D01*
Y142042D01*
X1032050Y141833D01*
G01X1044450Y154750D02*
X1043210Y154333D01*
X1042280Y153292D01*
X1041660Y152042D01*
X1041195Y150375D01*
X1041040Y148500D01*
X1041195Y146625D01*
X1041660Y144958D01*
X1042280Y143708D01*
X1043210Y142667D01*
X1044450Y142250D01*
X1045690Y142667D01*
X1046620Y143708D01*
X1047240Y144958D01*
X1047705Y146625D01*
X1047860Y148500D01*
X1047705Y150375D01*
X1047240Y152042D01*
X1046620Y153292D01*
X1045690Y154333D01*
X1044450Y154750D01*
G01X1000740Y167250D02*
X1001050Y169958D01*
X1001515Y172250D01*
X1002135Y174333D01*
X1002910Y176625D01*
X1004150Y179750D01*
X997950D01*
G01X1010815Y168708D02*
X1011900Y167667D01*
X1013140Y167250D01*
X1014380Y167667D01*
X1015465Y168916D01*
X1016240Y170792D01*
X1016550Y172667D01*
Y174958D01*
X1016240Y176833D01*
X1015465Y178500D01*
X1014535Y179333D01*
X1013450Y179750D01*
X1012210Y179333D01*
X1011280Y178500D01*
X1010660Y177250D01*
X1010350Y175583D01*
X1010660Y174125D01*
X1011435Y172667D01*
X1012365Y171833D01*
X1013450Y171625D01*
X1014690Y172041D01*
X1015620Y173083D01*
X1016550Y174958D01*
G01X1025850Y166833D02*
X1025540Y167042D01*
Y167458D01*
X1025850Y167667D01*
X1026160Y167458D01*
Y167042D01*
X1025850Y166833D01*
G01X1038250Y179750D02*
X1037010Y179333D01*
X1036080Y178292D01*
X1035460Y177042D01*
X1034995Y175375D01*
X1034840Y173500D01*
X1034995Y171625D01*
X1035460Y169958D01*
X1036080Y168708D01*
X1037010Y167667D01*
X1038250Y167250D01*
X1039490Y167667D01*
X1040420Y168708D01*
X1041040Y169958D01*
X1041505Y171625D01*
X1041660Y173500D01*
X1041505Y175375D01*
X1041040Y177042D01*
X1040420Y178292D01*
X1039490Y179333D01*
X1038250Y179750D01*
G01X1000740Y192250D02*
X1001050Y194958D01*
X1001515Y197250D01*
X1002135Y199333D01*
X1002910Y201625D01*
X1004150Y204750D01*
X997950D01*
G01X1010505Y197458D02*
X1011590Y198917D01*
X1012520Y199750D01*
X1013760Y200167D01*
X1014845Y199750D01*
X1015620Y198917D01*
X1016240Y197667D01*
X1016395Y196208D01*
X1016240Y194958D01*
X1015620Y193708D01*
X1014690Y192667D01*
X1013605Y192250D01*
X1012365Y192667D01*
X1011280Y193916D01*
X1010660Y195792D01*
X1010505Y197875D01*
X1010815Y200583D01*
X1011280Y202042D01*
X1012055Y203500D01*
X1013140Y204542D01*
X1014225Y204750D01*
X1015310Y204333D01*
X1016085Y203292D01*
G01X1025850Y191833D02*
X1025540Y192042D01*
Y192458D01*
X1025850Y192667D01*
X1026160Y192458D01*
Y192042D01*
X1025850Y191833D01*
G01X1038250Y204750D02*
X1037010Y204333D01*
X1036080Y203292D01*
X1035460Y202042D01*
X1034995Y200375D01*
X1034840Y198500D01*
X1034995Y196625D01*
X1035460Y194958D01*
X1036080Y193708D01*
X1037010Y192667D01*
X1038250Y192250D01*
X1039490Y192667D01*
X1040420Y193708D01*
X1041040Y194958D01*
X1041505Y196625D01*
X1041660Y198500D01*
X1041505Y200375D01*
X1041040Y202042D01*
X1040420Y203292D01*
X1039490Y204333D01*
X1038250Y204750D01*
G01X998105Y222458D02*
X999190Y223917D01*
X1000120Y224750D01*
X1001360Y225167D01*
X1002445Y224750D01*
X1003220Y223917D01*
X1003840Y222667D01*
X1003995Y221208D01*
X1003840Y219958D01*
X1003220Y218708D01*
X1002290Y217667D01*
X1001205Y217250D01*
X999965Y217667D01*
X998880Y218916D01*
X998260Y220792D01*
X998105Y222875D01*
X998415Y225583D01*
X998880Y227042D01*
X999655Y228500D01*
X1000740Y229542D01*
X1001825Y229750D01*
X1002910Y229333D01*
X1003685Y228292D01*
G01X1010040Y219750D02*
X1010970Y218291D01*
X1012210Y217458D01*
X1013605Y217250D01*
X1014845Y217458D01*
X1016085Y218500D01*
X1016860Y219750D01*
X1017015Y221000D01*
X1016705Y222458D01*
X1015620Y223500D01*
X1014535Y223917D01*
X1013140D01*
G01X1014535D02*
X1015465Y224542D01*
X1016240Y225583D01*
X1016550Y226833D01*
X1016240Y228083D01*
X1015465Y229125D01*
X1014070Y229750D01*
X1012675Y229542D01*
X1011280Y228708D01*
G01X1025850Y216833D02*
X1025540Y217042D01*
Y217458D01*
X1025850Y217667D01*
X1026160Y217458D01*
Y217042D01*
X1025850Y216833D01*
G01X1038250Y229750D02*
X1037010Y229333D01*
X1036080Y228292D01*
X1035460Y227042D01*
X1034995Y225375D01*
X1034840Y223500D01*
X1034995Y221625D01*
X1035460Y219958D01*
X1036080Y218708D01*
X1037010Y217667D01*
X1038250Y217250D01*
X1039490Y217667D01*
X1040420Y218708D01*
X1041040Y219958D01*
X1041505Y221625D01*
X1041660Y223500D01*
X1041505Y225375D01*
X1041040Y227042D01*
X1040420Y228292D01*
X1039490Y229333D01*
X1038250Y229750D01*
G01X997640Y244125D02*
X998570Y243083D01*
X999655Y242458D01*
X1001050Y242250D01*
X1002445Y242667D01*
X1003530Y243500D01*
X1004305Y244958D01*
X1004460Y246625D01*
X1004150Y248292D01*
X1003375Y249333D01*
X1002290Y250167D01*
X1001205Y250375D01*
X1000120Y250167D01*
X998725Y249333D01*
X999190Y254750D01*
X1003375D01*
G01X1010815Y243708D02*
X1011900Y242667D01*
X1013140Y242250D01*
X1014380Y242667D01*
X1015465Y243916D01*
X1016240Y245792D01*
X1016550Y247667D01*
Y249958D01*
X1016240Y251833D01*
X1015465Y253500D01*
X1014535Y254333D01*
X1013450Y254750D01*
X1012210Y254333D01*
X1011280Y253500D01*
X1010660Y252250D01*
X1010350Y250583D01*
X1010660Y249125D01*
X1011435Y247667D01*
X1012365Y246833D01*
X1013450Y246625D01*
X1014690Y247041D01*
X1015620Y248083D01*
X1016550Y249958D01*
G01X1025850Y241833D02*
X1025540Y242042D01*
Y242458D01*
X1025850Y242667D01*
X1026160Y242458D01*
Y242042D01*
X1025850Y241833D01*
G01X1038250Y254750D02*
X1037010Y254333D01*
X1036080Y253292D01*
X1035460Y252042D01*
X1034995Y250375D01*
X1034840Y248500D01*
X1034995Y246625D01*
X1035460Y244958D01*
X1036080Y243708D01*
X1037010Y242667D01*
X1038250Y242250D01*
X1039490Y242667D01*
X1040420Y243708D01*
X1041040Y244958D01*
X1041505Y246625D01*
X1041660Y248500D01*
X1041505Y250375D01*
X1041040Y252042D01*
X1040420Y253292D01*
X1039490Y254333D01*
X1038250Y254750D01*
G01X997640Y269750D02*
X998570Y268291D01*
X999810Y267458D01*
X1001205Y267250D01*
X1002445Y267458D01*
X1003685Y268500D01*
X1004460Y269750D01*
X1004615Y271000D01*
X1004305Y272458D01*
X1003220Y273500D01*
X1002135Y273917D01*
X1000740D01*
G01X1002135D02*
X1003065Y274542D01*
X1003840Y275583D01*
X1004150Y276833D01*
X1003840Y278083D01*
X1003065Y279125D01*
X1001670Y279750D01*
X1000275Y279542D01*
X998880Y278708D01*
G01X1010040Y269750D02*
X1010970Y268291D01*
X1012210Y267458D01*
X1013605Y267250D01*
X1014845Y267458D01*
X1016085Y268500D01*
X1016860Y269750D01*
X1017015Y271000D01*
X1016705Y272458D01*
X1015620Y273500D01*
X1014535Y273917D01*
X1013140D01*
G01X1014535D02*
X1015465Y274542D01*
X1016240Y275583D01*
X1016550Y276833D01*
X1016240Y278083D01*
X1015465Y279125D01*
X1014070Y279750D01*
X1012675Y279542D01*
X1011280Y278708D01*
G01X1025850Y266833D02*
X1025540Y267042D01*
Y267458D01*
X1025850Y267667D01*
X1026160Y267458D01*
Y267042D01*
X1025850Y266833D01*
G01X1038250Y279750D02*
X1037010Y279333D01*
X1036080Y278292D01*
X1035460Y277042D01*
X1034995Y275375D01*
X1034840Y273500D01*
X1034995Y271625D01*
X1035460Y269958D01*
X1036080Y268708D01*
X1037010Y267667D01*
X1038250Y267250D01*
X1039490Y267667D01*
X1040420Y268708D01*
X1041040Y269958D01*
X1041505Y271625D01*
X1041660Y273500D01*
X1041505Y275375D01*
X1041040Y277042D01*
X1040420Y278292D01*
X1039490Y279333D01*
X1038250Y279750D01*
G01X1001050Y292250D02*
Y304750D01*
X999190Y302250D01*
G01Y292250D02*
X1002910D01*
G01X1010505Y297458D02*
X1011590Y298917D01*
X1012520Y299750D01*
X1013760Y300167D01*
X1014845Y299750D01*
X1015620Y298917D01*
X1016240Y297667D01*
X1016395Y296208D01*
X1016240Y294958D01*
X1015620Y293708D01*
X1014690Y292667D01*
X1013605Y292250D01*
X1012365Y292667D01*
X1011280Y293916D01*
X1010660Y295792D01*
X1010505Y297875D01*
X1010815Y300583D01*
X1011280Y302042D01*
X1012055Y303500D01*
X1013140Y304542D01*
X1014225Y304750D01*
X1015310Y304333D01*
X1016085Y303292D01*
G01X1025850Y291833D02*
X1025540Y292042D01*
Y292458D01*
X1025850Y292667D01*
X1026160Y292458D01*
Y292042D01*
X1025850Y291833D01*
G01X1038250Y304750D02*
X1037010Y304333D01*
X1036080Y303292D01*
X1035460Y302042D01*
X1034995Y300375D01*
X1034840Y298500D01*
X1034995Y296625D01*
X1035460Y294958D01*
X1036080Y293708D01*
X1037010Y292667D01*
X1038250Y292250D01*
X1039490Y292667D01*
X1040420Y293708D01*
X1041040Y294958D01*
X1041505Y296625D01*
X1041660Y298500D01*
X1041505Y300375D01*
X1041040Y302042D01*
X1040420Y303292D01*
X1039490Y304333D01*
X1038250Y304750D01*
G01X1001050Y317250D02*
Y329750D01*
X999190Y327250D01*
G01Y317250D02*
X1002910D01*
G01X1010505Y327667D02*
X1011435Y328916D01*
X1012520Y329542D01*
X1013760Y329750D01*
X1015310Y329333D01*
X1016395Y328292D01*
X1016705Y327042D01*
X1016550Y325791D01*
X1015930Y324750D01*
X1012830Y322667D01*
X1011435Y321208D01*
X1010505Y319125D01*
X1010195Y317250D01*
X1016705D01*
G01X1025850Y316833D02*
X1025540Y317042D01*
Y317458D01*
X1025850Y317667D01*
X1026160Y317458D01*
Y317042D01*
X1025850Y316833D01*
G01X1038250Y329750D02*
X1037010Y329333D01*
X1036080Y328292D01*
X1035460Y327042D01*
X1034995Y325375D01*
X1034840Y323500D01*
X1034995Y321625D01*
X1035460Y319958D01*
X1036080Y318708D01*
X1037010Y317667D01*
X1038250Y317250D01*
X1039490Y317667D01*
X1040420Y318708D01*
X1041040Y319958D01*
X1041505Y321625D01*
X1041660Y323500D01*
X1041505Y325375D01*
X1041040Y327042D01*
X1040420Y328292D01*
X1039490Y329333D01*
X1038250Y329750D01*
G01X1001050Y342250D02*
Y354750D01*
X999190Y352250D01*
G01Y342250D02*
X1002910D01*
G01X1013450Y354750D02*
X1012210Y354333D01*
X1011280Y353292D01*
X1010660Y352042D01*
X1010195Y350375D01*
X1010040Y348500D01*
X1010195Y346625D01*
X1010660Y344958D01*
X1011280Y343708D01*
X1012210Y342667D01*
X1013450Y342250D01*
X1014690Y342667D01*
X1015620Y343708D01*
X1016240Y344958D01*
X1016705Y346625D01*
X1016860Y348500D01*
X1016705Y350375D01*
X1016240Y352042D01*
X1015620Y353292D01*
X1014690Y354333D01*
X1013450Y354750D01*
G01X1025850Y341833D02*
X1025540Y342042D01*
Y342458D01*
X1025850Y342667D01*
X1026160Y342458D01*
Y342042D01*
X1025850Y341833D01*
G01X1038250Y354750D02*
X1037010Y354333D01*
X1036080Y353292D01*
X1035460Y352042D01*
X1034995Y350375D01*
X1034840Y348500D01*
X1034995Y346625D01*
X1035460Y344958D01*
X1036080Y343708D01*
X1037010Y342667D01*
X1038250Y342250D01*
X1039490Y342667D01*
X1040420Y343708D01*
X1041040Y344958D01*
X1041505Y346625D01*
X1041660Y348500D01*
X1041505Y350375D01*
X1041040Y352042D01*
X1040420Y353292D01*
X1039490Y354333D01*
X1038250Y354750D01*
G01X1007250Y367250D02*
X1008335Y367458D01*
X1009575Y368083D01*
X1010350Y369125D01*
X1010660Y370583D01*
X1010350Y372041D01*
X1009420Y373292D01*
X1008025Y373917D01*
X1006475D01*
X1005545Y374333D01*
X1004770Y375375D01*
X1004460Y376833D01*
X1004925Y378292D01*
X1006010Y379333D01*
X1007250Y379750D01*
X1008490Y379333D01*
X1009575Y378292D01*
X1010040Y376833D01*
X1009730Y375375D01*
X1008955Y374333D01*
X1008025Y373917D01*
X1006475D01*
X1005080Y373292D01*
X1004150Y372041D01*
X1003840Y370583D01*
X1004150Y369125D01*
X1004925Y368083D01*
X1006165Y367458D01*
X1007250Y367250D01*
G01X1019650Y366833D02*
X1019340Y367042D01*
Y367458D01*
X1019650Y367667D01*
X1019960Y367458D01*
Y367042D01*
X1019650Y366833D01*
G01X1032050Y379750D02*
X1030810Y379333D01*
X1029880Y378292D01*
X1029260Y377042D01*
X1028795Y375375D01*
X1028640Y373500D01*
X1028795Y371625D01*
X1029260Y369958D01*
X1029880Y368708D01*
X1030810Y367667D01*
X1032050Y367250D01*
X1033290Y367667D01*
X1034220Y368708D01*
X1034840Y369958D01*
X1035305Y371625D01*
X1035460Y373500D01*
X1035305Y375375D01*
X1034840Y377042D01*
X1034220Y378292D01*
X1033290Y379333D01*
X1032050Y379750D01*
G01X1019340Y442250D02*
Y454750D01*
X1022440D01*
X1023680Y454125D01*
X1024610Y453292D01*
X1025385Y452042D01*
X1026005Y450583D01*
X1026160Y448500D01*
X1026005Y446417D01*
X1025385Y444958D01*
X1024610Y443708D01*
X1023680Y442875D01*
X1022440Y442250D01*
X1019340D01*
G01X1032050D02*
Y454750D01*
X1035925D01*
X1037165Y454125D01*
X1037940Y453292D01*
X1038250Y451625D01*
X1037940Y449958D01*
X1037010Y448917D01*
X1035925Y448292D01*
X1032050D01*
G01X1035925D02*
X1038250Y442250D01*
G01X1045690Y454750D02*
X1049410D01*
G01X1047550D02*
Y442250D01*
G01X1045690D02*
X1049410D01*
G01X1056850Y454750D02*
Y442250D01*
X1063050D01*
G01X1069250Y454750D02*
Y442250D01*
X1075450D01*
G01X1100560Y453708D02*
X1099630Y454333D01*
X1098545Y454750D01*
X1097305D01*
X1095910Y454125D01*
X1094825Y453083D01*
X1094050Y451833D01*
X1093430Y449750D01*
X1093275Y447875D01*
X1093585Y446000D01*
X1094050Y444750D01*
X1094980Y443500D01*
X1096065Y442667D01*
X1097150Y442250D01*
X1098235D01*
X1099320Y442667D01*
X1100250Y443291D01*
X1101025Y444125D01*
G01X1106295Y442250D02*
Y454750D01*
G01X1112805D02*
Y442250D01*
G01Y448500D02*
X1106295D01*
G01X1118075Y442250D02*
X1121950Y454750D01*
X1125825Y442250D01*
G01X1124430Y446625D02*
X1119470D01*
G01X1131250Y442250D02*
Y454750D01*
X1135125D01*
X1136365Y454125D01*
X1137140Y453292D01*
X1137450Y451625D01*
X1137140Y449958D01*
X1136210Y448917D01*
X1135125Y448292D01*
X1131250D01*
G01X1135125D02*
X1137450Y442250D01*
G01X1146750Y454750D02*
Y442250D01*
G01X1143185Y454750D02*
X1150315D01*
G01X1159150Y441833D02*
X1158840Y442042D01*
Y442458D01*
X1159150Y442667D01*
X1159460Y442458D01*
Y442042D01*
X1159150Y441833D01*
G01Y447458D02*
X1158840Y447667D01*
Y448083D01*
X1159150Y448292D01*
X1159460Y448083D01*
Y447667D01*
X1159150Y447458D01*
G01X1183950Y454750D02*
Y442250D01*
G01X1180385Y454750D02*
X1187515D01*
G01X1196350Y442250D02*
X1195110Y442458D01*
X1194025Y443291D01*
X1193095Y444542D01*
X1192475Y446000D01*
X1192165Y447667D01*
Y449333D01*
X1192475Y451000D01*
X1193095Y452458D01*
X1194025Y453708D01*
X1195110Y454542D01*
X1196350Y454750D01*
X1197590Y454542D01*
X1198675Y453708D01*
X1199605Y452458D01*
X1200225Y451000D01*
X1200535Y449333D01*
Y447667D01*
X1200225Y446000D01*
X1199605Y444542D01*
X1198675Y443291D01*
X1197590Y442458D01*
X1196350Y442250D01*
G01X1205650D02*
Y454750D01*
X1209370D01*
X1210610Y454125D01*
X1211540Y452667D01*
X1211850Y451000D01*
X1211540Y449333D01*
X1210765Y448083D01*
X1209370Y447458D01*
X1205650D01*
G01X1233550Y454750D02*
Y442250D01*
G01X1231380Y450583D02*
X1235720D01*
G01X1245950Y442250D02*
X1245020Y442458D01*
X1244090Y443291D01*
X1243470Y444750D01*
X1243160Y446417D01*
X1243470Y448083D01*
X1244090Y449542D01*
X1245020Y450375D01*
X1245950Y450583D01*
X1246880Y450375D01*
X1247810Y449542D01*
X1248430Y448083D01*
X1248585Y446417D01*
X1248430Y444750D01*
X1247810Y443291D01*
X1246880Y442458D01*
X1245950Y442250D01*
G01X1271990Y448917D02*
X1272610Y449542D01*
X1273075Y450583D01*
X1273385Y452042D01*
X1273075Y453292D01*
X1272455Y454125D01*
X1271370Y454750D01*
X1267185D01*
Y442250D01*
X1272300D01*
X1273385Y443083D01*
X1274005Y444333D01*
X1274315Y445792D01*
X1274005Y447250D01*
X1273075Y448500D01*
X1271990Y448917D01*
X1267185D01*
G01X1283150Y442250D02*
X1281910Y442458D01*
X1280825Y443291D01*
X1279895Y444542D01*
X1279275Y446000D01*
X1278965Y447667D01*
Y449333D01*
X1279275Y451000D01*
X1279895Y452458D01*
X1280825Y453708D01*
X1281910Y454542D01*
X1283150Y454750D01*
X1284390Y454542D01*
X1285475Y453708D01*
X1286405Y452458D01*
X1287025Y451000D01*
X1287335Y449333D01*
Y447667D01*
X1287025Y446000D01*
X1286405Y444542D01*
X1285475Y443291D01*
X1284390Y442458D01*
X1283150Y442250D01*
G01X1295550Y454750D02*
Y442250D01*
G01X1291985Y454750D02*
X1299115D01*
G01X1307950D02*
Y442250D01*
G01X1304385Y454750D02*
X1311515D01*
G01X1320350Y442250D02*
X1319110Y442458D01*
X1318025Y443291D01*
X1317095Y444542D01*
X1316475Y446000D01*
X1316165Y447667D01*
Y449333D01*
X1316475Y451000D01*
X1317095Y452458D01*
X1318025Y453708D01*
X1319110Y454542D01*
X1320350Y454750D01*
X1321590Y454542D01*
X1322675Y453708D01*
X1323605Y452458D01*
X1324225Y451000D01*
X1324535Y449333D01*
Y447667D01*
X1324225Y446000D01*
X1323605Y444542D01*
X1322675Y443291D01*
X1321590Y442458D01*
X1320350Y442250D01*
G01X1328720D02*
Y454750D01*
X1332750Y444333D01*
X1336780Y454750D01*
Y442250D01*
G01X1049875Y417250D02*
X1053750Y429750D01*
X1057625Y417250D01*
G01X1056230Y421625D02*
X1051270D01*
G01X1063050Y429750D02*
Y417250D01*
X1069250D01*
G01X1075450Y429750D02*
Y417250D01*
X1081650D01*
G01X1099940Y429750D02*
Y420792D01*
X1100560Y418916D01*
X1101800Y417667D01*
X1103350Y417250D01*
X1104900Y417667D01*
X1106140Y418916D01*
X1106760Y420792D01*
Y429750D01*
G01X1112185Y417250D02*
Y429750D01*
X1119315Y417250D01*
Y429750D01*
G01X1126290D02*
X1130010D01*
G01X1128150D02*
Y417250D01*
G01X1126290D02*
X1130010D01*
G01X1140550Y429750D02*
Y417250D01*
G01X1136985Y429750D02*
X1144115D01*
G01X1149695Y418916D02*
X1150935Y417875D01*
X1152330Y417250D01*
X1153570D01*
X1154810Y417875D01*
X1155740Y418916D01*
X1156205Y420375D01*
X1155895Y421833D01*
X1155120Y423083D01*
X1153725Y423917D01*
X1151865Y424333D01*
X1150780Y425167D01*
X1150315Y426625D01*
X1150625Y428083D01*
X1151400Y429125D01*
X1152485Y429750D01*
X1153570D01*
X1154655Y429333D01*
X1155585Y428292D01*
G01X1173875Y417250D02*
X1177750Y429750D01*
X1181625Y417250D01*
G01X1180230Y421625D02*
X1175270D01*
G01X1187050Y417250D02*
Y429750D01*
X1190925D01*
X1192165Y429125D01*
X1192940Y428292D01*
X1193250Y426625D01*
X1192940Y424958D01*
X1192010Y423917D01*
X1190925Y423292D01*
X1187050D01*
G01X1190925D02*
X1193250Y417250D01*
G01X1205650D02*
X1199450D01*
Y429750D01*
X1205650D01*
G01X1203170Y423708D02*
X1199450D01*
G01X1225490Y429750D02*
X1229210D01*
G01X1227350D02*
Y417250D01*
G01X1225490D02*
X1229210D01*
G01X1236185D02*
Y429750D01*
X1243315Y417250D01*
Y429750D01*
G01X1260520Y417250D02*
Y429750D01*
X1264550Y419333D01*
X1268580Y429750D01*
Y417250D01*
G01X1275090Y429750D02*
X1278810D01*
G01X1276950D02*
Y417250D01*
G01X1275090D02*
X1278810D01*
G01X1286250Y429750D02*
Y417250D01*
X1292450D01*
G01X1298495Y418916D02*
X1299735Y417875D01*
X1301130Y417250D01*
X1302370D01*
X1303610Y417875D01*
X1304540Y418916D01*
X1305005Y420375D01*
X1304695Y421833D01*
X1303920Y423083D01*
X1302525Y423917D01*
X1300665Y424333D01*
X1299580Y425167D01*
X1299115Y426625D01*
X1299425Y428083D01*
X1300200Y429125D01*
X1301285Y429750D01*
X1302370D01*
X1303455Y429333D01*
X1304385Y428292D01*
G01X1120400Y411000D02*
Y11000D01*
G01X1134350Y404750D02*
Y392250D01*
G01X1130785Y404750D02*
X1137915D01*
G01X1146750Y392250D02*
X1145510Y392458D01*
X1144425Y393291D01*
X1143495Y394542D01*
X1142875Y396000D01*
X1142565Y397667D01*
Y399333D01*
X1142875Y401000D01*
X1143495Y402458D01*
X1144425Y403708D01*
X1145510Y404542D01*
X1146750Y404750D01*
X1147990Y404542D01*
X1149075Y403708D01*
X1150005Y402458D01*
X1150625Y401000D01*
X1150935Y399333D01*
Y397667D01*
X1150625Y396000D01*
X1150005Y394542D01*
X1149075Y393291D01*
X1147990Y392458D01*
X1146750Y392250D01*
G01X1156050Y404750D02*
Y392250D01*
X1162250D01*
G01X1174650D02*
X1168450D01*
Y404750D01*
X1174650D01*
G01X1172170Y398708D02*
X1168450D01*
G01X1180850Y392250D02*
Y404750D01*
X1184725D01*
X1185965Y404125D01*
X1186740Y403292D01*
X1187050Y401625D01*
X1186740Y399958D01*
X1185810Y398917D01*
X1184725Y398292D01*
X1180850D01*
G01X1184725D02*
X1187050Y392250D01*
G01X1192475D02*
X1196350Y404750D01*
X1200225Y392250D01*
G01X1198830Y396625D02*
X1193870D01*
G01X1205185Y392250D02*
Y404750D01*
X1212315Y392250D01*
Y404750D01*
G01X1224560Y403708D02*
X1223630Y404333D01*
X1222545Y404750D01*
X1221305D01*
X1219910Y404125D01*
X1218825Y403083D01*
X1218050Y401833D01*
X1217430Y399750D01*
X1217275Y397875D01*
X1217585Y396000D01*
X1218050Y394750D01*
X1218980Y393500D01*
X1220065Y392667D01*
X1221150Y392250D01*
X1222235D01*
X1223320Y392667D01*
X1224250Y393291D01*
X1225025Y394125D01*
G01X1236650Y392250D02*
X1230450D01*
Y404750D01*
X1236650D01*
G01X1234170Y398708D02*
X1230450D01*
G01X1241300Y388083D02*
X1250600D01*
G01X1254940Y392250D02*
Y404750D01*
X1258040D01*
X1259280Y404125D01*
X1260210Y403292D01*
X1260985Y402042D01*
X1261605Y400583D01*
X1261760Y398500D01*
X1261605Y396417D01*
X1260985Y394958D01*
X1260210Y393708D01*
X1259280Y392875D01*
X1258040Y392250D01*
X1254940D01*
G01X1267650D02*
Y404750D01*
X1271525D01*
X1272765Y404125D01*
X1273540Y403292D01*
X1273850Y401625D01*
X1273540Y399958D01*
X1272610Y398917D01*
X1271525Y398292D01*
X1267650D01*
G01X1271525D02*
X1273850Y392250D01*
G01X1281290Y404750D02*
X1285010D01*
G01X1283150D02*
Y392250D01*
G01X1281290D02*
X1285010D01*
G01X1292450Y404750D02*
Y392250D01*
X1298650D01*
G01X1304850Y404750D02*
Y392250D01*
X1311050D01*
G01X1169585Y16417D02*
X1173615D01*
G01X1231895D02*
X1235615D01*
G01X1233600Y19125D02*
Y13708D01*
G01X1169845Y21417D02*
X1173565D01*
G01X1171550Y24125D02*
Y18708D01*
G01X1180540Y19750D02*
X1181470Y18291D01*
X1182710Y17458D01*
X1184105Y17250D01*
X1185345Y17458D01*
X1186585Y18500D01*
X1187360Y19750D01*
X1187515Y21000D01*
X1187205Y22458D01*
X1186120Y23500D01*
X1185035Y23917D01*
X1183640D01*
G01X1185035D02*
X1185965Y24542D01*
X1186740Y25583D01*
X1187050Y26833D01*
X1186740Y28083D01*
X1185965Y29125D01*
X1184570Y29750D01*
X1183175Y29542D01*
X1181780Y28708D01*
G01X1196350Y16833D02*
X1196040Y17042D01*
Y17458D01*
X1196350Y17667D01*
X1196660Y17458D01*
Y17042D01*
X1196350Y16833D01*
G01X1208750Y29750D02*
X1207510Y29333D01*
X1206580Y28292D01*
X1205960Y27042D01*
X1205495Y25375D01*
X1205340Y23500D01*
X1205495Y21625D01*
X1205960Y19958D01*
X1206580Y18708D01*
X1207510Y17667D01*
X1208750Y17250D01*
X1209990Y17667D01*
X1210920Y18708D01*
X1211540Y19958D01*
X1212005Y21625D01*
X1212160Y23500D01*
X1212005Y25375D01*
X1211540Y27042D01*
X1210920Y28292D01*
X1209990Y29333D01*
X1208750Y29750D01*
G01X1218360Y16833D02*
X1223940Y29750D01*
G01X1231535Y21417D02*
X1235565D01*
G01X1242540Y19750D02*
X1243470Y18291D01*
X1244710Y17458D01*
X1246105Y17250D01*
X1247345Y17458D01*
X1248585Y18500D01*
X1249360Y19750D01*
X1249515Y21000D01*
X1249205Y22458D01*
X1248120Y23500D01*
X1247035Y23917D01*
X1245640D01*
G01X1247035D02*
X1247965Y24542D01*
X1248740Y25583D01*
X1249050Y26833D01*
X1248740Y28083D01*
X1247965Y29125D01*
X1246570Y29750D01*
X1245175Y29542D01*
X1243780Y28708D01*
G01X1258350Y16833D02*
X1258040Y17042D01*
Y17458D01*
X1258350Y17667D01*
X1258660Y17458D01*
Y17042D01*
X1258350Y16833D01*
G01X1270750Y29750D02*
X1269510Y29333D01*
X1268580Y28292D01*
X1267960Y27042D01*
X1267495Y25375D01*
X1267340Y23500D01*
X1267495Y21625D01*
X1267960Y19958D01*
X1268580Y18708D01*
X1269510Y17667D01*
X1270750Y17250D01*
X1271990Y17667D01*
X1272920Y18708D01*
X1273540Y19958D01*
X1274005Y21625D01*
X1274160Y23500D01*
X1274005Y25375D01*
X1273540Y27042D01*
X1272920Y28292D01*
X1271990Y29333D01*
X1270750Y29750D01*
G01X1169415Y40587D02*
X1173445D01*
G01X1231725D02*
X1235445D01*
G01X1233430Y43295D02*
Y37878D01*
G01X1169845Y46417D02*
X1173565D01*
G01X1171550Y49125D02*
Y43708D01*
G01X1180540Y44750D02*
X1181470Y43291D01*
X1182710Y42458D01*
X1184105Y42250D01*
X1185345Y42458D01*
X1186585Y43500D01*
X1187360Y44750D01*
X1187515Y46000D01*
X1187205Y47458D01*
X1186120Y48500D01*
X1185035Y48917D01*
X1183640D01*
G01X1185035D02*
X1185965Y49542D01*
X1186740Y50583D01*
X1187050Y51833D01*
X1186740Y53083D01*
X1185965Y54125D01*
X1184570Y54750D01*
X1183175Y54542D01*
X1181780Y53708D01*
G01X1196350Y41833D02*
X1196040Y42042D01*
Y42458D01*
X1196350Y42667D01*
X1196660Y42458D01*
Y42042D01*
X1196350Y41833D01*
G01X1208750Y54750D02*
X1207510Y54333D01*
X1206580Y53292D01*
X1205960Y52042D01*
X1205495Y50375D01*
X1205340Y48500D01*
X1205495Y46625D01*
X1205960Y44958D01*
X1206580Y43708D01*
X1207510Y42667D01*
X1208750Y42250D01*
X1209990Y42667D01*
X1210920Y43708D01*
X1211540Y44958D01*
X1212005Y46625D01*
X1212160Y48500D01*
X1212005Y50375D01*
X1211540Y52042D01*
X1210920Y53292D01*
X1209990Y54333D01*
X1208750Y54750D01*
G01X1218360Y41833D02*
X1223940Y54750D01*
G01X1231535Y46417D02*
X1235565D01*
G01X1242540Y44750D02*
X1243470Y43291D01*
X1244710Y42458D01*
X1246105Y42250D01*
X1247345Y42458D01*
X1248585Y43500D01*
X1249360Y44750D01*
X1249515Y46000D01*
X1249205Y47458D01*
X1248120Y48500D01*
X1247035Y48917D01*
X1245640D01*
G01X1247035D02*
X1247965Y49542D01*
X1248740Y50583D01*
X1249050Y51833D01*
X1248740Y53083D01*
X1247965Y54125D01*
X1246570Y54750D01*
X1245175Y54542D01*
X1243780Y53708D01*
G01X1258350Y41833D02*
X1258040Y42042D01*
Y42458D01*
X1258350Y42667D01*
X1258660Y42458D01*
Y42042D01*
X1258350Y41833D01*
G01X1270750Y54750D02*
X1269510Y54333D01*
X1268580Y53292D01*
X1267960Y52042D01*
X1267495Y50375D01*
X1267340Y48500D01*
X1267495Y46625D01*
X1267960Y44958D01*
X1268580Y43708D01*
X1269510Y42667D01*
X1270750Y42250D01*
X1271990Y42667D01*
X1272920Y43708D01*
X1273540Y44958D01*
X1274005Y46625D01*
X1274160Y48500D01*
X1274005Y50375D01*
X1273540Y52042D01*
X1272920Y53292D01*
X1271990Y54333D01*
X1270750Y54750D01*
G01X1169845Y71417D02*
X1173565D01*
G01X1171550Y74125D02*
Y68708D01*
G01X1181005Y77667D02*
X1181935Y78916D01*
X1183020Y79542D01*
X1184260Y79750D01*
X1185810Y79333D01*
X1186895Y78292D01*
X1187205Y77042D01*
X1187050Y75791D01*
X1186430Y74750D01*
X1183330Y72667D01*
X1181935Y71208D01*
X1181005Y69125D01*
X1180695Y67250D01*
X1187205D01*
G01X1196350Y66833D02*
X1196040Y67042D01*
Y67458D01*
X1196350Y67667D01*
X1196660Y67458D01*
Y67042D01*
X1196350Y66833D01*
G01X1208750Y79750D02*
X1207510Y79333D01*
X1206580Y78292D01*
X1205960Y77042D01*
X1205495Y75375D01*
X1205340Y73500D01*
X1205495Y71625D01*
X1205960Y69958D01*
X1206580Y68708D01*
X1207510Y67667D01*
X1208750Y67250D01*
X1209990Y67667D01*
X1210920Y68708D01*
X1211540Y69958D01*
X1212005Y71625D01*
X1212160Y73500D01*
X1212005Y75375D01*
X1211540Y77042D01*
X1210920Y78292D01*
X1209990Y79333D01*
X1208750Y79750D01*
G01X1218360Y66833D02*
X1223940Y79750D01*
G01X1231535Y71417D02*
X1235565D01*
G01X1243005Y77667D02*
X1243935Y78916D01*
X1245020Y79542D01*
X1246260Y79750D01*
X1247810Y79333D01*
X1248895Y78292D01*
X1249205Y77042D01*
X1249050Y75791D01*
X1248430Y74750D01*
X1245330Y72667D01*
X1243935Y71208D01*
X1243005Y69125D01*
X1242695Y67250D01*
X1249205D01*
G01X1258350Y66833D02*
X1258040Y67042D01*
Y67458D01*
X1258350Y67667D01*
X1258660Y67458D01*
Y67042D01*
X1258350Y66833D01*
G01X1270750Y79750D02*
X1269510Y79333D01*
X1268580Y78292D01*
X1267960Y77042D01*
X1267495Y75375D01*
X1267340Y73500D01*
X1267495Y71625D01*
X1267960Y69958D01*
X1268580Y68708D01*
X1269510Y67667D01*
X1270750Y67250D01*
X1271990Y67667D01*
X1272920Y68708D01*
X1273540Y69958D01*
X1274005Y71625D01*
X1274160Y73500D01*
X1274005Y75375D01*
X1273540Y77042D01*
X1272920Y78292D01*
X1271990Y79333D01*
X1270750Y79750D01*
G01X1169845Y96417D02*
X1173565D01*
G01X1171550Y99125D02*
Y93708D01*
G01X1181005Y102667D02*
X1181935Y103916D01*
X1183020Y104542D01*
X1184260Y104750D01*
X1185810Y104333D01*
X1186895Y103292D01*
X1187205Y102042D01*
X1187050Y100791D01*
X1186430Y99750D01*
X1183330Y97667D01*
X1181935Y96208D01*
X1181005Y94125D01*
X1180695Y92250D01*
X1187205D01*
G01X1196350Y91833D02*
X1196040Y92042D01*
Y92458D01*
X1196350Y92667D01*
X1196660Y92458D01*
Y92042D01*
X1196350Y91833D01*
G01X1208750Y104750D02*
X1207510Y104333D01*
X1206580Y103292D01*
X1205960Y102042D01*
X1205495Y100375D01*
X1205340Y98500D01*
X1205495Y96625D01*
X1205960Y94958D01*
X1206580Y93708D01*
X1207510Y92667D01*
X1208750Y92250D01*
X1209990Y92667D01*
X1210920Y93708D01*
X1211540Y94958D01*
X1212005Y96625D01*
X1212160Y98500D01*
X1212005Y100375D01*
X1211540Y102042D01*
X1210920Y103292D01*
X1209990Y104333D01*
X1208750Y104750D01*
G01X1218360Y91833D02*
X1223940Y104750D01*
G01X1231535Y96417D02*
X1235565D01*
G01X1243005Y102667D02*
X1243935Y103916D01*
X1245020Y104542D01*
X1246260Y104750D01*
X1247810Y104333D01*
X1248895Y103292D01*
X1249205Y102042D01*
X1249050Y100791D01*
X1248430Y99750D01*
X1245330Y97667D01*
X1243935Y96208D01*
X1243005Y94125D01*
X1242695Y92250D01*
X1249205D01*
G01X1258350Y91833D02*
X1258040Y92042D01*
Y92458D01*
X1258350Y92667D01*
X1258660Y92458D01*
Y92042D01*
X1258350Y91833D01*
G01X1270750Y104750D02*
X1269510Y104333D01*
X1268580Y103292D01*
X1267960Y102042D01*
X1267495Y100375D01*
X1267340Y98500D01*
X1267495Y96625D01*
X1267960Y94958D01*
X1268580Y93708D01*
X1269510Y92667D01*
X1270750Y92250D01*
X1271990Y92667D01*
X1272920Y93708D01*
X1273540Y94958D01*
X1274005Y96625D01*
X1274160Y98500D01*
X1274005Y100375D01*
X1273540Y102042D01*
X1272920Y103292D01*
X1271990Y104333D01*
X1270750Y104750D01*
G01X1169845Y121417D02*
X1173565D01*
G01X1171550Y124125D02*
Y118708D01*
G01X1181005Y127667D02*
X1181935Y128916D01*
X1183020Y129542D01*
X1184260Y129750D01*
X1185810Y129333D01*
X1186895Y128292D01*
X1187205Y127042D01*
X1187050Y125791D01*
X1186430Y124750D01*
X1183330Y122667D01*
X1181935Y121208D01*
X1181005Y119125D01*
X1180695Y117250D01*
X1187205D01*
G01X1196350Y116833D02*
X1196040Y117042D01*
Y117458D01*
X1196350Y117667D01*
X1196660Y117458D01*
Y117042D01*
X1196350Y116833D01*
G01X1208750Y129750D02*
X1207510Y129333D01*
X1206580Y128292D01*
X1205960Y127042D01*
X1205495Y125375D01*
X1205340Y123500D01*
X1205495Y121625D01*
X1205960Y119958D01*
X1206580Y118708D01*
X1207510Y117667D01*
X1208750Y117250D01*
X1209990Y117667D01*
X1210920Y118708D01*
X1211540Y119958D01*
X1212005Y121625D01*
X1212160Y123500D01*
X1212005Y125375D01*
X1211540Y127042D01*
X1210920Y128292D01*
X1209990Y129333D01*
X1208750Y129750D01*
G01X1218360Y116833D02*
X1223940Y129750D01*
G01X1231535Y121417D02*
X1235565D01*
G01X1243005Y127667D02*
X1243935Y128916D01*
X1245020Y129542D01*
X1246260Y129750D01*
X1247810Y129333D01*
X1248895Y128292D01*
X1249205Y127042D01*
X1249050Y125791D01*
X1248430Y124750D01*
X1245330Y122667D01*
X1243935Y121208D01*
X1243005Y119125D01*
X1242695Y117250D01*
X1249205D01*
G01X1258350Y116833D02*
X1258040Y117042D01*
Y117458D01*
X1258350Y117667D01*
X1258660Y117458D01*
Y117042D01*
X1258350Y116833D01*
G01X1270750Y129750D02*
X1269510Y129333D01*
X1268580Y128292D01*
X1267960Y127042D01*
X1267495Y125375D01*
X1267340Y123500D01*
X1267495Y121625D01*
X1267960Y119958D01*
X1268580Y118708D01*
X1269510Y117667D01*
X1270750Y117250D01*
X1271990Y117667D01*
X1272920Y118708D01*
X1273540Y119958D01*
X1274005Y121625D01*
X1274160Y123500D01*
X1274005Y125375D01*
X1273540Y127042D01*
X1272920Y128292D01*
X1271990Y129333D01*
X1270750Y129750D01*
G01X1169845Y146417D02*
X1173565D01*
G01X1171550Y149125D02*
Y143708D01*
G01X1180540Y144750D02*
X1181470Y143291D01*
X1182710Y142458D01*
X1184105Y142250D01*
X1185345Y142458D01*
X1186585Y143500D01*
X1187360Y144750D01*
X1187515Y146000D01*
X1187205Y147458D01*
X1186120Y148500D01*
X1185035Y148917D01*
X1183640D01*
G01X1185035D02*
X1185965Y149542D01*
X1186740Y150583D01*
X1187050Y151833D01*
X1186740Y153083D01*
X1185965Y154125D01*
X1184570Y154750D01*
X1183175Y154542D01*
X1181780Y153708D01*
G01X1196350Y141833D02*
X1196040Y142042D01*
Y142458D01*
X1196350Y142667D01*
X1196660Y142458D01*
Y142042D01*
X1196350Y141833D01*
G01X1208750Y154750D02*
X1207510Y154333D01*
X1206580Y153292D01*
X1205960Y152042D01*
X1205495Y150375D01*
X1205340Y148500D01*
X1205495Y146625D01*
X1205960Y144958D01*
X1206580Y143708D01*
X1207510Y142667D01*
X1208750Y142250D01*
X1209990Y142667D01*
X1210920Y143708D01*
X1211540Y144958D01*
X1212005Y146625D01*
X1212160Y148500D01*
X1212005Y150375D01*
X1211540Y152042D01*
X1210920Y153292D01*
X1209990Y154333D01*
X1208750Y154750D01*
G01X1218360Y141833D02*
X1223940Y154750D01*
G01X1231535Y146417D02*
X1235565D01*
G01X1242540Y144750D02*
X1243470Y143291D01*
X1244710Y142458D01*
X1246105Y142250D01*
X1247345Y142458D01*
X1248585Y143500D01*
X1249360Y144750D01*
X1249515Y146000D01*
X1249205Y147458D01*
X1248120Y148500D01*
X1247035Y148917D01*
X1245640D01*
G01X1247035D02*
X1247965Y149542D01*
X1248740Y150583D01*
X1249050Y151833D01*
X1248740Y153083D01*
X1247965Y154125D01*
X1246570Y154750D01*
X1245175Y154542D01*
X1243780Y153708D01*
G01X1258350Y141833D02*
X1258040Y142042D01*
Y142458D01*
X1258350Y142667D01*
X1258660Y142458D01*
Y142042D01*
X1258350Y141833D01*
G01X1270750Y154750D02*
X1269510Y154333D01*
X1268580Y153292D01*
X1267960Y152042D01*
X1267495Y150375D01*
X1267340Y148500D01*
X1267495Y146625D01*
X1267960Y144958D01*
X1268580Y143708D01*
X1269510Y142667D01*
X1270750Y142250D01*
X1271990Y142667D01*
X1272920Y143708D01*
X1273540Y144958D01*
X1274005Y146625D01*
X1274160Y148500D01*
X1274005Y150375D01*
X1273540Y152042D01*
X1272920Y153292D01*
X1271990Y154333D01*
X1270750Y154750D01*
G01X1169845Y171417D02*
X1173565D01*
G01X1171550Y174125D02*
Y168708D01*
G01X1180540Y169750D02*
X1181470Y168291D01*
X1182710Y167458D01*
X1184105Y167250D01*
X1185345Y167458D01*
X1186585Y168500D01*
X1187360Y169750D01*
X1187515Y171000D01*
X1187205Y172458D01*
X1186120Y173500D01*
X1185035Y173917D01*
X1183640D01*
G01X1185035D02*
X1185965Y174542D01*
X1186740Y175583D01*
X1187050Y176833D01*
X1186740Y178083D01*
X1185965Y179125D01*
X1184570Y179750D01*
X1183175Y179542D01*
X1181780Y178708D01*
G01X1196350Y166833D02*
X1196040Y167042D01*
Y167458D01*
X1196350Y167667D01*
X1196660Y167458D01*
Y167042D01*
X1196350Y166833D01*
G01X1208750Y179750D02*
X1207510Y179333D01*
X1206580Y178292D01*
X1205960Y177042D01*
X1205495Y175375D01*
X1205340Y173500D01*
X1205495Y171625D01*
X1205960Y169958D01*
X1206580Y168708D01*
X1207510Y167667D01*
X1208750Y167250D01*
X1209990Y167667D01*
X1210920Y168708D01*
X1211540Y169958D01*
X1212005Y171625D01*
X1212160Y173500D01*
X1212005Y175375D01*
X1211540Y177042D01*
X1210920Y178292D01*
X1209990Y179333D01*
X1208750Y179750D01*
G01X1218360Y166833D02*
X1223940Y179750D01*
G01X1231535Y171417D02*
X1235565D01*
G01X1242540Y169750D02*
X1243470Y168291D01*
X1244710Y167458D01*
X1246105Y167250D01*
X1247345Y167458D01*
X1248585Y168500D01*
X1249360Y169750D01*
X1249515Y171000D01*
X1249205Y172458D01*
X1248120Y173500D01*
X1247035Y173917D01*
X1245640D01*
G01X1247035D02*
X1247965Y174542D01*
X1248740Y175583D01*
X1249050Y176833D01*
X1248740Y178083D01*
X1247965Y179125D01*
X1246570Y179750D01*
X1245175Y179542D01*
X1243780Y178708D01*
G01X1258350Y166833D02*
X1258040Y167042D01*
Y167458D01*
X1258350Y167667D01*
X1258660Y167458D01*
Y167042D01*
X1258350Y166833D01*
G01X1270750Y179750D02*
X1269510Y179333D01*
X1268580Y178292D01*
X1267960Y177042D01*
X1267495Y175375D01*
X1267340Y173500D01*
X1267495Y171625D01*
X1267960Y169958D01*
X1268580Y168708D01*
X1269510Y167667D01*
X1270750Y167250D01*
X1271990Y167667D01*
X1272920Y168708D01*
X1273540Y169958D01*
X1274005Y171625D01*
X1274160Y173500D01*
X1274005Y175375D01*
X1273540Y177042D01*
X1272920Y178292D01*
X1271990Y179333D01*
X1270750Y179750D01*
G01X1169845Y196417D02*
X1173565D01*
G01X1171550Y199125D02*
Y193708D01*
G01X1180540Y194750D02*
X1181470Y193291D01*
X1182710Y192458D01*
X1184105Y192250D01*
X1185345Y192458D01*
X1186585Y193500D01*
X1187360Y194750D01*
X1187515Y196000D01*
X1187205Y197458D01*
X1186120Y198500D01*
X1185035Y198917D01*
X1183640D01*
G01X1185035D02*
X1185965Y199542D01*
X1186740Y200583D01*
X1187050Y201833D01*
X1186740Y203083D01*
X1185965Y204125D01*
X1184570Y204750D01*
X1183175Y204542D01*
X1181780Y203708D01*
G01X1196350Y191833D02*
X1196040Y192042D01*
Y192458D01*
X1196350Y192667D01*
X1196660Y192458D01*
Y192042D01*
X1196350Y191833D01*
G01X1208750Y204750D02*
X1207510Y204333D01*
X1206580Y203292D01*
X1205960Y202042D01*
X1205495Y200375D01*
X1205340Y198500D01*
X1205495Y196625D01*
X1205960Y194958D01*
X1206580Y193708D01*
X1207510Y192667D01*
X1208750Y192250D01*
X1209990Y192667D01*
X1210920Y193708D01*
X1211540Y194958D01*
X1212005Y196625D01*
X1212160Y198500D01*
X1212005Y200375D01*
X1211540Y202042D01*
X1210920Y203292D01*
X1209990Y204333D01*
X1208750Y204750D01*
G01X1218360Y191833D02*
X1223940Y204750D01*
G01X1231535Y196417D02*
X1235565D01*
G01X1242540Y194750D02*
X1243470Y193291D01*
X1244710Y192458D01*
X1246105Y192250D01*
X1247345Y192458D01*
X1248585Y193500D01*
X1249360Y194750D01*
X1249515Y196000D01*
X1249205Y197458D01*
X1248120Y198500D01*
X1247035Y198917D01*
X1245640D01*
G01X1247035D02*
X1247965Y199542D01*
X1248740Y200583D01*
X1249050Y201833D01*
X1248740Y203083D01*
X1247965Y204125D01*
X1246570Y204750D01*
X1245175Y204542D01*
X1243780Y203708D01*
G01X1258350Y191833D02*
X1258040Y192042D01*
Y192458D01*
X1258350Y192667D01*
X1258660Y192458D01*
Y192042D01*
X1258350Y191833D01*
G01X1270750Y204750D02*
X1269510Y204333D01*
X1268580Y203292D01*
X1267960Y202042D01*
X1267495Y200375D01*
X1267340Y198500D01*
X1267495Y196625D01*
X1267960Y194958D01*
X1268580Y193708D01*
X1269510Y192667D01*
X1270750Y192250D01*
X1271990Y192667D01*
X1272920Y193708D01*
X1273540Y194958D01*
X1274005Y196625D01*
X1274160Y198500D01*
X1274005Y200375D01*
X1273540Y202042D01*
X1272920Y203292D01*
X1271990Y204333D01*
X1270750Y204750D01*
G01X1169845Y221417D02*
X1173565D01*
G01X1171550Y224125D02*
Y218708D01*
G01X1180540Y219750D02*
X1181470Y218291D01*
X1182710Y217458D01*
X1184105Y217250D01*
X1185345Y217458D01*
X1186585Y218500D01*
X1187360Y219750D01*
X1187515Y221000D01*
X1187205Y222458D01*
X1186120Y223500D01*
X1185035Y223917D01*
X1183640D01*
G01X1185035D02*
X1185965Y224542D01*
X1186740Y225583D01*
X1187050Y226833D01*
X1186740Y228083D01*
X1185965Y229125D01*
X1184570Y229750D01*
X1183175Y229542D01*
X1181780Y228708D01*
G01X1196350Y216833D02*
X1196040Y217042D01*
Y217458D01*
X1196350Y217667D01*
X1196660Y217458D01*
Y217042D01*
X1196350Y216833D01*
G01X1208750Y229750D02*
X1207510Y229333D01*
X1206580Y228292D01*
X1205960Y227042D01*
X1205495Y225375D01*
X1205340Y223500D01*
X1205495Y221625D01*
X1205960Y219958D01*
X1206580Y218708D01*
X1207510Y217667D01*
X1208750Y217250D01*
X1209990Y217667D01*
X1210920Y218708D01*
X1211540Y219958D01*
X1212005Y221625D01*
X1212160Y223500D01*
X1212005Y225375D01*
X1211540Y227042D01*
X1210920Y228292D01*
X1209990Y229333D01*
X1208750Y229750D01*
G01X1218360Y216833D02*
X1223940Y229750D01*
G01X1231535Y221417D02*
X1235565D01*
G01X1242540Y219750D02*
X1243470Y218291D01*
X1244710Y217458D01*
X1246105Y217250D01*
X1247345Y217458D01*
X1248585Y218500D01*
X1249360Y219750D01*
X1249515Y221000D01*
X1249205Y222458D01*
X1248120Y223500D01*
X1247035Y223917D01*
X1245640D01*
G01X1247035D02*
X1247965Y224542D01*
X1248740Y225583D01*
X1249050Y226833D01*
X1248740Y228083D01*
X1247965Y229125D01*
X1246570Y229750D01*
X1245175Y229542D01*
X1243780Y228708D01*
G01X1258350Y216833D02*
X1258040Y217042D01*
Y217458D01*
X1258350Y217667D01*
X1258660Y217458D01*
Y217042D01*
X1258350Y216833D01*
G01X1270750Y229750D02*
X1269510Y229333D01*
X1268580Y228292D01*
X1267960Y227042D01*
X1267495Y225375D01*
X1267340Y223500D01*
X1267495Y221625D01*
X1267960Y219958D01*
X1268580Y218708D01*
X1269510Y217667D01*
X1270750Y217250D01*
X1271990Y217667D01*
X1272920Y218708D01*
X1273540Y219958D01*
X1274005Y221625D01*
X1274160Y223500D01*
X1274005Y225375D01*
X1273540Y227042D01*
X1272920Y228292D01*
X1271990Y229333D01*
X1270750Y229750D01*
G01X1169845Y246417D02*
X1173565D01*
G01X1171550Y249125D02*
Y243708D01*
G01X1180540Y244750D02*
X1181470Y243291D01*
X1182710Y242458D01*
X1184105Y242250D01*
X1185345Y242458D01*
X1186585Y243500D01*
X1187360Y244750D01*
X1187515Y246000D01*
X1187205Y247458D01*
X1186120Y248500D01*
X1185035Y248917D01*
X1183640D01*
G01X1185035D02*
X1185965Y249542D01*
X1186740Y250583D01*
X1187050Y251833D01*
X1186740Y253083D01*
X1185965Y254125D01*
X1184570Y254750D01*
X1183175Y254542D01*
X1181780Y253708D01*
G01X1196350Y241833D02*
X1196040Y242042D01*
Y242458D01*
X1196350Y242667D01*
X1196660Y242458D01*
Y242042D01*
X1196350Y241833D01*
G01X1208750Y254750D02*
X1207510Y254333D01*
X1206580Y253292D01*
X1205960Y252042D01*
X1205495Y250375D01*
X1205340Y248500D01*
X1205495Y246625D01*
X1205960Y244958D01*
X1206580Y243708D01*
X1207510Y242667D01*
X1208750Y242250D01*
X1209990Y242667D01*
X1210920Y243708D01*
X1211540Y244958D01*
X1212005Y246625D01*
X1212160Y248500D01*
X1212005Y250375D01*
X1211540Y252042D01*
X1210920Y253292D01*
X1209990Y254333D01*
X1208750Y254750D01*
G01X1218360Y241833D02*
X1223940Y254750D01*
G01X1231535Y246417D02*
X1235565D01*
G01X1242540Y244750D02*
X1243470Y243291D01*
X1244710Y242458D01*
X1246105Y242250D01*
X1247345Y242458D01*
X1248585Y243500D01*
X1249360Y244750D01*
X1249515Y246000D01*
X1249205Y247458D01*
X1248120Y248500D01*
X1247035Y248917D01*
X1245640D01*
G01X1247035D02*
X1247965Y249542D01*
X1248740Y250583D01*
X1249050Y251833D01*
X1248740Y253083D01*
X1247965Y254125D01*
X1246570Y254750D01*
X1245175Y254542D01*
X1243780Y253708D01*
G01X1258350Y241833D02*
X1258040Y242042D01*
Y242458D01*
X1258350Y242667D01*
X1258660Y242458D01*
Y242042D01*
X1258350Y241833D01*
G01X1270750Y254750D02*
X1269510Y254333D01*
X1268580Y253292D01*
X1267960Y252042D01*
X1267495Y250375D01*
X1267340Y248500D01*
X1267495Y246625D01*
X1267960Y244958D01*
X1268580Y243708D01*
X1269510Y242667D01*
X1270750Y242250D01*
X1271990Y242667D01*
X1272920Y243708D01*
X1273540Y244958D01*
X1274005Y246625D01*
X1274160Y248500D01*
X1274005Y250375D01*
X1273540Y252042D01*
X1272920Y253292D01*
X1271990Y254333D01*
X1270750Y254750D01*
G01X1169845Y271417D02*
X1173565D01*
G01X1171550Y274125D02*
Y268708D01*
G01X1180540Y269750D02*
X1181470Y268291D01*
X1182710Y267458D01*
X1184105Y267250D01*
X1185345Y267458D01*
X1186585Y268500D01*
X1187360Y269750D01*
X1187515Y271000D01*
X1187205Y272458D01*
X1186120Y273500D01*
X1185035Y273917D01*
X1183640D01*
G01X1185035D02*
X1185965Y274542D01*
X1186740Y275583D01*
X1187050Y276833D01*
X1186740Y278083D01*
X1185965Y279125D01*
X1184570Y279750D01*
X1183175Y279542D01*
X1181780Y278708D01*
G01X1196350Y266833D02*
X1196040Y267042D01*
Y267458D01*
X1196350Y267667D01*
X1196660Y267458D01*
Y267042D01*
X1196350Y266833D01*
G01X1208750Y279750D02*
X1207510Y279333D01*
X1206580Y278292D01*
X1205960Y277042D01*
X1205495Y275375D01*
X1205340Y273500D01*
X1205495Y271625D01*
X1205960Y269958D01*
X1206580Y268708D01*
X1207510Y267667D01*
X1208750Y267250D01*
X1209990Y267667D01*
X1210920Y268708D01*
X1211540Y269958D01*
X1212005Y271625D01*
X1212160Y273500D01*
X1212005Y275375D01*
X1211540Y277042D01*
X1210920Y278292D01*
X1209990Y279333D01*
X1208750Y279750D01*
G01X1218360Y266833D02*
X1223940Y279750D01*
G01X1231535Y271417D02*
X1235565D01*
G01X1242540Y269750D02*
X1243470Y268291D01*
X1244710Y267458D01*
X1246105Y267250D01*
X1247345Y267458D01*
X1248585Y268500D01*
X1249360Y269750D01*
X1249515Y271000D01*
X1249205Y272458D01*
X1248120Y273500D01*
X1247035Y273917D01*
X1245640D01*
G01X1247035D02*
X1247965Y274542D01*
X1248740Y275583D01*
X1249050Y276833D01*
X1248740Y278083D01*
X1247965Y279125D01*
X1246570Y279750D01*
X1245175Y279542D01*
X1243780Y278708D01*
G01X1258350Y266833D02*
X1258040Y267042D01*
Y267458D01*
X1258350Y267667D01*
X1258660Y267458D01*
Y267042D01*
X1258350Y266833D01*
G01X1270750Y279750D02*
X1269510Y279333D01*
X1268580Y278292D01*
X1267960Y277042D01*
X1267495Y275375D01*
X1267340Y273500D01*
X1267495Y271625D01*
X1267960Y269958D01*
X1268580Y268708D01*
X1269510Y267667D01*
X1270750Y267250D01*
X1271990Y267667D01*
X1272920Y268708D01*
X1273540Y269958D01*
X1274005Y271625D01*
X1274160Y273500D01*
X1274005Y275375D01*
X1273540Y277042D01*
X1272920Y278292D01*
X1271990Y279333D01*
X1270750Y279750D01*
G01X1169845Y296417D02*
X1173565D01*
G01X1171550Y299125D02*
Y293708D01*
G01X1180540Y294750D02*
X1181470Y293291D01*
X1182710Y292458D01*
X1184105Y292250D01*
X1185345Y292458D01*
X1186585Y293500D01*
X1187360Y294750D01*
X1187515Y296000D01*
X1187205Y297458D01*
X1186120Y298500D01*
X1185035Y298917D01*
X1183640D01*
G01X1185035D02*
X1185965Y299542D01*
X1186740Y300583D01*
X1187050Y301833D01*
X1186740Y303083D01*
X1185965Y304125D01*
X1184570Y304750D01*
X1183175Y304542D01*
X1181780Y303708D01*
G01X1196350Y291833D02*
X1196040Y292042D01*
Y292458D01*
X1196350Y292667D01*
X1196660Y292458D01*
Y292042D01*
X1196350Y291833D01*
G01X1208750Y304750D02*
X1207510Y304333D01*
X1206580Y303292D01*
X1205960Y302042D01*
X1205495Y300375D01*
X1205340Y298500D01*
X1205495Y296625D01*
X1205960Y294958D01*
X1206580Y293708D01*
X1207510Y292667D01*
X1208750Y292250D01*
X1209990Y292667D01*
X1210920Y293708D01*
X1211540Y294958D01*
X1212005Y296625D01*
X1212160Y298500D01*
X1212005Y300375D01*
X1211540Y302042D01*
X1210920Y303292D01*
X1209990Y304333D01*
X1208750Y304750D01*
G01X1218360Y291833D02*
X1223940Y304750D01*
G01X1231535Y296417D02*
X1235565D01*
G01X1242540Y294750D02*
X1243470Y293291D01*
X1244710Y292458D01*
X1246105Y292250D01*
X1247345Y292458D01*
X1248585Y293500D01*
X1249360Y294750D01*
X1249515Y296000D01*
X1249205Y297458D01*
X1248120Y298500D01*
X1247035Y298917D01*
X1245640D01*
G01X1247035D02*
X1247965Y299542D01*
X1248740Y300583D01*
X1249050Y301833D01*
X1248740Y303083D01*
X1247965Y304125D01*
X1246570Y304750D01*
X1245175Y304542D01*
X1243780Y303708D01*
G01X1258350Y291833D02*
X1258040Y292042D01*
Y292458D01*
X1258350Y292667D01*
X1258660Y292458D01*
Y292042D01*
X1258350Y291833D01*
G01X1270750Y304750D02*
X1269510Y304333D01*
X1268580Y303292D01*
X1267960Y302042D01*
X1267495Y300375D01*
X1267340Y298500D01*
X1267495Y296625D01*
X1267960Y294958D01*
X1268580Y293708D01*
X1269510Y292667D01*
X1270750Y292250D01*
X1271990Y292667D01*
X1272920Y293708D01*
X1273540Y294958D01*
X1274005Y296625D01*
X1274160Y298500D01*
X1274005Y300375D01*
X1273540Y302042D01*
X1272920Y303292D01*
X1271990Y304333D01*
X1270750Y304750D01*
G01X1163645Y321417D02*
X1167365D01*
G01X1165350Y324125D02*
Y318708D01*
G01X1177750Y329750D02*
X1176510Y329333D01*
X1175580Y328292D01*
X1174960Y327042D01*
X1174495Y325375D01*
X1174340Y323500D01*
X1174495Y321625D01*
X1174960Y319958D01*
X1175580Y318708D01*
X1176510Y317667D01*
X1177750Y317250D01*
X1178990Y317667D01*
X1179920Y318708D01*
X1180540Y319958D01*
X1181005Y321625D01*
X1181160Y323500D01*
X1181005Y325375D01*
X1180540Y327042D01*
X1179920Y328292D01*
X1178990Y329333D01*
X1177750Y329750D01*
G01X1190150Y316833D02*
X1189840Y317042D01*
Y317458D01*
X1190150Y317667D01*
X1190460Y317458D01*
Y317042D01*
X1190150Y316833D01*
G01X1202550Y329750D02*
X1201310Y329333D01*
X1200380Y328292D01*
X1199760Y327042D01*
X1199295Y325375D01*
X1199140Y323500D01*
X1199295Y321625D01*
X1199760Y319958D01*
X1200380Y318708D01*
X1201310Y317667D01*
X1202550Y317250D01*
X1203790Y317667D01*
X1204720Y318708D01*
X1205340Y319958D01*
X1205805Y321625D01*
X1205960Y323500D01*
X1205805Y325375D01*
X1205340Y327042D01*
X1204720Y328292D01*
X1203790Y329333D01*
X1202550Y329750D01*
G01X1212160Y316833D02*
X1217740Y329750D01*
G01X1225335Y321417D02*
X1229365D01*
G01X1239750Y317250D02*
Y329750D01*
X1237890Y327250D01*
G01Y317250D02*
X1241610D01*
G01X1249205Y327667D02*
X1250135Y328916D01*
X1251220Y329542D01*
X1252460Y329750D01*
X1254010Y329333D01*
X1255095Y328292D01*
X1255405Y327042D01*
X1255250Y325791D01*
X1254630Y324750D01*
X1251530Y322667D01*
X1250135Y321208D01*
X1249205Y319125D01*
X1248895Y317250D01*
X1255405D01*
G01X1264550Y316833D02*
X1264240Y317042D01*
Y317458D01*
X1264550Y317667D01*
X1264860Y317458D01*
Y317042D01*
X1264550Y316833D01*
G01X1276950Y329750D02*
X1275710Y329333D01*
X1274780Y328292D01*
X1274160Y327042D01*
X1273695Y325375D01*
X1273540Y323500D01*
X1273695Y321625D01*
X1274160Y319958D01*
X1274780Y318708D01*
X1275710Y317667D01*
X1276950Y317250D01*
X1278190Y317667D01*
X1279120Y318708D01*
X1279740Y319958D01*
X1280205Y321625D01*
X1280360Y323500D01*
X1280205Y325375D01*
X1279740Y327042D01*
X1279120Y328292D01*
X1278190Y329333D01*
X1276950Y329750D01*
G01X1163645Y346417D02*
X1167365D01*
G01X1165350Y349125D02*
Y343708D01*
G01X1177750Y354750D02*
X1176510Y354333D01*
X1175580Y353292D01*
X1174960Y352042D01*
X1174495Y350375D01*
X1174340Y348500D01*
X1174495Y346625D01*
X1174960Y344958D01*
X1175580Y343708D01*
X1176510Y342667D01*
X1177750Y342250D01*
X1178990Y342667D01*
X1179920Y343708D01*
X1180540Y344958D01*
X1181005Y346625D01*
X1181160Y348500D01*
X1181005Y350375D01*
X1180540Y352042D01*
X1179920Y353292D01*
X1178990Y354333D01*
X1177750Y354750D01*
G01X1190150Y341833D02*
X1189840Y342042D01*
Y342458D01*
X1190150Y342667D01*
X1190460Y342458D01*
Y342042D01*
X1190150Y341833D01*
G01X1202550Y354750D02*
X1201310Y354333D01*
X1200380Y353292D01*
X1199760Y352042D01*
X1199295Y350375D01*
X1199140Y348500D01*
X1199295Y346625D01*
X1199760Y344958D01*
X1200380Y343708D01*
X1201310Y342667D01*
X1202550Y342250D01*
X1203790Y342667D01*
X1204720Y343708D01*
X1205340Y344958D01*
X1205805Y346625D01*
X1205960Y348500D01*
X1205805Y350375D01*
X1205340Y352042D01*
X1204720Y353292D01*
X1203790Y354333D01*
X1202550Y354750D01*
G01X1212160Y341833D02*
X1217740Y354750D01*
G01X1225335Y346417D02*
X1229365D01*
G01X1239750Y342250D02*
Y354750D01*
X1237890Y352250D01*
G01Y342250D02*
X1241610D01*
G01X1252150Y354750D02*
X1250910Y354333D01*
X1249980Y353292D01*
X1249360Y352042D01*
X1248895Y350375D01*
X1248740Y348500D01*
X1248895Y346625D01*
X1249360Y344958D01*
X1249980Y343708D01*
X1250910Y342667D01*
X1252150Y342250D01*
X1253390Y342667D01*
X1254320Y343708D01*
X1254940Y344958D01*
X1255405Y346625D01*
X1255560Y348500D01*
X1255405Y350375D01*
X1254940Y352042D01*
X1254320Y353292D01*
X1253390Y354333D01*
X1252150Y354750D01*
G01X1264550Y341833D02*
X1264240Y342042D01*
Y342458D01*
X1264550Y342667D01*
X1264860Y342458D01*
Y342042D01*
X1264550Y341833D01*
G01X1276950Y354750D02*
X1275710Y354333D01*
X1274780Y353292D01*
X1274160Y352042D01*
X1273695Y350375D01*
X1273540Y348500D01*
X1273695Y346625D01*
X1274160Y344958D01*
X1274780Y343708D01*
X1275710Y342667D01*
X1276950Y342250D01*
X1278190Y342667D01*
X1279120Y343708D01*
X1279740Y344958D01*
X1280205Y346625D01*
X1280360Y348500D01*
X1280205Y350375D01*
X1279740Y352042D01*
X1279120Y353292D01*
X1278190Y354333D01*
X1276950Y354750D01*
G01X1169845Y371417D02*
X1173565D01*
G01X1171550Y374125D02*
Y368708D01*
G01X1183950Y379750D02*
X1182710Y379333D01*
X1181780Y378292D01*
X1181160Y377042D01*
X1180695Y375375D01*
X1180540Y373500D01*
X1180695Y371625D01*
X1181160Y369958D01*
X1181780Y368708D01*
X1182710Y367667D01*
X1183950Y367250D01*
X1185190Y367667D01*
X1186120Y368708D01*
X1186740Y369958D01*
X1187205Y371625D01*
X1187360Y373500D01*
X1187205Y375375D01*
X1186740Y377042D01*
X1186120Y378292D01*
X1185190Y379333D01*
X1183950Y379750D01*
G01X1196350Y366833D02*
X1196040Y367042D01*
Y367458D01*
X1196350Y367667D01*
X1196660Y367458D01*
Y367042D01*
X1196350Y366833D01*
G01X1208750Y379750D02*
X1207510Y379333D01*
X1206580Y378292D01*
X1205960Y377042D01*
X1205495Y375375D01*
X1205340Y373500D01*
X1205495Y371625D01*
X1205960Y369958D01*
X1206580Y368708D01*
X1207510Y367667D01*
X1208750Y367250D01*
X1209990Y367667D01*
X1210920Y368708D01*
X1211540Y369958D01*
X1212005Y371625D01*
X1212160Y373500D01*
X1212005Y375375D01*
X1211540Y377042D01*
X1210920Y378292D01*
X1209990Y379333D01*
X1208750Y379750D01*
G01X1218360Y366833D02*
X1223940Y379750D01*
G01X1231535Y371417D02*
X1235565D01*
G01X1245950Y367250D02*
X1247035Y367458D01*
X1248275Y368083D01*
X1249050Y369125D01*
X1249360Y370583D01*
X1249050Y372041D01*
X1248120Y373292D01*
X1246725Y373917D01*
X1245175D01*
X1244245Y374333D01*
X1243470Y375375D01*
X1243160Y376833D01*
X1243625Y378292D01*
X1244710Y379333D01*
X1245950Y379750D01*
X1247190Y379333D01*
X1248275Y378292D01*
X1248740Y376833D01*
X1248430Y375375D01*
X1247655Y374333D01*
X1246725Y373917D01*
X1245175D01*
X1243780Y373292D01*
X1242850Y372041D01*
X1242540Y370583D01*
X1242850Y369125D01*
X1243625Y368083D01*
X1244865Y367458D01*
X1245950Y367250D01*
G01X1258350Y366833D02*
X1258040Y367042D01*
Y367458D01*
X1258350Y367667D01*
X1258660Y367458D01*
Y367042D01*
X1258350Y366833D01*
G01X1270750Y379750D02*
X1269510Y379333D01*
X1268580Y378292D01*
X1267960Y377042D01*
X1267495Y375375D01*
X1267340Y373500D01*
X1267495Y371625D01*
X1267960Y369958D01*
X1268580Y368708D01*
X1269510Y367667D01*
X1270750Y367250D01*
X1271990Y367667D01*
X1272920Y368708D01*
X1273540Y369958D01*
X1274005Y371625D01*
X1274160Y373500D01*
X1274005Y375375D01*
X1273540Y377042D01*
X1272920Y378292D01*
X1271990Y379333D01*
X1270750Y379750D01*
G01X1277500Y-1436500D02*
Y-1416500D01*
X1274500Y-1420500D01*
G01Y-1436500D02*
X1280500D01*
G01X1297500Y-1437167D02*
X1297000Y-1436833D01*
Y-1436167D01*
X1297500Y-1435833D01*
X1298000Y-1436167D01*
Y-1436833D01*
X1297500Y-1437167D01*
G01Y-1428167D02*
X1297000Y-1427833D01*
Y-1427167D01*
X1297500Y-1426834D01*
X1298000Y-1427167D01*
Y-1427833D01*
X1297500Y-1428167D01*
G01X1317500Y-1436500D02*
Y-1416500D01*
X1314500Y-1420500D01*
G01Y-1436500D02*
X1320500D01*
G01X1284610Y-1466600D02*
X1286490D01*
G01X1285550D02*
Y-1472900D01*
G01X1284610D02*
X1286490D01*
G01X1290048D02*
Y-1466600D01*
X1293652Y-1472900D01*
Y-1466600D01*
G01X1299873Y-1467125D02*
X1299403Y-1466810D01*
X1298855Y-1466600D01*
X1298228D01*
X1297523Y-1466915D01*
X1296975Y-1467440D01*
X1296583Y-1468070D01*
X1296270Y-1469120D01*
X1296192Y-1470065D01*
X1296348Y-1471010D01*
X1296583Y-1471640D01*
X1297053Y-1472270D01*
X1297602Y-1472690D01*
X1298150Y-1472900D01*
X1298698D01*
X1299247Y-1472690D01*
X1299717Y-1472375D01*
X1300108Y-1471955D01*
G01X1302805Y-1472900D02*
Y-1466600D01*
G01X1306095D02*
Y-1472900D01*
G01Y-1469750D02*
X1302805D01*
G01X1295450Y4750D02*
Y-7750D01*
G01X1291885Y4750D02*
X1299015D01*
G01X1307850Y-7750D02*
X1306610Y-7542D01*
X1305525Y-6709D01*
X1304595Y-5458D01*
X1303975Y-4000D01*
X1303665Y-2333D01*
Y-667D01*
X1303975Y1000D01*
X1304595Y2458D01*
X1305525Y3708D01*
X1306610Y4542D01*
X1307850Y4750D01*
X1309090Y4542D01*
X1310175Y3708D01*
X1311105Y2458D01*
X1311725Y1000D01*
X1312035Y-667D01*
Y-2333D01*
X1311725Y-4000D01*
X1311105Y-5458D01*
X1310175Y-6709D01*
X1309090Y-7542D01*
X1307850Y-7750D01*
G01X1320250Y4750D02*
Y-7750D01*
G01X1316685Y4750D02*
X1323815D01*
G01X1328775Y-7750D02*
X1332650Y4750D01*
X1336525Y-7750D01*
G01X1335130Y-3375D02*
X1330170D01*
G01X1341950Y4750D02*
Y-7750D01*
X1348150D01*
G01X1366595D02*
Y4750D01*
G01X1373105D02*
Y-7750D01*
G01Y-1500D02*
X1366595D01*
G01X1382250Y-7750D02*
X1381010Y-7542D01*
X1379925Y-6709D01*
X1378995Y-5458D01*
X1378375Y-4000D01*
X1378065Y-2333D01*
Y-667D01*
X1378375Y1000D01*
X1378995Y2458D01*
X1379925Y3708D01*
X1381010Y4542D01*
X1382250Y4750D01*
X1383490Y4542D01*
X1384575Y3708D01*
X1385505Y2458D01*
X1386125Y1000D01*
X1386435Y-667D01*
Y-2333D01*
X1386125Y-4000D01*
X1385505Y-5458D01*
X1384575Y-6709D01*
X1383490Y-7542D01*
X1382250Y-7750D01*
G01X1391550Y4750D02*
Y-7750D01*
X1397750D01*
G01X1410150D02*
X1403950D01*
Y4750D01*
X1410150D01*
G01X1407670Y-1292D02*
X1403950D01*
G01X1416195Y-6084D02*
X1417435Y-7125D01*
X1418830Y-7750D01*
X1420070D01*
X1421310Y-7125D01*
X1422240Y-6084D01*
X1422705Y-4625D01*
X1422395Y-3167D01*
X1421620Y-1917D01*
X1420225Y-1083D01*
X1418365Y-667D01*
X1417280Y167D01*
X1416815Y1625D01*
X1417125Y3083D01*
X1417900Y4125D01*
X1418985Y4750D01*
X1420070D01*
X1421155Y4333D01*
X1422085Y3292D01*
G01X1431850Y-8167D02*
X1431540Y-7958D01*
Y-7542D01*
X1431850Y-7333D01*
X1432160Y-7542D01*
Y-7958D01*
X1431850Y-8167D01*
G01Y-2542D02*
X1431540Y-2333D01*
Y-1917D01*
X1431850Y-1708D01*
X1432160Y-1917D01*
Y-2333D01*
X1431850Y-2542D01*
G01X1321900Y411000D02*
Y11000D01*
G01X1326085Y67250D02*
Y79750D01*
X1333215Y67250D01*
Y79750D01*
G01X1342050Y67250D02*
X1340810Y67458D01*
X1339725Y68291D01*
X1338795Y69542D01*
X1338175Y71000D01*
X1337865Y72667D01*
Y74333D01*
X1338175Y76000D01*
X1338795Y77458D01*
X1339725Y78708D01*
X1340810Y79542D01*
X1342050Y79750D01*
X1343290Y79542D01*
X1344375Y78708D01*
X1345305Y77458D01*
X1345925Y76000D01*
X1346235Y74333D01*
Y72667D01*
X1345925Y71000D01*
X1345305Y69542D01*
X1344375Y68291D01*
X1343290Y67458D01*
X1342050Y67250D01*
G01X1350885D02*
Y79750D01*
X1358015Y67250D01*
Y79750D01*
G01X1364835Y71417D02*
X1368865D01*
G01X1376150Y67250D02*
Y79750D01*
X1379870D01*
X1381110Y79125D01*
X1382040Y77667D01*
X1382350Y76000D01*
X1382040Y74333D01*
X1381265Y73083D01*
X1379870Y72458D01*
X1376150D01*
G01X1388550Y79750D02*
Y67250D01*
X1394750D01*
G01X1400175D02*
X1404050Y79750D01*
X1407925Y67250D01*
G01X1406530Y71625D02*
X1401570D01*
G01X1416450Y79750D02*
Y67250D01*
G01X1412885Y79750D02*
X1420015D01*
G01X1431950Y67250D02*
X1425750D01*
Y79750D01*
X1431950D01*
G01X1429470Y73708D02*
X1425750D01*
G01X1437840Y67250D02*
Y79750D01*
X1440940D01*
X1442180Y79125D01*
X1443110Y78292D01*
X1443885Y77042D01*
X1444505Y75583D01*
X1444660Y73500D01*
X1444505Y71417D01*
X1443885Y69958D01*
X1443110Y68708D01*
X1442180Y67875D01*
X1440940Y67250D01*
X1437840D01*
G01X1326085Y92250D02*
Y104750D01*
X1333215Y92250D01*
Y104750D01*
G01X1342050Y92250D02*
X1340810Y92458D01*
X1339725Y93291D01*
X1338795Y94542D01*
X1338175Y96000D01*
X1337865Y97667D01*
Y99333D01*
X1338175Y101000D01*
X1338795Y102458D01*
X1339725Y103708D01*
X1340810Y104542D01*
X1342050Y104750D01*
X1343290Y104542D01*
X1344375Y103708D01*
X1345305Y102458D01*
X1345925Y101000D01*
X1346235Y99333D01*
Y97667D01*
X1345925Y96000D01*
X1345305Y94542D01*
X1344375Y93291D01*
X1343290Y92458D01*
X1342050Y92250D01*
G01X1350885D02*
Y104750D01*
X1358015Y92250D01*
Y104750D01*
G01X1364835Y96417D02*
X1368865D01*
G01X1376150Y92250D02*
Y104750D01*
X1379870D01*
X1381110Y104125D01*
X1382040Y102667D01*
X1382350Y101000D01*
X1382040Y99333D01*
X1381265Y98083D01*
X1379870Y97458D01*
X1376150D01*
G01X1388550Y104750D02*
Y92250D01*
X1394750D01*
G01X1400175D02*
X1404050Y104750D01*
X1407925Y92250D01*
G01X1406530Y96625D02*
X1401570D01*
G01X1416450Y104750D02*
Y92250D01*
G01X1412885Y104750D02*
X1420015D01*
G01X1431950Y92250D02*
X1425750D01*
Y104750D01*
X1431950D01*
G01X1429470Y98708D02*
X1425750D01*
G01X1437840Y92250D02*
Y104750D01*
X1440940D01*
X1442180Y104125D01*
X1443110Y103292D01*
X1443885Y102042D01*
X1444505Y100583D01*
X1444660Y98500D01*
X1444505Y96417D01*
X1443885Y94958D01*
X1443110Y93708D01*
X1442180Y92875D01*
X1440940Y92250D01*
X1437840D01*
G01X1326085Y117250D02*
Y129750D01*
X1333215Y117250D01*
Y129750D01*
G01X1342050Y117250D02*
X1340810Y117458D01*
X1339725Y118291D01*
X1338795Y119542D01*
X1338175Y121000D01*
X1337865Y122667D01*
Y124333D01*
X1338175Y126000D01*
X1338795Y127458D01*
X1339725Y128708D01*
X1340810Y129542D01*
X1342050Y129750D01*
X1343290Y129542D01*
X1344375Y128708D01*
X1345305Y127458D01*
X1345925Y126000D01*
X1346235Y124333D01*
Y122667D01*
X1345925Y121000D01*
X1345305Y119542D01*
X1344375Y118291D01*
X1343290Y117458D01*
X1342050Y117250D01*
G01X1350885D02*
Y129750D01*
X1358015Y117250D01*
Y129750D01*
G01X1364835Y121417D02*
X1368865D01*
G01X1376150Y117250D02*
Y129750D01*
X1379870D01*
X1381110Y129125D01*
X1382040Y127667D01*
X1382350Y126000D01*
X1382040Y124333D01*
X1381265Y123083D01*
X1379870Y122458D01*
X1376150D01*
G01X1388550Y129750D02*
Y117250D01*
X1394750D01*
G01X1400175D02*
X1404050Y129750D01*
X1407925Y117250D01*
G01X1406530Y121625D02*
X1401570D01*
G01X1416450Y129750D02*
Y117250D01*
G01X1412885Y129750D02*
X1420015D01*
G01X1431950Y117250D02*
X1425750D01*
Y129750D01*
X1431950D01*
G01X1429470Y123708D02*
X1425750D01*
G01X1437840Y117250D02*
Y129750D01*
X1440940D01*
X1442180Y129125D01*
X1443110Y128292D01*
X1443885Y127042D01*
X1444505Y125583D01*
X1444660Y123500D01*
X1444505Y121417D01*
X1443885Y119958D01*
X1443110Y118708D01*
X1442180Y117875D01*
X1440940Y117250D01*
X1437840D01*
G01X1353050Y-1486000D02*
Y-1470400D01*
X1350710Y-1473520D01*
G01Y-1486000D02*
X1355390D01*
G01X1351350Y17250D02*
Y29750D01*
X1355070D01*
X1356310Y29125D01*
X1357240Y27667D01*
X1357550Y26000D01*
X1357240Y24333D01*
X1356465Y23083D01*
X1355070Y22458D01*
X1351350D01*
G01X1363750Y29750D02*
Y17250D01*
X1369950D01*
G01X1375375D02*
X1379250Y29750D01*
X1383125Y17250D01*
G01X1381730Y21625D02*
X1376770D01*
G01X1391650Y29750D02*
Y17250D01*
G01X1388085Y29750D02*
X1395215D01*
G01X1407150Y17250D02*
X1400950D01*
Y29750D01*
X1407150D01*
G01X1404670Y23708D02*
X1400950D01*
G01X1413040Y17250D02*
Y29750D01*
X1416140D01*
X1417380Y29125D01*
X1418310Y28292D01*
X1419085Y27042D01*
X1419705Y25583D01*
X1419860Y23500D01*
X1419705Y21417D01*
X1419085Y19958D01*
X1418310Y18708D01*
X1417380Y17875D01*
X1416140Y17250D01*
X1413040D01*
G01X1351350Y42250D02*
Y54750D01*
X1355070D01*
X1356310Y54125D01*
X1357240Y52667D01*
X1357550Y51000D01*
X1357240Y49333D01*
X1356465Y48083D01*
X1355070Y47458D01*
X1351350D01*
G01X1363750Y54750D02*
Y42250D01*
X1369950D01*
G01X1375375D02*
X1379250Y54750D01*
X1383125Y42250D01*
G01X1381730Y46625D02*
X1376770D01*
G01X1391650Y54750D02*
Y42250D01*
G01X1388085Y54750D02*
X1395215D01*
G01X1407150Y42250D02*
X1400950D01*
Y54750D01*
X1407150D01*
G01X1404670Y48708D02*
X1400950D01*
G01X1413040Y42250D02*
Y54750D01*
X1416140D01*
X1417380Y54125D01*
X1418310Y53292D01*
X1419085Y52042D01*
X1419705Y50583D01*
X1419860Y48500D01*
X1419705Y46417D01*
X1419085Y44958D01*
X1418310Y43708D01*
X1417380Y42875D01*
X1416140Y42250D01*
X1413040D01*
G01X1351350Y142250D02*
Y154750D01*
X1355070D01*
X1356310Y154125D01*
X1357240Y152667D01*
X1357550Y151000D01*
X1357240Y149333D01*
X1356465Y148083D01*
X1355070Y147458D01*
X1351350D01*
G01X1363750Y154750D02*
Y142250D01*
X1369950D01*
G01X1375375D02*
X1379250Y154750D01*
X1383125Y142250D01*
G01X1381730Y146625D02*
X1376770D01*
G01X1391650Y154750D02*
Y142250D01*
G01X1388085Y154750D02*
X1395215D01*
G01X1407150Y142250D02*
X1400950D01*
Y154750D01*
X1407150D01*
G01X1404670Y148708D02*
X1400950D01*
G01X1413040Y142250D02*
Y154750D01*
X1416140D01*
X1417380Y154125D01*
X1418310Y153292D01*
X1419085Y152042D01*
X1419705Y150583D01*
X1419860Y148500D01*
X1419705Y146417D01*
X1419085Y144958D01*
X1418310Y143708D01*
X1417380Y142875D01*
X1416140Y142250D01*
X1413040D01*
G01X1351350Y167250D02*
Y179750D01*
X1355070D01*
X1356310Y179125D01*
X1357240Y177667D01*
X1357550Y176000D01*
X1357240Y174333D01*
X1356465Y173083D01*
X1355070Y172458D01*
X1351350D01*
G01X1363750Y179750D02*
Y167250D01*
X1369950D01*
G01X1375375D02*
X1379250Y179750D01*
X1383125Y167250D01*
G01X1381730Y171625D02*
X1376770D01*
G01X1391650Y179750D02*
Y167250D01*
G01X1388085Y179750D02*
X1395215D01*
G01X1407150Y167250D02*
X1400950D01*
Y179750D01*
X1407150D01*
G01X1404670Y173708D02*
X1400950D01*
G01X1413040Y167250D02*
Y179750D01*
X1416140D01*
X1417380Y179125D01*
X1418310Y178292D01*
X1419085Y177042D01*
X1419705Y175583D01*
X1419860Y173500D01*
X1419705Y171417D01*
X1419085Y169958D01*
X1418310Y168708D01*
X1417380Y167875D01*
X1416140Y167250D01*
X1413040D01*
G01X1351350Y192250D02*
Y204750D01*
X1355070D01*
X1356310Y204125D01*
X1357240Y202667D01*
X1357550Y201000D01*
X1357240Y199333D01*
X1356465Y198083D01*
X1355070Y197458D01*
X1351350D01*
G01X1363750Y204750D02*
Y192250D01*
X1369950D01*
G01X1375375D02*
X1379250Y204750D01*
X1383125Y192250D01*
G01X1381730Y196625D02*
X1376770D01*
G01X1391650Y204750D02*
Y192250D01*
G01X1388085Y204750D02*
X1395215D01*
G01X1407150Y192250D02*
X1400950D01*
Y204750D01*
X1407150D01*
G01X1404670Y198708D02*
X1400950D01*
G01X1413040Y192250D02*
Y204750D01*
X1416140D01*
X1417380Y204125D01*
X1418310Y203292D01*
X1419085Y202042D01*
X1419705Y200583D01*
X1419860Y198500D01*
X1419705Y196417D01*
X1419085Y194958D01*
X1418310Y193708D01*
X1417380Y192875D01*
X1416140Y192250D01*
X1413040D01*
G01X1351350Y217250D02*
Y229750D01*
X1355070D01*
X1356310Y229125D01*
X1357240Y227667D01*
X1357550Y226000D01*
X1357240Y224333D01*
X1356465Y223083D01*
X1355070Y222458D01*
X1351350D01*
G01X1363750Y229750D02*
Y217250D01*
X1369950D01*
G01X1375375D02*
X1379250Y229750D01*
X1383125Y217250D01*
G01X1381730Y221625D02*
X1376770D01*
G01X1391650Y229750D02*
Y217250D01*
G01X1388085Y229750D02*
X1395215D01*
G01X1407150Y217250D02*
X1400950D01*
Y229750D01*
X1407150D01*
G01X1404670Y223708D02*
X1400950D01*
G01X1413040Y217250D02*
Y229750D01*
X1416140D01*
X1417380Y229125D01*
X1418310Y228292D01*
X1419085Y227042D01*
X1419705Y225583D01*
X1419860Y223500D01*
X1419705Y221417D01*
X1419085Y219958D01*
X1418310Y218708D01*
X1417380Y217875D01*
X1416140Y217250D01*
X1413040D01*
G01X1351350Y242250D02*
Y254750D01*
X1355070D01*
X1356310Y254125D01*
X1357240Y252667D01*
X1357550Y251000D01*
X1357240Y249333D01*
X1356465Y248083D01*
X1355070Y247458D01*
X1351350D01*
G01X1363750Y254750D02*
Y242250D01*
X1369950D01*
G01X1375375D02*
X1379250Y254750D01*
X1383125Y242250D01*
G01X1381730Y246625D02*
X1376770D01*
G01X1391650Y254750D02*
Y242250D01*
G01X1388085Y254750D02*
X1395215D01*
G01X1407150Y242250D02*
X1400950D01*
Y254750D01*
X1407150D01*
G01X1404670Y248708D02*
X1400950D01*
G01X1413040Y242250D02*
Y254750D01*
X1416140D01*
X1417380Y254125D01*
X1418310Y253292D01*
X1419085Y252042D01*
X1419705Y250583D01*
X1419860Y248500D01*
X1419705Y246417D01*
X1419085Y244958D01*
X1418310Y243708D01*
X1417380Y242875D01*
X1416140Y242250D01*
X1413040D01*
G01X1351350Y267250D02*
Y279750D01*
X1355070D01*
X1356310Y279125D01*
X1357240Y277667D01*
X1357550Y276000D01*
X1357240Y274333D01*
X1356465Y273083D01*
X1355070Y272458D01*
X1351350D01*
G01X1363750Y279750D02*
Y267250D01*
X1369950D01*
G01X1375375D02*
X1379250Y279750D01*
X1383125Y267250D01*
G01X1381730Y271625D02*
X1376770D01*
G01X1391650Y279750D02*
Y267250D01*
G01X1388085Y279750D02*
X1395215D01*
G01X1407150Y267250D02*
X1400950D01*
Y279750D01*
X1407150D01*
G01X1404670Y273708D02*
X1400950D01*
G01X1413040Y267250D02*
Y279750D01*
X1416140D01*
X1417380Y279125D01*
X1418310Y278292D01*
X1419085Y277042D01*
X1419705Y275583D01*
X1419860Y273500D01*
X1419705Y271417D01*
X1419085Y269958D01*
X1418310Y268708D01*
X1417380Y267875D01*
X1416140Y267250D01*
X1413040D01*
G01X1351350Y292250D02*
Y304750D01*
X1355070D01*
X1356310Y304125D01*
X1357240Y302667D01*
X1357550Y301000D01*
X1357240Y299333D01*
X1356465Y298083D01*
X1355070Y297458D01*
X1351350D01*
G01X1363750Y304750D02*
Y292250D01*
X1369950D01*
G01X1375375D02*
X1379250Y304750D01*
X1383125Y292250D01*
G01X1381730Y296625D02*
X1376770D01*
G01X1391650Y304750D02*
Y292250D01*
G01X1388085Y304750D02*
X1395215D01*
G01X1407150Y292250D02*
X1400950D01*
Y304750D01*
X1407150D01*
G01X1404670Y298708D02*
X1400950D01*
G01X1413040Y292250D02*
Y304750D01*
X1416140D01*
X1417380Y304125D01*
X1418310Y303292D01*
X1419085Y302042D01*
X1419705Y300583D01*
X1419860Y298500D01*
X1419705Y296417D01*
X1419085Y294958D01*
X1418310Y293708D01*
X1417380Y292875D01*
X1416140Y292250D01*
X1413040D01*
G01X1351350Y317250D02*
Y329750D01*
X1355070D01*
X1356310Y329125D01*
X1357240Y327667D01*
X1357550Y326000D01*
X1357240Y324333D01*
X1356465Y323083D01*
X1355070Y322458D01*
X1351350D01*
G01X1363750Y329750D02*
Y317250D01*
X1369950D01*
G01X1375375D02*
X1379250Y329750D01*
X1383125Y317250D01*
G01X1381730Y321625D02*
X1376770D01*
G01X1391650Y329750D02*
Y317250D01*
G01X1388085Y329750D02*
X1395215D01*
G01X1407150Y317250D02*
X1400950D01*
Y329750D01*
X1407150D01*
G01X1404670Y323708D02*
X1400950D01*
G01X1413040Y317250D02*
Y329750D01*
X1416140D01*
X1417380Y329125D01*
X1418310Y328292D01*
X1419085Y327042D01*
X1419705Y325583D01*
X1419860Y323500D01*
X1419705Y321417D01*
X1419085Y319958D01*
X1418310Y318708D01*
X1417380Y317875D01*
X1416140Y317250D01*
X1413040D01*
G01X1351350Y342250D02*
Y354750D01*
X1355070D01*
X1356310Y354125D01*
X1357240Y352667D01*
X1357550Y351000D01*
X1357240Y349333D01*
X1356465Y348083D01*
X1355070Y347458D01*
X1351350D01*
G01X1363750Y354750D02*
Y342250D01*
X1369950D01*
G01X1375375D02*
X1379250Y354750D01*
X1383125Y342250D01*
G01X1381730Y346625D02*
X1376770D01*
G01X1391650Y354750D02*
Y342250D01*
G01X1388085Y354750D02*
X1395215D01*
G01X1407150Y342250D02*
X1400950D01*
Y354750D01*
X1407150D01*
G01X1404670Y348708D02*
X1400950D01*
G01X1413040Y342250D02*
Y354750D01*
X1416140D01*
X1417380Y354125D01*
X1418310Y353292D01*
X1419085Y352042D01*
X1419705Y350583D01*
X1419860Y348500D01*
X1419705Y346417D01*
X1419085Y344958D01*
X1418310Y343708D01*
X1417380Y342875D01*
X1416140Y342250D01*
X1413040D01*
G01X1351350Y367250D02*
Y379750D01*
X1355070D01*
X1356310Y379125D01*
X1357240Y377667D01*
X1357550Y376000D01*
X1357240Y374333D01*
X1356465Y373083D01*
X1355070Y372458D01*
X1351350D01*
G01X1363750Y379750D02*
Y367250D01*
X1369950D01*
G01X1375375D02*
X1379250Y379750D01*
X1383125Y367250D01*
G01X1381730Y371625D02*
X1376770D01*
G01X1391650Y379750D02*
Y367250D01*
G01X1388085Y379750D02*
X1395215D01*
G01X1407150Y367250D02*
X1400950D01*
Y379750D01*
X1407150D01*
G01X1404670Y373708D02*
X1400950D01*
G01X1413040Y367250D02*
Y379750D01*
X1416140D01*
X1417380Y379125D01*
X1418310Y378292D01*
X1419085Y377042D01*
X1419705Y375583D01*
X1419860Y373500D01*
X1419705Y371417D01*
X1419085Y369958D01*
X1418310Y368708D01*
X1417380Y367875D01*
X1416140Y367250D01*
X1413040D01*
G01X1351350Y392250D02*
Y404750D01*
X1355070D01*
X1356310Y404125D01*
X1357240Y402667D01*
X1357550Y401000D01*
X1357240Y399333D01*
X1356465Y398083D01*
X1355070Y397458D01*
X1351350D01*
G01X1363750Y404750D02*
Y392250D01*
X1369950D01*
G01X1375375D02*
X1379250Y404750D01*
X1383125Y392250D01*
G01X1381730Y396625D02*
X1376770D01*
G01X1391650Y404750D02*
Y392250D01*
G01X1388085Y404750D02*
X1395215D01*
G01X1407150Y392250D02*
X1400950D01*
Y404750D01*
X1407150D01*
G01X1404670Y398708D02*
X1400950D01*
G01X1413040Y392250D02*
Y404750D01*
X1416140D01*
X1417380Y404125D01*
X1418310Y403292D01*
X1419085Y402042D01*
X1419705Y400583D01*
X1419860Y398500D01*
X1419705Y396417D01*
X1419085Y394958D01*
X1418310Y393708D01*
X1417380Y392875D01*
X1416140Y392250D01*
X1413040D01*
G01X1458450Y-1471500D02*
Y-1455900D01*
X1463325D01*
X1464885Y-1456680D01*
X1465860Y-1457720D01*
X1466250Y-1459800D01*
X1465860Y-1461880D01*
X1464690Y-1463180D01*
X1463325Y-1463960D01*
X1458450D01*
G01X1463325D02*
X1466250Y-1471500D01*
G01X1482590D02*
Y-1455900D01*
X1475375Y-1467080D01*
X1485125D01*
G01X1498150Y-1455900D02*
X1496590Y-1456420D01*
X1495420Y-1457720D01*
X1494640Y-1459280D01*
X1494055Y-1461360D01*
X1493860Y-1463700D01*
X1494055Y-1466040D01*
X1494640Y-1468120D01*
X1495420Y-1469680D01*
X1496590Y-1470980D01*
X1498150Y-1471500D01*
X1499710Y-1470980D01*
X1500880Y-1469680D01*
X1501660Y-1468120D01*
X1502245Y-1466040D01*
X1502440Y-1463700D01*
X1502245Y-1461360D01*
X1501660Y-1459280D01*
X1500880Y-1457720D01*
X1499710Y-1456420D01*
X1498150Y-1455900D01*
G01X1516050D02*
X1514490Y-1456420D01*
X1513320Y-1457720D01*
X1512540Y-1459280D01*
X1511955Y-1461360D01*
X1511760Y-1463700D01*
X1511955Y-1466040D01*
X1512540Y-1468120D01*
X1513320Y-1469680D01*
X1514490Y-1470980D01*
X1516050Y-1471500D01*
X1517610Y-1470980D01*
X1518780Y-1469680D01*
X1519560Y-1468120D01*
X1520145Y-1466040D01*
X1520340Y-1463700D01*
X1520145Y-1461360D01*
X1519560Y-1459280D01*
X1518780Y-1457720D01*
X1517610Y-1456420D01*
X1516050Y-1455900D01*
G01X1530245Y-1465000D02*
X1531610Y-1463180D01*
X1532780Y-1462140D01*
X1534340Y-1461620D01*
X1535705Y-1462140D01*
X1536680Y-1463180D01*
X1537460Y-1464740D01*
X1537655Y-1466560D01*
X1537460Y-1468120D01*
X1536680Y-1469680D01*
X1535510Y-1470980D01*
X1534145Y-1471500D01*
X1532585Y-1470980D01*
X1531220Y-1469420D01*
X1530440Y-1467080D01*
X1530245Y-1464480D01*
X1530635Y-1461100D01*
X1531220Y-1459280D01*
X1532195Y-1457460D01*
X1533560Y-1456160D01*
X1534925Y-1455900D01*
X1536290Y-1456420D01*
X1537265Y-1457720D01*
G01X1549315Y-1466300D02*
X1554385D01*
G01X1571310Y-1463180D02*
X1572090Y-1462400D01*
X1572675Y-1461100D01*
X1573065Y-1459280D01*
X1572675Y-1457720D01*
X1571895Y-1456680D01*
X1570530Y-1455900D01*
X1565265D01*
Y-1471500D01*
X1571700D01*
X1573065Y-1470460D01*
X1573845Y-1468900D01*
X1574235Y-1467080D01*
X1573845Y-1465260D01*
X1572675Y-1463700D01*
X1571310Y-1463180D01*
X1565265D01*
G01X1587650Y-1455900D02*
X1586090Y-1456420D01*
X1584920Y-1457720D01*
X1584140Y-1459280D01*
X1583555Y-1461360D01*
X1583360Y-1463700D01*
X1583555Y-1466040D01*
X1584140Y-1468120D01*
X1584920Y-1469680D01*
X1586090Y-1470980D01*
X1587650Y-1471500D01*
X1589210Y-1470980D01*
X1590380Y-1469680D01*
X1591160Y-1468120D01*
X1591745Y-1466040D01*
X1591940Y-1463700D01*
X1591745Y-1461360D01*
X1591160Y-1459280D01*
X1590380Y-1457720D01*
X1589210Y-1456420D01*
X1587650Y-1455900D01*
G01X1605550D02*
X1603990Y-1456420D01*
X1602820Y-1457720D01*
X1602040Y-1459280D01*
X1601455Y-1461360D01*
X1601260Y-1463700D01*
X1601455Y-1466040D01*
X1602040Y-1468120D01*
X1602820Y-1469680D01*
X1603990Y-1470980D01*
X1605550Y-1471500D01*
X1607110Y-1470980D01*
X1608280Y-1469680D01*
X1609060Y-1468120D01*
X1609645Y-1466040D01*
X1609840Y-1463700D01*
X1609645Y-1461360D01*
X1609060Y-1459280D01*
X1608280Y-1457720D01*
X1607110Y-1456420D01*
X1605550Y-1455900D01*
G01X1623450D02*
X1621890Y-1456420D01*
X1620720Y-1457720D01*
X1619940Y-1459280D01*
X1619355Y-1461360D01*
X1619160Y-1463700D01*
X1619355Y-1466040D01*
X1619940Y-1468120D01*
X1620720Y-1469680D01*
X1621890Y-1470980D01*
X1623450Y-1471500D01*
X1625010Y-1470980D01*
X1626180Y-1469680D01*
X1626960Y-1468120D01*
X1627545Y-1466040D01*
X1627740Y-1463700D01*
X1627545Y-1461360D01*
X1626960Y-1459280D01*
X1626180Y-1457720D01*
X1625010Y-1456420D01*
X1623450Y-1455900D01*
G01X1641350Y-1471500D02*
Y-1455900D01*
X1639010Y-1459020D01*
G01Y-1471500D02*
X1643690D01*
G01X1656715Y-1466300D02*
X1661785D01*
G01X1677150Y-1455900D02*
X1675590Y-1456420D01*
X1674420Y-1457720D01*
X1673640Y-1459280D01*
X1673055Y-1461360D01*
X1672860Y-1463700D01*
X1673055Y-1466040D01*
X1673640Y-1468120D01*
X1674420Y-1469680D01*
X1675590Y-1470980D01*
X1677150Y-1471500D01*
X1678710Y-1470980D01*
X1679880Y-1469680D01*
X1680660Y-1468120D01*
X1681245Y-1466040D01*
X1681440Y-1463700D01*
X1681245Y-1461360D01*
X1680660Y-1459280D01*
X1679880Y-1457720D01*
X1678710Y-1456420D01*
X1677150Y-1455900D01*
G01X1691345Y-1458500D02*
X1692515Y-1456940D01*
X1693880Y-1456160D01*
X1695440Y-1455900D01*
X1697390Y-1456420D01*
X1698755Y-1457720D01*
X1699145Y-1459280D01*
X1698950Y-1460840D01*
X1698170Y-1462140D01*
X1694270Y-1464740D01*
X1692515Y-1466560D01*
X1691345Y-1469160D01*
X1690955Y-1471500D01*
X1699145D01*
G01X1449000Y411000D02*
Y11000D01*
G01X1460250Y-1564500D02*
Y-1544500D01*
X1469750D01*
G01X1466250Y-1554166D02*
X1460250D01*
G01X1478750Y-1564500D02*
X1485000Y-1544500D01*
X1491250Y-1564500D01*
G01X1489000Y-1557500D02*
X1481000D01*
G01X1507000Y-1553833D02*
X1508000Y-1552833D01*
X1508750Y-1551167D01*
X1509250Y-1548833D01*
X1508750Y-1546833D01*
X1507750Y-1545500D01*
X1506000Y-1544500D01*
X1499250D01*
Y-1564500D01*
X1507500D01*
X1509250Y-1563167D01*
X1510250Y-1561167D01*
X1510750Y-1558833D01*
X1510250Y-1556500D01*
X1508750Y-1554500D01*
X1507000Y-1553833D01*
X1499250D01*
G01X1520000Y-1564500D02*
Y-1544500D01*
X1526250D01*
X1528250Y-1545500D01*
X1529500Y-1546833D01*
X1530000Y-1549500D01*
X1529500Y-1552167D01*
X1528000Y-1553833D01*
X1526250Y-1554834D01*
X1520000D01*
G01X1526250D02*
X1530000Y-1564500D01*
G01X1542000Y-1544500D02*
X1548000D01*
G01X1545000D02*
Y-1564500D01*
G01X1542000D02*
X1548000D01*
G01X1570500Y-1546167D02*
X1569000Y-1545167D01*
X1567250Y-1544500D01*
X1565250D01*
X1563000Y-1545500D01*
X1561250Y-1547167D01*
X1560000Y-1549167D01*
X1559000Y-1552500D01*
X1558750Y-1555500D01*
X1559250Y-1558500D01*
X1560000Y-1560500D01*
X1561500Y-1562500D01*
X1563250Y-1563833D01*
X1565000Y-1564500D01*
X1566750D01*
X1568500Y-1563833D01*
X1570000Y-1562834D01*
X1571250Y-1561501D01*
G01X1578750Y-1564500D02*
X1585000Y-1544500D01*
X1591250Y-1564500D01*
G01X1589000Y-1557500D02*
X1581000D01*
G01X1605000Y-1544500D02*
Y-1564500D01*
G01X1599250Y-1544500D02*
X1610750D01*
G01X1622000D02*
X1628000D01*
G01X1625000D02*
Y-1564500D01*
G01X1622000D02*
X1628000D01*
G01X1645000D02*
X1643000Y-1564167D01*
X1641250Y-1562834D01*
X1639750Y-1560834D01*
X1638750Y-1558500D01*
X1638250Y-1555833D01*
Y-1553167D01*
X1638750Y-1550500D01*
X1639750Y-1548166D01*
X1641250Y-1546167D01*
X1643000Y-1544833D01*
X1645000Y-1544500D01*
X1647000Y-1544833D01*
X1648750Y-1546167D01*
X1650250Y-1548166D01*
X1651250Y-1550500D01*
X1651750Y-1553167D01*
Y-1555833D01*
X1651250Y-1558500D01*
X1650250Y-1560834D01*
X1648750Y-1562834D01*
X1647000Y-1564167D01*
X1645000Y-1564500D01*
G01X1659250D02*
Y-1544500D01*
X1670750Y-1564500D01*
Y-1544500D01*
G01X1699500Y-1564500D02*
Y-1544500D01*
X1704500D01*
X1706500Y-1545500D01*
X1708000Y-1546833D01*
X1709250Y-1548833D01*
X1710250Y-1551167D01*
X1710500Y-1554500D01*
X1710250Y-1557834D01*
X1709250Y-1560167D01*
X1708000Y-1562167D01*
X1706500Y-1563500D01*
X1704500Y-1564500D01*
X1699500D01*
G01X1720000D02*
Y-1544500D01*
X1726250D01*
X1728250Y-1545500D01*
X1729500Y-1546833D01*
X1730000Y-1549500D01*
X1729500Y-1552167D01*
X1728000Y-1553833D01*
X1726250Y-1554834D01*
X1720000D01*
G01X1726250D02*
X1730000Y-1564500D01*
G01X1738750D02*
X1745000Y-1544500D01*
X1751250Y-1564500D01*
G01X1749000Y-1557500D02*
X1741000D01*
G01X1757500Y-1544500D02*
X1761000Y-1564500D01*
X1765000Y-1544500D01*
X1769000Y-1564500D01*
X1772500Y-1544500D01*
G01X1782000D02*
X1788000D01*
G01X1785000D02*
Y-1564500D01*
G01X1782000D02*
X1788000D01*
G01X1799250D02*
Y-1544500D01*
X1810750Y-1564500D01*
Y-1544500D01*
G01X1826500Y-1554500D02*
X1831500D01*
Y-1560500D01*
X1830000Y-1562500D01*
X1828250Y-1563833D01*
X1825750Y-1564500D01*
X1823250Y-1563833D01*
X1821500Y-1562500D01*
X1820000Y-1560500D01*
X1819000Y-1558167D01*
X1818500Y-1555500D01*
Y-1553167D01*
X1819000Y-1551167D01*
X1820000Y-1548833D01*
X1821500Y-1546833D01*
X1823000Y-1545500D01*
X1825000Y-1544500D01*
X1826750D01*
X1828750Y-1545167D01*
X1830250Y-1546500D01*
G01X1466205Y2667D02*
X1467135Y3916D01*
X1468220Y4542D01*
X1469460Y4750D01*
X1471010Y4333D01*
X1472095Y3292D01*
X1472405Y2042D01*
X1472250Y791D01*
X1471630Y-250D01*
X1468530Y-2333D01*
X1467135Y-3792D01*
X1466205Y-5875D01*
X1465895Y-7750D01*
X1472405D01*
G01X1478140Y-5875D02*
X1479070Y-6917D01*
X1480155Y-7542D01*
X1481550Y-7750D01*
X1482945Y-7333D01*
X1484030Y-6500D01*
X1484805Y-5042D01*
X1484960Y-3375D01*
X1484650Y-1708D01*
X1483875Y-667D01*
X1482790Y167D01*
X1481705Y375D01*
X1480620Y167D01*
X1479225Y-667D01*
X1479690Y4750D01*
X1483875D01*
G01X1491315Y-6292D02*
X1492400Y-7333D01*
X1493640Y-7750D01*
X1494880Y-7333D01*
X1495965Y-6084D01*
X1496740Y-4208D01*
X1497050Y-2333D01*
Y-42D01*
X1496740Y1833D01*
X1495965Y3500D01*
X1495035Y4333D01*
X1493950Y4750D01*
X1492710Y4333D01*
X1491780Y3500D01*
X1491160Y2250D01*
X1490850Y583D01*
X1491160Y-875D01*
X1491935Y-2333D01*
X1492865Y-3167D01*
X1493950Y-3375D01*
X1495190Y-2959D01*
X1496120Y-1917D01*
X1497050Y-42D01*
G01X1506350Y-7750D02*
Y4750D01*
X1504490Y2250D01*
G01Y-7750D02*
X1508210D01*
G01X1469150Y342250D02*
Y354750D01*
X1467290Y352250D01*
G01Y342250D02*
X1471010D01*
G01X1478140Y344750D02*
X1479070Y343291D01*
X1480310Y342458D01*
X1481705Y342250D01*
X1482945Y342458D01*
X1484185Y343500D01*
X1484960Y344750D01*
X1485115Y346000D01*
X1484805Y347458D01*
X1483720Y348500D01*
X1482635Y348917D01*
X1481240D01*
G01X1482635D02*
X1483565Y349542D01*
X1484340Y350583D01*
X1484650Y351833D01*
X1484340Y353083D01*
X1483565Y354125D01*
X1482170Y354750D01*
X1480775Y354542D01*
X1479380Y353708D01*
G01X1493950Y354750D02*
X1492710Y354333D01*
X1491780Y353292D01*
X1491160Y352042D01*
X1490695Y350375D01*
X1490540Y348500D01*
X1490695Y346625D01*
X1491160Y344958D01*
X1491780Y343708D01*
X1492710Y342667D01*
X1493950Y342250D01*
X1495190Y342667D01*
X1496120Y343708D01*
X1496740Y344958D01*
X1497205Y346625D01*
X1497360Y348500D01*
X1497205Y350375D01*
X1496740Y352042D01*
X1496120Y353292D01*
X1495190Y354333D01*
X1493950Y354750D01*
G01X1506040Y342250D02*
X1506350Y344958D01*
X1506815Y347250D01*
X1507435Y349333D01*
X1508210Y351625D01*
X1509450Y354750D01*
X1503250D01*
G01X1469150Y367250D02*
Y379750D01*
X1467290Y377250D01*
G01Y367250D02*
X1471010D01*
G01X1481550D02*
Y379750D01*
X1479690Y377250D01*
G01Y367250D02*
X1483410D01*
G01X1493950D02*
X1495035Y367458D01*
X1496275Y368083D01*
X1497050Y369125D01*
X1497360Y370583D01*
X1497050Y372041D01*
X1496120Y373292D01*
X1494725Y373917D01*
X1493175D01*
X1492245Y374333D01*
X1491470Y375375D01*
X1491160Y376833D01*
X1491625Y378292D01*
X1492710Y379333D01*
X1493950Y379750D01*
X1495190Y379333D01*
X1496275Y378292D01*
X1496740Y376833D01*
X1496430Y375375D01*
X1495655Y374333D01*
X1494725Y373917D01*
X1493175D01*
X1491780Y373292D01*
X1490850Y372041D01*
X1490540Y370583D01*
X1490850Y369125D01*
X1491625Y368083D01*
X1492865Y367458D01*
X1493950Y367250D01*
G01X1503405Y377667D02*
X1504335Y378916D01*
X1505420Y379542D01*
X1506660Y379750D01*
X1508210Y379333D01*
X1509295Y378292D01*
X1509605Y377042D01*
X1509450Y375791D01*
X1508830Y374750D01*
X1505730Y372667D01*
X1504335Y371208D01*
X1503405Y369125D01*
X1503095Y367250D01*
X1509605D01*
G01X1475350Y392250D02*
X1474110Y392458D01*
X1473025Y393291D01*
X1472095Y394542D01*
X1471475Y396000D01*
X1471165Y397667D01*
Y399333D01*
X1471475Y401000D01*
X1472095Y402458D01*
X1473025Y403708D01*
X1474110Y404542D01*
X1475350Y404750D01*
X1476590Y404542D01*
X1477675Y403708D01*
X1478605Y402458D01*
X1479225Y401000D01*
X1479535Y399333D01*
Y397667D01*
X1479225Y396000D01*
X1478605Y394542D01*
X1477675Y393291D01*
X1476590Y392458D01*
X1475350Y392250D01*
G01X1476590Y395583D02*
X1478450Y392250D01*
G01X1487750Y404750D02*
Y392250D01*
G01X1484185Y404750D02*
X1491315D01*
G01X1500150Y392250D02*
Y397875D01*
X1497050Y404750D01*
G01X1503250D02*
X1500150Y397875D01*
G01X1489610Y17250D02*
Y29750D01*
X1483875Y20792D01*
X1491625D01*
G01X1484805Y52667D02*
X1485735Y53916D01*
X1486820Y54542D01*
X1488060Y54750D01*
X1489610Y54333D01*
X1490695Y53292D01*
X1491005Y52042D01*
X1490850Y50791D01*
X1490230Y49750D01*
X1487130Y47667D01*
X1485735Y46208D01*
X1484805Y44125D01*
X1484495Y42250D01*
X1491005D01*
G01X1489610Y67250D02*
Y79750D01*
X1483875Y70792D01*
X1491625D01*
G01X1484805Y102667D02*
X1485735Y103916D01*
X1486820Y104542D01*
X1488060Y104750D01*
X1489610Y104333D01*
X1490695Y103292D01*
X1491005Y102042D01*
X1490850Y100791D01*
X1490230Y99750D01*
X1487130Y97667D01*
X1485735Y96208D01*
X1484805Y94125D01*
X1484495Y92250D01*
X1491005D01*
G01X1489610Y117250D02*
Y129750D01*
X1483875Y120792D01*
X1491625D01*
G01X1489610Y142250D02*
Y154750D01*
X1483875Y145792D01*
X1491625D01*
G01X1487750Y167250D02*
X1488835Y167458D01*
X1490075Y168083D01*
X1490850Y169125D01*
X1491160Y170583D01*
X1490850Y172041D01*
X1489920Y173292D01*
X1488525Y173917D01*
X1486975D01*
X1486045Y174333D01*
X1485270Y175375D01*
X1484960Y176833D01*
X1485425Y178292D01*
X1486510Y179333D01*
X1487750Y179750D01*
X1488990Y179333D01*
X1490075Y178292D01*
X1490540Y176833D01*
X1490230Y175375D01*
X1489455Y174333D01*
X1488525Y173917D01*
X1486975D01*
X1485580Y173292D01*
X1484650Y172041D01*
X1484340Y170583D01*
X1484650Y169125D01*
X1485425Y168083D01*
X1486665Y167458D01*
X1487750Y167250D01*
G01X1484805Y197458D02*
X1485890Y198917D01*
X1486820Y199750D01*
X1488060Y200167D01*
X1489145Y199750D01*
X1489920Y198917D01*
X1490540Y197667D01*
X1490695Y196208D01*
X1490540Y194958D01*
X1489920Y193708D01*
X1488990Y192667D01*
X1487905Y192250D01*
X1486665Y192667D01*
X1485580Y193916D01*
X1484960Y195792D01*
X1484805Y197875D01*
X1485115Y200583D01*
X1485580Y202042D01*
X1486355Y203500D01*
X1487440Y204542D01*
X1488525Y204750D01*
X1489610Y204333D01*
X1490385Y203292D01*
G01X1481550Y217250D02*
Y229750D01*
X1479690Y227250D01*
G01Y217250D02*
X1483410D01*
G01X1491005Y222458D02*
X1492090Y223917D01*
X1493020Y224750D01*
X1494260Y225167D01*
X1495345Y224750D01*
X1496120Y223917D01*
X1496740Y222667D01*
X1496895Y221208D01*
X1496740Y219958D01*
X1496120Y218708D01*
X1495190Y217667D01*
X1494105Y217250D01*
X1492865Y217667D01*
X1491780Y218916D01*
X1491160Y220792D01*
X1491005Y222875D01*
X1491315Y225583D01*
X1491780Y227042D01*
X1492555Y228500D01*
X1493640Y229542D01*
X1494725Y229750D01*
X1495810Y229333D01*
X1496585Y228292D01*
G01X1489610Y242250D02*
Y254750D01*
X1483875Y245792D01*
X1491625D01*
G01X1484805Y277667D02*
X1485735Y278916D01*
X1486820Y279542D01*
X1488060Y279750D01*
X1489610Y279333D01*
X1490695Y278292D01*
X1491005Y277042D01*
X1490850Y275791D01*
X1490230Y274750D01*
X1487130Y272667D01*
X1485735Y271208D01*
X1484805Y269125D01*
X1484495Y267250D01*
X1491005D01*
G01X1481550Y292250D02*
Y304750D01*
X1479690Y302250D01*
G01Y292250D02*
X1483410D01*
G01X1495810D02*
Y304750D01*
X1490075Y295792D01*
X1497825D01*
G01X1478140Y319750D02*
X1479070Y318291D01*
X1480310Y317458D01*
X1481705Y317250D01*
X1482945Y317458D01*
X1484185Y318500D01*
X1484960Y319750D01*
X1485115Y321000D01*
X1484805Y322458D01*
X1483720Y323500D01*
X1482635Y323917D01*
X1481240D01*
G01X1482635D02*
X1483565Y324542D01*
X1484340Y325583D01*
X1484650Y326833D01*
X1484340Y328083D01*
X1483565Y329125D01*
X1482170Y329750D01*
X1480775Y329542D01*
X1479380Y328708D01*
G01X1491005Y327667D02*
X1491935Y328916D01*
X1493020Y329542D01*
X1494260Y329750D01*
X1495810Y329333D01*
X1496895Y328292D01*
X1497205Y327042D01*
X1497050Y325791D01*
X1496430Y324750D01*
X1493330Y322667D01*
X1491935Y321208D01*
X1491005Y319125D01*
X1490695Y317250D01*
X1497205D01*
G01X1553500Y-1504000D02*
Y-1524000D01*
G01X1547750Y-1504000D02*
X1559250D01*
G01X1570500D02*
X1576500D01*
G01X1573500D02*
Y-1524000D01*
G01X1570500D02*
X1576500D01*
G01X1587000D02*
Y-1504000D01*
X1593500Y-1520667D01*
X1600000Y-1504000D01*
Y-1524000D01*
G01X1610500Y-1504000D02*
X1616500D01*
G01X1613500D02*
Y-1524000D01*
G01X1610500D02*
X1616500D01*
G01X1627750D02*
Y-1504000D01*
X1639250Y-1524000D01*
Y-1504000D01*
G01X1655000Y-1514000D02*
X1660000D01*
Y-1520000D01*
X1658500Y-1522000D01*
X1656750Y-1523333D01*
X1654250Y-1524000D01*
X1651750Y-1523333D01*
X1650000Y-1522000D01*
X1648500Y-1520000D01*
X1647500Y-1517667D01*
X1647000Y-1515000D01*
Y-1512667D01*
X1647500Y-1510667D01*
X1648500Y-1508333D01*
X1650000Y-1506333D01*
X1651500Y-1505000D01*
X1653500Y-1504000D01*
X1655250D01*
X1657250Y-1504667D01*
X1658750Y-1506000D01*
G01X1699000Y-1505667D02*
X1697500Y-1504667D01*
X1695750Y-1504000D01*
X1693750D01*
X1691500Y-1505000D01*
X1689750Y-1506667D01*
X1688500Y-1508667D01*
X1687500Y-1512000D01*
X1687250Y-1515000D01*
X1687750Y-1518000D01*
X1688500Y-1520000D01*
X1690000Y-1522000D01*
X1691750Y-1523333D01*
X1693500Y-1524000D01*
X1695250D01*
X1697000Y-1523333D01*
X1698500Y-1522334D01*
X1699750Y-1521001D01*
G01X1707250Y-1524000D02*
X1713500Y-1504000D01*
X1719750Y-1524000D01*
G01X1717500Y-1517000D02*
X1709500D01*
G01X1728500Y-1524000D02*
Y-1504000D01*
X1734750D01*
X1736750Y-1505000D01*
X1738000Y-1506333D01*
X1738500Y-1509000D01*
X1738000Y-1511667D01*
X1736500Y-1513333D01*
X1734750Y-1514334D01*
X1728500D01*
G01X1734750D02*
X1738500Y-1524000D01*
G01X1748000D02*
Y-1504000D01*
X1753000D01*
X1755000Y-1505000D01*
X1756500Y-1506333D01*
X1757750Y-1508333D01*
X1758750Y-1510667D01*
X1759000Y-1514000D01*
X1758750Y-1517334D01*
X1757750Y-1519667D01*
X1756500Y-1521667D01*
X1755000Y-1523000D01*
X1753000Y-1524000D01*
X1748000D01*
G01X1569650Y1507500D02*
Y1532500D01*
X1577525D01*
X1580045Y1531250D01*
X1581620Y1529583D01*
X1582250Y1526250D01*
X1581620Y1522916D01*
X1579730Y1520834D01*
X1577525Y1519583D01*
X1569650D01*
G01X1577525D02*
X1582250Y1507500D01*
G01X1604930D02*
Y1532500D01*
X1593275Y1514583D01*
X1609025D01*
G01X1626350Y1532500D02*
X1623830Y1531667D01*
X1621940Y1529583D01*
X1620680Y1527084D01*
X1619735Y1523750D01*
X1619420Y1520000D01*
X1619735Y1516250D01*
X1620680Y1512916D01*
X1621940Y1510416D01*
X1623830Y1508333D01*
X1626350Y1507500D01*
X1628870Y1508333D01*
X1630760Y1510416D01*
X1632020Y1512916D01*
X1632965Y1516250D01*
X1633280Y1520000D01*
X1632965Y1523750D01*
X1632020Y1527084D01*
X1630760Y1529583D01*
X1628870Y1531667D01*
X1626350Y1532500D01*
G01X1651550D02*
X1649030Y1531667D01*
X1647140Y1529583D01*
X1645880Y1527084D01*
X1644935Y1523750D01*
X1644620Y1520000D01*
X1644935Y1516250D01*
X1645880Y1512916D01*
X1647140Y1510416D01*
X1649030Y1508333D01*
X1651550Y1507500D01*
X1654070Y1508333D01*
X1655960Y1510416D01*
X1657220Y1512916D01*
X1658165Y1516250D01*
X1658480Y1520000D01*
X1658165Y1523750D01*
X1657220Y1527084D01*
X1655960Y1529583D01*
X1654070Y1531667D01*
X1651550Y1532500D01*
G01X1670765Y1517916D02*
X1672970Y1520834D01*
X1674860Y1522500D01*
X1677380Y1523333D01*
X1679585Y1522500D01*
X1681160Y1520834D01*
X1682420Y1518333D01*
X1682735Y1515417D01*
X1682420Y1512916D01*
X1681160Y1510416D01*
X1679270Y1508333D01*
X1677065Y1507500D01*
X1674545Y1508333D01*
X1672340Y1510833D01*
X1671080Y1514583D01*
X1670765Y1518750D01*
X1671395Y1524166D01*
X1672340Y1527084D01*
X1673915Y1530000D01*
X1676120Y1532083D01*
X1678325Y1532500D01*
X1680530Y1531667D01*
X1682105Y1529583D01*
G01X1697855Y1515833D02*
X1706045D01*
G01X1729670Y1520834D02*
X1730930Y1522083D01*
X1731875Y1524166D01*
X1732505Y1527084D01*
X1731875Y1529583D01*
X1730615Y1531250D01*
X1728410Y1532500D01*
X1719905D01*
Y1507500D01*
X1730300D01*
X1732505Y1509166D01*
X1733765Y1511667D01*
X1734395Y1514583D01*
X1733765Y1517499D01*
X1731875Y1520000D01*
X1729670Y1520834D01*
X1719905D01*
G01X1752350Y1532500D02*
X1749830Y1531667D01*
X1747940Y1529583D01*
X1746680Y1527084D01*
X1745735Y1523750D01*
X1745420Y1520000D01*
X1745735Y1516250D01*
X1746680Y1512916D01*
X1747940Y1510416D01*
X1749830Y1508333D01*
X1752350Y1507500D01*
X1754870Y1508333D01*
X1756760Y1510416D01*
X1758020Y1512916D01*
X1758965Y1516250D01*
X1759280Y1520000D01*
X1758965Y1523750D01*
X1758020Y1527084D01*
X1756760Y1529583D01*
X1754870Y1531667D01*
X1752350Y1532500D01*
G01X1777550D02*
X1775030Y1531667D01*
X1773140Y1529583D01*
X1771880Y1527084D01*
X1770935Y1523750D01*
X1770620Y1520000D01*
X1770935Y1516250D01*
X1771880Y1512916D01*
X1773140Y1510416D01*
X1775030Y1508333D01*
X1777550Y1507500D01*
X1780070Y1508333D01*
X1781960Y1510416D01*
X1783220Y1512916D01*
X1784165Y1516250D01*
X1784480Y1520000D01*
X1784165Y1523750D01*
X1783220Y1527084D01*
X1781960Y1529583D01*
X1780070Y1531667D01*
X1777550Y1532500D01*
G01X1802750D02*
X1800230Y1531667D01*
X1798340Y1529583D01*
X1797080Y1527084D01*
X1796135Y1523750D01*
X1795820Y1520000D01*
X1796135Y1516250D01*
X1797080Y1512916D01*
X1798340Y1510416D01*
X1800230Y1508333D01*
X1802750Y1507500D01*
X1805270Y1508333D01*
X1807160Y1510416D01*
X1808420Y1512916D01*
X1809365Y1516250D01*
X1809680Y1520000D01*
X1809365Y1523750D01*
X1808420Y1527084D01*
X1807160Y1529583D01*
X1805270Y1531667D01*
X1802750Y1532500D01*
G01X1827950Y1507500D02*
Y1532500D01*
X1824170Y1527500D01*
G01Y1507500D02*
X1831729D01*
G01X1849055Y1515833D02*
X1857245D01*
G01X1878350Y1532500D02*
X1875830Y1531667D01*
X1873940Y1529583D01*
X1872680Y1527084D01*
X1871735Y1523750D01*
X1871420Y1520000D01*
X1871735Y1516250D01*
X1872680Y1512916D01*
X1873940Y1510416D01*
X1875830Y1508333D01*
X1878350Y1507500D01*
X1880870Y1508333D01*
X1882760Y1510416D01*
X1884020Y1512916D01*
X1884965Y1516250D01*
X1885280Y1520000D01*
X1884965Y1523750D01*
X1884020Y1527084D01*
X1882760Y1529583D01*
X1880870Y1531667D01*
X1878350Y1532500D01*
G01X1897565Y1528333D02*
X1899455Y1530833D01*
X1901660Y1532083D01*
X1904180Y1532500D01*
X1907330Y1531667D01*
X1909535Y1529583D01*
X1910165Y1527084D01*
X1909850Y1524583D01*
X1908590Y1522500D01*
X1902290Y1518333D01*
X1899455Y1515417D01*
X1897565Y1511249D01*
X1896935Y1507500D01*
X1910165D01*
G01X1621500Y-1683333D02*
X1622500Y-1682333D01*
X1623250Y-1680667D01*
X1623750Y-1678333D01*
X1623250Y-1676333D01*
X1622250Y-1675000D01*
X1620500Y-1674000D01*
X1613750D01*
Y-1694000D01*
X1622000D01*
X1623750Y-1692667D01*
X1624750Y-1690667D01*
X1625250Y-1688333D01*
X1624750Y-1686000D01*
X1623250Y-1684000D01*
X1621500Y-1683333D01*
X1613750D01*
G01X1634250Y-1691334D02*
X1636250Y-1693000D01*
X1638500Y-1694000D01*
X1640500D01*
X1642500Y-1693000D01*
X1644000Y-1691334D01*
X1644750Y-1689000D01*
X1644250Y-1686667D01*
X1643000Y-1684667D01*
X1640750Y-1683333D01*
X1637750Y-1682667D01*
X1636000Y-1681334D01*
X1635250Y-1679000D01*
X1635750Y-1676667D01*
X1637000Y-1675000D01*
X1638750Y-1674000D01*
X1640500D01*
X1642250Y-1674667D01*
X1643750Y-1676333D01*
G01X1654250Y-1694000D02*
Y-1674000D01*
G01X1664750D02*
Y-1694000D01*
G01Y-1684000D02*
X1654250D01*
G01X1673250Y-1694000D02*
X1679500Y-1674000D01*
X1685750Y-1694000D01*
G01X1683500Y-1687000D02*
X1675500D01*
G01X1693750Y-1694000D02*
Y-1674000D01*
X1705250Y-1694000D01*
Y-1674000D01*
G01X1621500Y-1639833D02*
X1622500Y-1638833D01*
X1623250Y-1637167D01*
X1623750Y-1634833D01*
X1623250Y-1632833D01*
X1622250Y-1631500D01*
X1620500Y-1630500D01*
X1613750D01*
Y-1650500D01*
X1622000D01*
X1623750Y-1649167D01*
X1624750Y-1647167D01*
X1625250Y-1644833D01*
X1624750Y-1642500D01*
X1623250Y-1640500D01*
X1621500Y-1639833D01*
X1613750D01*
G01X1634250Y-1650500D02*
Y-1630500D01*
G01X1644750D02*
Y-1650500D01*
G01Y-1640500D02*
X1634250D01*
G01X1654000Y-1630500D02*
Y-1644833D01*
X1655000Y-1647834D01*
X1657000Y-1649833D01*
X1659500Y-1650500D01*
X1662000Y-1649833D01*
X1664000Y-1647834D01*
X1665000Y-1644833D01*
Y-1630500D01*
G01X1673000Y-1650500D02*
Y-1630500D01*
X1679500Y-1647167D01*
X1686000Y-1630500D01*
Y-1650500D01*
G01X1693250D02*
X1699500Y-1630500D01*
X1705750Y-1650500D01*
G01X1703500Y-1643500D02*
X1695500D01*
G01X1714500Y-1650500D02*
Y-1630500D01*
X1720750D01*
X1722750Y-1631500D01*
X1724000Y-1632833D01*
X1724500Y-1635500D01*
X1724000Y-1638167D01*
X1722500Y-1639833D01*
X1720750Y-1640834D01*
X1714500D01*
G01X1720750D02*
X1724500Y-1650500D01*
G01X1736500Y-1630500D02*
X1742500D01*
G01X1739500D02*
Y-1650500D01*
G01X1736500D02*
X1742500D01*
G01X1753750D02*
Y-1630500D01*
X1765250Y-1650500D01*
Y-1630500D01*
G01X1619500Y-1592167D02*
X1618000Y-1591167D01*
X1616250Y-1590500D01*
X1614250D01*
X1612000Y-1591500D01*
X1610250Y-1593167D01*
X1609000Y-1595167D01*
X1608000Y-1598500D01*
X1607750Y-1601500D01*
X1608250Y-1604500D01*
X1609000Y-1606500D01*
X1610500Y-1608500D01*
X1612250Y-1609833D01*
X1614000Y-1610500D01*
X1615750D01*
X1617500Y-1609833D01*
X1619000Y-1608834D01*
X1620250Y-1607501D01*
G01X1627750Y-1610500D02*
X1634000Y-1590500D01*
X1640250Y-1610500D01*
G01X1638000Y-1603500D02*
X1630000D01*
G01X1654000Y-1590500D02*
Y-1610500D01*
G01X1648250Y-1590500D02*
X1659750D01*
G01X1668750Y-1610500D02*
Y-1590500D01*
G01X1679250D02*
Y-1610500D01*
G01Y-1600500D02*
X1668750D01*
G01X1694000Y-1610500D02*
Y-1601500D01*
X1689000Y-1590500D01*
G01X1699000D02*
X1694000Y-1601500D01*
G01X1728750Y-1610500D02*
Y-1590500D01*
G01X1739250D02*
Y-1610500D01*
G01Y-1600500D02*
X1728750D01*
G01X1748500Y-1590500D02*
Y-1604833D01*
X1749500Y-1607834D01*
X1751500Y-1609833D01*
X1754000Y-1610500D01*
X1756500Y-1609833D01*
X1758500Y-1607834D01*
X1759500Y-1604833D01*
Y-1590500D01*
G01X1767750Y-1610500D02*
X1774000Y-1590500D01*
X1780250Y-1610500D01*
G01X1778000Y-1603500D02*
X1770000D01*
G01X1788250Y-1610500D02*
Y-1590500D01*
X1799750Y-1610500D01*
Y-1590500D01*
G01X1815500Y-1600500D02*
X1820500D01*
Y-1606500D01*
X1819000Y-1608500D01*
X1817250Y-1609833D01*
X1814750Y-1610500D01*
X1812250Y-1609833D01*
X1810500Y-1608500D01*
X1809000Y-1606500D01*
X1808000Y-1604167D01*
X1807500Y-1601500D01*
Y-1599167D01*
X1808000Y-1597167D01*
X1809000Y-1594833D01*
X1810500Y-1592833D01*
X1812000Y-1591500D01*
X1814000Y-1590500D01*
X1815750D01*
X1817750Y-1591167D01*
X1819250Y-1592500D01*
G01X1778350Y-1451900D02*
X1776790Y-1452420D01*
X1775620Y-1453720D01*
X1774840Y-1455280D01*
X1774255Y-1457360D01*
X1774060Y-1459700D01*
X1774255Y-1462040D01*
X1774840Y-1464120D01*
X1775620Y-1465680D01*
X1776790Y-1466980D01*
X1778350Y-1467500D01*
X1779910Y-1466980D01*
X1781080Y-1465680D01*
X1781860Y-1464120D01*
X1782445Y-1462040D01*
X1782640Y-1459700D01*
X1782445Y-1457360D01*
X1781860Y-1455280D01*
X1781080Y-1453720D01*
X1779910Y-1452420D01*
X1778350Y-1451900D01*
G01X1796250Y-1467500D02*
Y-1451900D01*
X1793910Y-1455020D01*
G01Y-1467500D02*
X1798590D01*
G01X1837750Y-1674833D02*
X1839250Y-1672834D01*
X1841000Y-1671833D01*
X1843000Y-1671500D01*
X1845500Y-1672167D01*
X1847250Y-1673833D01*
X1847750Y-1675833D01*
X1847500Y-1677834D01*
X1846500Y-1679500D01*
X1841500Y-1682833D01*
X1839250Y-1685167D01*
X1837750Y-1688501D01*
X1837250Y-1691500D01*
X1847750D01*
G01X1862500Y-1671500D02*
X1860500Y-1672167D01*
X1859000Y-1673833D01*
X1858000Y-1675833D01*
X1857250Y-1678500D01*
X1857000Y-1681500D01*
X1857250Y-1684500D01*
X1858000Y-1687167D01*
X1859000Y-1689167D01*
X1860500Y-1690833D01*
X1862500Y-1691500D01*
X1864500Y-1690833D01*
X1866000Y-1689167D01*
X1867000Y-1687167D01*
X1867750Y-1684500D01*
X1868000Y-1681500D01*
X1867750Y-1678500D01*
X1867000Y-1675833D01*
X1866000Y-1673833D01*
X1864500Y-1672167D01*
X1862500Y-1671500D01*
G01X1877750Y-1674833D02*
X1879250Y-1672834D01*
X1881000Y-1671833D01*
X1883000Y-1671500D01*
X1885500Y-1672167D01*
X1887250Y-1673833D01*
X1887750Y-1675833D01*
X1887500Y-1677834D01*
X1886500Y-1679500D01*
X1881500Y-1682833D01*
X1879250Y-1685167D01*
X1877750Y-1688501D01*
X1877250Y-1691500D01*
X1887750D01*
G01X1897750Y-1674833D02*
X1899250Y-1672834D01*
X1901000Y-1671833D01*
X1903000Y-1671500D01*
X1905500Y-1672167D01*
X1907250Y-1673833D01*
X1907750Y-1675833D01*
X1907500Y-1677834D01*
X1906500Y-1679500D01*
X1901500Y-1682833D01*
X1899250Y-1685167D01*
X1897750Y-1688501D01*
X1897250Y-1691500D01*
X1907750D01*
G01X1919250Y-1684834D02*
X1925750D01*
G01X1942500Y-1671500D02*
X1940500Y-1672167D01*
X1939000Y-1673833D01*
X1938000Y-1675833D01*
X1937250Y-1678500D01*
X1937000Y-1681500D01*
X1937250Y-1684500D01*
X1938000Y-1687167D01*
X1939000Y-1689167D01*
X1940500Y-1690833D01*
X1942500Y-1691500D01*
X1944500Y-1690833D01*
X1946000Y-1689167D01*
X1947000Y-1687167D01*
X1947750Y-1684500D01*
X1948000Y-1681500D01*
X1947750Y-1678500D01*
X1947000Y-1675833D01*
X1946000Y-1673833D01*
X1944500Y-1672167D01*
X1942500Y-1671500D01*
G01X1957750Y-1674833D02*
X1959250Y-1672834D01*
X1961000Y-1671833D01*
X1963000Y-1671500D01*
X1965500Y-1672167D01*
X1967250Y-1673833D01*
X1967750Y-1675833D01*
X1967500Y-1677834D01*
X1966500Y-1679500D01*
X1961500Y-1682833D01*
X1959250Y-1685167D01*
X1957750Y-1688501D01*
X1957250Y-1691500D01*
X1967750D01*
G01X1979250Y-1684834D02*
X1985750D01*
G01X1997750Y-1674833D02*
X1999250Y-1672834D01*
X2001000Y-1671833D01*
X2003000Y-1671500D01*
X2005500Y-1672167D01*
X2007250Y-1673833D01*
X2007750Y-1675833D01*
X2007500Y-1677834D01*
X2006500Y-1679500D01*
X2001500Y-1682833D01*
X1999250Y-1685167D01*
X1997750Y-1688501D01*
X1997250Y-1691500D01*
X2007750D01*
G01X2017000Y-1688501D02*
X2018500Y-1690167D01*
X2020250Y-1691167D01*
X2022500Y-1691500D01*
X2024750Y-1690833D01*
X2026500Y-1689500D01*
X2027750Y-1687167D01*
X2028000Y-1684500D01*
X2027500Y-1681834D01*
X2026250Y-1680167D01*
X2024500Y-1678834D01*
X2022750Y-1678500D01*
X2021000Y-1678834D01*
X2018750Y-1680167D01*
X2019500Y-1671500D01*
X2026250D01*
G01X1834250Y-1636333D02*
X1835750Y-1634334D01*
X1837500Y-1633333D01*
X1839500Y-1633000D01*
X1842000Y-1633667D01*
X1843750Y-1635333D01*
X1844250Y-1637333D01*
X1844000Y-1639334D01*
X1843000Y-1641000D01*
X1838000Y-1644333D01*
X1835750Y-1646667D01*
X1834250Y-1650001D01*
X1833750Y-1653000D01*
X1844250D01*
G01X1859000Y-1633000D02*
X1857000Y-1633667D01*
X1855500Y-1635333D01*
X1854500Y-1637333D01*
X1853750Y-1640000D01*
X1853500Y-1643000D01*
X1853750Y-1646000D01*
X1854500Y-1648667D01*
X1855500Y-1650667D01*
X1857000Y-1652333D01*
X1859000Y-1653000D01*
X1861000Y-1652333D01*
X1862500Y-1650667D01*
X1863500Y-1648667D01*
X1864250Y-1646000D01*
X1864500Y-1643000D01*
X1864250Y-1640000D01*
X1863500Y-1637333D01*
X1862500Y-1635333D01*
X1861000Y-1633667D01*
X1859000Y-1633000D01*
G01X1874250Y-1636333D02*
X1875750Y-1634334D01*
X1877500Y-1633333D01*
X1879500Y-1633000D01*
X1882000Y-1633667D01*
X1883750Y-1635333D01*
X1884250Y-1637333D01*
X1884000Y-1639334D01*
X1883000Y-1641000D01*
X1878000Y-1644333D01*
X1875750Y-1646667D01*
X1874250Y-1650001D01*
X1873750Y-1653000D01*
X1884250D01*
G01X1894250Y-1636333D02*
X1895750Y-1634334D01*
X1897500Y-1633333D01*
X1899500Y-1633000D01*
X1902000Y-1633667D01*
X1903750Y-1635333D01*
X1904250Y-1637333D01*
X1904000Y-1639334D01*
X1903000Y-1641000D01*
X1898000Y-1644333D01*
X1895750Y-1646667D01*
X1894250Y-1650001D01*
X1893750Y-1653000D01*
X1904250D01*
G01X1915750Y-1646334D02*
X1922250D01*
G01X1939000Y-1633000D02*
X1937000Y-1633667D01*
X1935500Y-1635333D01*
X1934500Y-1637333D01*
X1933750Y-1640000D01*
X1933500Y-1643000D01*
X1933750Y-1646000D01*
X1934500Y-1648667D01*
X1935500Y-1650667D01*
X1937000Y-1652333D01*
X1939000Y-1653000D01*
X1941000Y-1652333D01*
X1942500Y-1650667D01*
X1943500Y-1648667D01*
X1944250Y-1646000D01*
X1944500Y-1643000D01*
X1944250Y-1640000D01*
X1943500Y-1637333D01*
X1942500Y-1635333D01*
X1941000Y-1633667D01*
X1939000Y-1633000D01*
G01X1954250Y-1636333D02*
X1955750Y-1634334D01*
X1957500Y-1633333D01*
X1959500Y-1633000D01*
X1962000Y-1633667D01*
X1963750Y-1635333D01*
X1964250Y-1637333D01*
X1964000Y-1639334D01*
X1963000Y-1641000D01*
X1958000Y-1644333D01*
X1955750Y-1646667D01*
X1954250Y-1650001D01*
X1953750Y-1653000D01*
X1964250D01*
G01X1975750Y-1646334D02*
X1982250D01*
G01X1994250Y-1636333D02*
X1995750Y-1634334D01*
X1997500Y-1633333D01*
X1999500Y-1633000D01*
X2002000Y-1633667D01*
X2003750Y-1635333D01*
X2004250Y-1637333D01*
X2004000Y-1639334D01*
X2003000Y-1641000D01*
X1998000Y-1644333D01*
X1995750Y-1646667D01*
X1994250Y-1650001D01*
X1993750Y-1653000D01*
X2004250D01*
G01X2013500Y-1650001D02*
X2015000Y-1651667D01*
X2016750Y-1652667D01*
X2019000Y-1653000D01*
X2021250Y-1652333D01*
X2023000Y-1651000D01*
X2024250Y-1648667D01*
X2024500Y-1646000D01*
X2024000Y-1643334D01*
X2022750Y-1641667D01*
X2021000Y-1640334D01*
X2019250Y-1640000D01*
X2017500Y-1640334D01*
X2015250Y-1641667D01*
X2016000Y-1633000D01*
X2022750D01*
G01X1834250Y-1592333D02*
X1835750Y-1590334D01*
X1837500Y-1589333D01*
X1839500Y-1589000D01*
X1842000Y-1589667D01*
X1843750Y-1591333D01*
X1844250Y-1593333D01*
X1844000Y-1595334D01*
X1843000Y-1597000D01*
X1838000Y-1600333D01*
X1835750Y-1602667D01*
X1834250Y-1606001D01*
X1833750Y-1609000D01*
X1844250D01*
G01X1859000Y-1589000D02*
X1857000Y-1589667D01*
X1855500Y-1591333D01*
X1854500Y-1593333D01*
X1853750Y-1596000D01*
X1853500Y-1599000D01*
X1853750Y-1602000D01*
X1854500Y-1604667D01*
X1855500Y-1606667D01*
X1857000Y-1608333D01*
X1859000Y-1609000D01*
X1861000Y-1608333D01*
X1862500Y-1606667D01*
X1863500Y-1604667D01*
X1864250Y-1602000D01*
X1864500Y-1599000D01*
X1864250Y-1596000D01*
X1863500Y-1593333D01*
X1862500Y-1591333D01*
X1861000Y-1589667D01*
X1859000Y-1589000D01*
G01X1874250Y-1592333D02*
X1875750Y-1590334D01*
X1877500Y-1589333D01*
X1879500Y-1589000D01*
X1882000Y-1589667D01*
X1883750Y-1591333D01*
X1884250Y-1593333D01*
X1884000Y-1595334D01*
X1883000Y-1597000D01*
X1878000Y-1600333D01*
X1875750Y-1602667D01*
X1874250Y-1606001D01*
X1873750Y-1609000D01*
X1884250D01*
G01X1894250Y-1592333D02*
X1895750Y-1590334D01*
X1897500Y-1589333D01*
X1899500Y-1589000D01*
X1902000Y-1589667D01*
X1903750Y-1591333D01*
X1904250Y-1593333D01*
X1904000Y-1595334D01*
X1903000Y-1597000D01*
X1898000Y-1600333D01*
X1895750Y-1602667D01*
X1894250Y-1606001D01*
X1893750Y-1609000D01*
X1904250D01*
G01X1915750Y-1602334D02*
X1922250D01*
G01X1939000Y-1589000D02*
X1937000Y-1589667D01*
X1935500Y-1591333D01*
X1934500Y-1593333D01*
X1933750Y-1596000D01*
X1933500Y-1599000D01*
X1933750Y-1602000D01*
X1934500Y-1604667D01*
X1935500Y-1606667D01*
X1937000Y-1608333D01*
X1939000Y-1609000D01*
X1941000Y-1608333D01*
X1942500Y-1606667D01*
X1943500Y-1604667D01*
X1944250Y-1602000D01*
X1944500Y-1599000D01*
X1944250Y-1596000D01*
X1943500Y-1593333D01*
X1942500Y-1591333D01*
X1941000Y-1589667D01*
X1939000Y-1589000D01*
G01X1954250Y-1592333D02*
X1955750Y-1590334D01*
X1957500Y-1589333D01*
X1959500Y-1589000D01*
X1962000Y-1589667D01*
X1963750Y-1591333D01*
X1964250Y-1593333D01*
X1964000Y-1595334D01*
X1963000Y-1597000D01*
X1958000Y-1600333D01*
X1955750Y-1602667D01*
X1954250Y-1606001D01*
X1953750Y-1609000D01*
X1964250D01*
G01X1975750Y-1602334D02*
X1982250D01*
G01X1994250Y-1592333D02*
X1995750Y-1590334D01*
X1997500Y-1589333D01*
X1999500Y-1589000D01*
X2002000Y-1589667D01*
X2003750Y-1591333D01*
X2004250Y-1593333D01*
X2004000Y-1595334D01*
X2003000Y-1597000D01*
X1998000Y-1600333D01*
X1995750Y-1602667D01*
X1994250Y-1606001D01*
X1993750Y-1609000D01*
X2004250D01*
G01X2013500Y-1606001D02*
X2015000Y-1607667D01*
X2016750Y-1608667D01*
X2019000Y-1609000D01*
X2021250Y-1608333D01*
X2023000Y-1607000D01*
X2024250Y-1604667D01*
X2024500Y-1602000D01*
X2024000Y-1599334D01*
X2022750Y-1597667D01*
X2021000Y-1596334D01*
X2019250Y-1596000D01*
X2017500Y-1596334D01*
X2015250Y-1597667D01*
X2016000Y-1589000D01*
X2022750D01*
G01X1858627Y-1448882D02*
G02I-672J0D01*
G01X1875355Y-1468526D02*
G02I-1546J0D01*
G01X1876368Y-1456700D02*
G02I-1679J0D01*
G01X1871955Y-1471484D02*
G02I-1102J0D01*
G01X1867974Y-1459892D02*
G02I-947J0D01*
G01X1871883Y-1458435D02*
G02I-1361J0D01*
G01X1869167Y-1473846D02*
G02I-671J0D01*
G01X1876358Y-1441092D02*
G02I-1680J0D01*
G01X1879013Y-1448882D02*
G02I-2314J0D01*
G01X1871871Y-1439368D02*
G02I-1360J0D01*
G01X1862587Y-1448882D02*
G02I-1102J0D01*
G01X1867219D02*
G02I-1548J0D01*
G01X1872728D02*
G02I-1981J0D01*
G01X1875362Y-1429242D02*
G02I-1546J0D01*
G01X1865174Y-1436751D02*
G02I-671J0D01*
G01X1867963Y-1437911D02*
G02I-947J0D01*
G01X1871955Y-1426281D02*
G02I-1102J0D01*
G01X1883402Y-1475307D02*
G02I-946J0D01*
G01X1882013Y-1477878D02*
G02I-673J0D01*
G01X1894998Y-1476663D02*
G02I-1545J0D01*
G01X1894558Y-1480852D02*
G02I-1105J0D01*
G01X1887322Y-1467653D02*
G02I-1680J0D01*
G01X1895767Y-1465638D02*
G02I-2314J0D01*
G01X1896254Y-1459023D02*
G02I-2801J0D01*
G01X1883918Y-1460732D02*
G02I-2313J0D01*
G01X1889819Y-1462630D02*
G02I-2087J0D01*
G01X1889086Y-1456049D02*
G02I-2800J0D01*
G01X1885267Y-1471813D02*
G02I-1360J0D01*
G01X1895438Y-1471590D02*
G02I-1985J0D01*
G01X1879381Y-1464936D02*
G02I-1983J0D01*
G01X1896254Y-1438740D02*
G02I-2801J0D01*
G01X1881802Y-1454605D02*
G02I-2091J0D01*
G01X1889086Y-1441714D02*
G02I-2800J0D01*
G01X1881790Y-1443176D02*
G02I-2090J0D01*
G01X1886116Y-1448882D02*
G02I-2802J0D01*
G01X1889903Y-1435100D02*
G02I-2087J0D01*
G01X1883923Y-1437038D02*
G02I-2314J0D01*
G01X1885412Y-1425893D02*
G02I-1360J0D01*
G01X1887434Y-1430066D02*
G02I-1680J0D01*
G01X1895438Y-1426173D02*
G02I-1985J0D01*
G01X1895767Y-1432126D02*
G02I-2314J0D01*
G01X1879381Y-1432827D02*
G02I-1983J0D01*
G01X1894998Y-1421100D02*
G02I-1545J0D01*
G01X1894558Y-1416911D02*
G02I-1105J0D01*
G01X1907598Y-1477162D02*
G02I-670J0D01*
G01X1906496Y-1474911D02*
G02I-946J0D01*
G01X1894126Y-1484380D02*
G02I-673J0D01*
G01X1911493Y-1464936D02*
G02I-1983J0D01*
G01X1907612Y-1460725D02*
G02I-2313J0D01*
G01X1904980Y-1471573D02*
G02I-1361J0D01*
G01X1903136Y-1467637D02*
G02I-1680J0D01*
G01X1901278Y-1462624D02*
G02I-2090J0D01*
G01X1903423Y-1456049D02*
G02I-2800J0D01*
G01Y-1441714D02*
G02I-2800J0D01*
G01X1911493Y-1432827D02*
G02I-1983J0D01*
G01X1905529Y-1422506D02*
G02I-949J0D01*
G01X1907612Y-1437038D02*
G02I-2313J0D01*
G01X1901329Y-1435157D02*
G02I-2091J0D01*
G01X1903041Y-1430150D02*
G02I-1679J0D01*
G01X1904475Y-1425994D02*
G02I-1361J0D01*
G01X1906507Y-1419830D02*
G02I-672J0D01*
G01X1894126Y-1413383D02*
G02I-673J0D01*
G01X1924922Y-1457729D02*
G03X1931063Y-1454761I-1189J10298D01*
G01X1919488Y-1456387D02*
G03X1924922Y-1457729I4820J7843D01*
G01X1914639Y-1468521D02*
G02I-1546J0D01*
G01X1925329Y-1455818D02*
G02X1922008Y-1455310I-608J7138D01*
G01X1930060Y-1453479D02*
G02X1925329Y-1455818I-7363J8939D01*
G01X1916520Y-1452948D02*
G03X1919488Y-1456387I7684J3631D01*
G01X1916681Y-1444340D02*
G03X1916520Y-1452948I9517J-4484D01*
G01X1924726Y-1439861D02*
G03X1916681Y-1444340I-232J-9047D01*
G01X1930974Y-1442340D02*
G03X1924726Y-1439861I-6790J-8000D01*
G01X1924455Y-1441787D02*
G02X1929887Y-1443607I0J-9017D01*
G01X1918112Y-1446910D02*
G02X1924455Y-1441787I6291J-1301D01*
G01X1922008Y-1455310D02*
G02X1918112Y-1446910I3570J6759D01*
G01X1936175Y-1457305D02*
G03X1944141Y-1455621I2822J6334D01*
G01X1942654Y-1450260D02*
Y-1450241D01*
G01X1935105Y-1450260D02*
X1942654D01*
G01X1935105Y-1450241D02*
Y-1450260D01*
G01X1942654Y-1450241D02*
G03X1935105I-3775J169D01*
G01X1942784Y-1454282D02*
G02X1936178Y-1454858I-3590J3000D01*
G01X1944141Y-1455621D02*
G03X1942784Y-1454282I-867J479D01*
G01X1932808Y-1453020D02*
G03X1936175Y-1457305I6565J1693D01*
G01X1932808Y-1450703D02*
Y-1453020D01*
G01X1945013Y-1450703D02*
G03X1932808I-6103J236D01*
G01X1935108Y-1451799D02*
X1945013D01*
G01X1936178Y-1454858D02*
G02X1935108Y-1451799I3537J2954D01*
G01X1931063Y-1454761D02*
G03X1930060Y-1453479I-758J440D01*
G01X1929887Y-1443607D02*
G03X1930974Y-1442340I435J727D01*
G01X1956083Y-1457305D02*
G03X1964049Y-1455621I2822J6334D01*
G01X1955013Y-1450260D02*
X1962562D01*
G01X1955013Y-1450241D02*
Y-1450260D01*
G01X1962562Y-1450241D02*
G03X1955013I-3774J169D01*
G01X1955016Y-1451799D02*
X1964921D01*
G01X1956086Y-1454858D02*
G02X1955016Y-1451799I3537J2954D01*
G01X1962692Y-1454282D02*
G02X1956086Y-1454858I-3590J3000D01*
G01X1952716Y-1453020D02*
G03X1956083Y-1457305I6565J1693D01*
G01X1952716Y-1450703D02*
Y-1453020D01*
G01X1964921Y-1450703D02*
G03X1952716I-6102J236D01*
G01X1947820Y-1440308D02*
G02X1949965Y-1440315I1072J-257D01*
G01X1947820Y-1456844D02*
Y-1440308D01*
G01X1949965Y-1456844D02*
G02X1947820I-1073J253D01*
G01X1949965Y-1440315D02*
Y-1456844D01*
G01X1945013Y-1451799D02*
Y-1450703D01*
G01X1973539Y-1450360D02*
G02X1969860Y-1448867I1911J9989D01*
G01X1976453Y-1452712D02*
G03X1973539Y-1450360I-3681J-1579D01*
G01X1976296Y-1455619D02*
G03X1976453Y-1452712I-3334J1638D01*
G01X1973551Y-1457602D02*
G03X1976296Y-1455619I-1336J4741D01*
G01X1969271Y-1457333D02*
G03X1973551Y-1457602I2765J9804D01*
G01X1966741Y-1455590D02*
G03X1969271Y-1457333I3982J3072D01*
G01X1968512Y-1454621D02*
G03X1966741Y-1455590I-793J-654D01*
G01X1971419Y-1455926D02*
G02X1968512Y-1454621I259J4466D01*
G01X1971994Y-1455937D02*
G02X1971419Y-1455926I-192J4985D01*
G01X1974161Y-1455009D02*
G02X1971994Y-1455937I-2245J2248D01*
G01X1974277Y-1453346D02*
G02X1974161Y-1455009I-927J-771D01*
G01X1971859Y-1451922D02*
G02X1974277Y-1453346I-1337J-5035D01*
G01X1968925Y-1450910D02*
G03X1971859Y-1451922I8703J20473D01*
G01X1967420Y-1448489D02*
G03X1968925Y-1450910I2813J70D01*
G01X1967420Y-1446900D02*
Y-1448489D01*
G01X1969162Y-1444895D02*
G03X1967420Y-1446900I2913J-4290D01*
G01X1976273Y-1445965D02*
G03X1969162Y-1444895I-4404J-5102D01*
G01X1974918Y-1447291D02*
G03X1976273Y-1445965I635J707D01*
G01X1972802Y-1446305D02*
G02X1974918Y-1447291I-1190J-5318D01*
G01X1970118Y-1446581D02*
G02X1972802Y-1446305I1763J-3957D01*
G01X1969860Y-1448867D02*
G02X1970118Y-1446581I1112J1032D01*
G01X1979558Y-1446587D02*
G02X1979503Y-1444442I262J1080D01*
G01X1980590Y-1446587D02*
X1979558D01*
G01X1979503Y-1444442D02*
X1980590D01*
G01X1962562Y-1450260D02*
Y-1450241D01*
G01X1964049Y-1455621D02*
G03X1962692Y-1454282I-867J479D01*
G01X1964921Y-1451799D02*
Y-1450703D01*
G01X1988450Y1534500D02*
X1985930Y1533667D01*
X1984040Y1531583D01*
X1982780Y1529084D01*
X1981835Y1525750D01*
X1981520Y1522000D01*
X1981835Y1518250D01*
X1982780Y1514916D01*
X1984040Y1512416D01*
X1985930Y1510333D01*
X1988450Y1509500D01*
X1990970Y1510333D01*
X1992860Y1512416D01*
X1994120Y1514916D01*
X1995065Y1518250D01*
X1995380Y1522000D01*
X1995065Y1525750D01*
X1994120Y1529084D01*
X1992860Y1531583D01*
X1990970Y1533667D01*
X1988450Y1534500D01*
G01X2013650Y1509500D02*
Y1534500D01*
X2009870Y1529500D01*
G01Y1509500D02*
X2017429D01*
G01X1997020Y-1450948D02*
G02X1997447Y-1448685I6225J-3D01*
G01X1997020Y-1451877D02*
Y-1450948D01*
G01X1997435Y-1453322D02*
G02X1997020Y-1451877I3999J1930D01*
G01X1996428Y-1455590D02*
G03X2000335Y-1457613I4656J4209D01*
G01X1994987Y-1452539D02*
G03X1996428Y-1455590I6065J999D01*
G01X1994987Y-1450707D02*
Y-1452539D01*
G01X1995486Y-1447987D02*
G03X1994987Y-1450707I10590J-3349D01*
G01X2000303Y-1444278D02*
G03X1995486Y-1447987I1335J-6717D01*
G01X1992271Y-1440634D02*
G02I-1265J0D01*
G01X1980590Y-1455164D02*
Y-1446587D01*
G01X1983995Y-1457613D02*
G02X1980590Y-1455164I-269J3217D01*
G01X1985372Y-1457613D02*
X1983995D01*
G01X1986856Y-1456577D02*
G02X1985372Y-1457613I-1509J580D01*
G01X1985943Y-1455470D02*
G02X1986856Y-1456577I104J-844D01*
G01X1982736Y-1454550D02*
G03X1985943Y-1455470I2170J1514D01*
G01X1982736Y-1446587D02*
Y-1454550D01*
G01X1985945Y-1446587D02*
X1982736D01*
G01X1985950Y-1444442D02*
G02X1985945Y-1446587I-192J-1072D01*
G01X1982736Y-1444442D02*
X1985950D01*
G01X1982729Y-1441776D02*
X1982736Y-1444442D01*
G01X1980590Y-1441853D02*
G02X1982729Y-1441776I1074J-74D01*
G01X1980590Y-1444442D02*
Y-1441853D01*
G01X1989779Y-1445359D02*
Y-1456693D01*
G01X1992227Y-1445359D02*
G03X1989779I-1224J-434D01*
G01X1992227Y-1456693D02*
Y-1445359D01*
G01X1989779Y-1456693D02*
G03X1992227I1224J207D01*
G01X2016046Y-1455778D02*
X2013361D01*
G01Y-1451183D02*
X2016122D01*
G01X2013361Y-1455778D02*
G02Y-1451183I204J2298D01*
G01X2013053Y-1444442D02*
X2016732D01*
G01X2010455Y-1445665D02*
G02X2013053Y-1444442I3218J-3465D01*
G01X2011205Y-1447187D02*
G02X2010455Y-1445665I-130J882D01*
G01X2012443Y-1446587D02*
G03X2011205Y-1447187I1530J-4735D01*
G01X2016424Y-1446587D02*
X2012443D01*
G01X2014449Y-1449325D02*
G02X2018261Y-1449648I361J-18399D01*
G01X2012107Y-1449650D02*
G02X2014449Y-1449325I2637J-10399D01*
G01X2012140Y-1457613D02*
G02X2012107Y-1449650I880J3985D01*
G01X2015814Y-1457613D02*
X2012140D01*
G01X2003613Y-1446848D02*
G02X2004856Y-1447987I-8597J-10630D01*
G01X2000828Y-1446148D02*
G02X2003613Y-1446848I332J-4570D01*
G01X1997447Y-1448685D02*
G02X2000828Y-1446148I4085J-1923D01*
G01X1999613Y-1455435D02*
G02X1997435Y-1453322I2138J4383D01*
G01X2002391Y-1455836D02*
G02X1999613Y-1455435I-717J4853D01*
G01X2004996Y-1454284D02*
G02X2002391Y-1455836I-3653J3170D01*
G01X2006306Y-1455659D02*
G03X2004996Y-1454284I-736J610D01*
G01X2005588Y-1456352D02*
X2006306Y-1455659D01*
G01X2002301Y-1457613D02*
G03X2005588Y-1456352I0J4916D01*
G01X2000335Y-1457613D02*
X2002301D01*
G01X2001765Y-1444278D02*
X2000303D01*
G01X2006519Y-1446748D02*
G03X2001765Y-1444278I-5065J-3938D01*
G01X2004856Y-1447987D02*
G03X2006519Y-1446748I619J904D01*
G01X2020406Y-1456844D02*
G02X2018261I-1073J194D01*
G01X2026573Y-1447212D02*
X2026336D01*
G01X2027187Y-1445437D02*
X2026573Y-1447212D01*
G01X2027486D02*
X2027187Y-1445437D01*
G01X2028061Y-1447212D02*
X2027486D01*
G01X2027479Y-1444515D02*
X2028061Y-1447212D01*
G01X2027019Y-1444515D02*
X2027479D01*
G01X2026448Y-1446245D02*
X2027019Y-1444515D01*
G01X2025871D02*
X2026448Y-1446245D01*
G01X2025442Y-1444515D02*
X2025871D01*
G01X2024863Y-1447212D02*
X2025442Y-1444515D01*
G01X2025423Y-1447212D02*
X2024863D01*
G01X2025715Y-1445455D02*
X2025423Y-1447212D01*
G01X2026336D02*
X2025715Y-1445455D01*
G01X2022238Y-1445052D02*
X2023133D01*
G01X2022238Y-1444515D02*
Y-1445052D01*
G01X2024613Y-1444515D02*
X2022238D01*
G01X2024613Y-1445052D02*
Y-1444515D01*
G01X2023715Y-1445052D02*
X2024613D01*
G01X2023715Y-1447201D02*
Y-1445052D01*
G01X2023133Y-1447201D02*
X2023715D01*
G01X2023133Y-1445052D02*
Y-1447201D01*
G01X2016122Y-1451183D02*
G02X2016046Y-1455778I0J-2298D01*
G01X2016732Y-1444442D02*
G02X2020406Y-1448114I-528J-4202D01*
G01X2018261Y-1448423D02*
G03X2016424Y-1446587I-1696J140D01*
G01X2018261Y-1449648D02*
Y-1448423D01*
G01Y-1456420D02*
G02X2015814Y-1457613I-3601J4281D01*
G01X2018261Y-1456844D02*
Y-1456420D01*
G01X2020406Y-1448114D02*
Y-1456844D01*
G01X662704Y199451D02*
X659604D01*
Y200371D01*
X659759Y200678D01*
X660121Y200908D01*
X660534Y200985D01*
X660947Y200908D01*
X661257Y200716D01*
X661412Y200371D01*
Y199451D01*
G01X659862Y204161D02*
X659707Y203931D01*
X659604Y203663D01*
Y203356D01*
X659759Y203011D01*
X660017Y202743D01*
X660327Y202551D01*
X660844Y202398D01*
X661309Y202360D01*
X661774Y202436D01*
X662084Y202551D01*
X662394Y202781D01*
X662601Y203050D01*
X662704Y203318D01*
Y203586D01*
X662601Y203855D01*
X662446Y204085D01*
X662239Y204276D01*
G01X661051Y206725D02*
X660896Y206878D01*
X660637Y206993D01*
X660276Y207070D01*
X659966Y206993D01*
X659759Y206840D01*
X659604Y206571D01*
Y205536D01*
X662704D01*
Y206801D01*
X662497Y207070D01*
X662187Y207223D01*
X661826Y207300D01*
X661464Y207223D01*
X661154Y206993D01*
X661051Y206725D01*
Y205536D01*
G01X662704Y213385D02*
Y211851D01*
X659604D01*
Y213385D01*
G01X661102Y212771D02*
Y211851D01*
G01X662704Y214875D02*
X659604D01*
Y215641D01*
X659759Y215948D01*
X659966Y216178D01*
X660276Y216370D01*
X660637Y216523D01*
X661154Y216561D01*
X661671Y216523D01*
X662032Y216370D01*
X662342Y216178D01*
X662549Y215948D01*
X662704Y215641D01*
Y214875D01*
G01X661154Y219048D02*
Y219815D01*
X662084D01*
X662394Y219585D01*
X662601Y219316D01*
X662704Y218933D01*
X662601Y218550D01*
X662394Y218281D01*
X662084Y218051D01*
X661722Y217898D01*
X661309Y217821D01*
X660947D01*
X660637Y217898D01*
X660276Y218051D01*
X659966Y218281D01*
X659759Y218511D01*
X659604Y218818D01*
Y219086D01*
X659707Y219393D01*
X659914Y219623D01*
G01X662704Y222685D02*
Y221151D01*
X659604D01*
Y222685D01*
G01X661102Y222071D02*
Y221151D01*
G54D18*
X126067Y104043D03*
Y184043D03*
Y264043D03*
X253967Y93443D03*
X265967D03*
X277867D03*
X286067Y104043D03*
Y264043D03*
X873950Y173500D03*
G54D19*
X143567Y106043D03*
X146067Y268043D03*
X268567Y112143D03*
Y255943D03*
X873950Y123500D03*
M02*
